-- pcdb file, Rev:1.0 written by Allegro Design Entry HDL 16.6-p007 (v16-6-112F) 10/10/2012 on Mon May 08 18:37:10 2017
#ISCELL
  mstr_symbols intel_corp_bpage *
  *
#ISCELL
  mstr_symbols intel_corp_bpage *
  *
#ISCELL
  mstr_symbols intel_corp_bpage *
  *
#ISCELL
  mstr_symbols intel_corp_bpage *
  *
#ISCELL
  mstr_symbols intel_corp_bpage *
  *
#ISCELL
  mstr_symbols intel_corp_bpage *
  *
#ISCELL
  mstr_symbols intel_corp_bpage *
  *
#ISCELL
  mstr_symbols intel_corp_bpage *
  *
#ISCELL
  mstr_symbols intel_corp_bpage *
  *
#ISCELL
  mstr_symbols intel_corp_bpage *
  *
#ISCELL
  mstr_symbols intel_corp_bpage *
  *
#ISCELL
  mstr_symbols intel_corp_bpage *
  *
#ISCELL
  mstr_symbols intel_corp_bpage *
  *
#ISCELL
  mstr_symbols intel_corp_bpage *
  *
#ISCELL
  mstr_symbols intel_corp_bpage *
  *
#ISCELL
  mstr_symbols intel_corp_bpage *
  *
#ISCELL
  mstr_symbols intel_corp_bpage *
  *
#ISCELL
  mstr_symbols intel_corp_bpage *
  *
#ISCELL
  mstr_symbols intel_corp_bpage *
  *
#ISCELL
  mstr_symbols intel_corp_bpage *
  *
#ISCELL
  mstr_misc prelim *
  *
#ISCELL
  mstr_symbols bom_note *
  *
#ISCELL
  mstr_symbols cad_note *
  *
#ISCELL
  mstr_symbols design_note *
  *
#ISCELL
  mstr_symbols intel_corp_bpage *
  *
#ISCELL
  mstr_standard offpage *
  page21_i10
#ISCELL
  mstr_standard offpage *
  page21_i106
#ISCELL
  mstr_standard offpage *
  page21_i107
#ISCELL
  mstr_standard offpage *
  page21_i108
#ISCELL
  mstr_standard offpage *
  page21_i11
#ISCELL
  mstr_standard offpage *
  page21_i111
#ISCELL
  mstr_standard offpage *
  page21_i12
#ISCELL
  mstr_standard offpage *
  page21_i133
#ISCELL
  mstr_standard offpage *
  page21_i134
#ISCELL
  mstr_standard offpage *
  page21_i135
#ISCELL
  mstr_standard offpage *
  page21_i136
#ISCELL
  mstr_standard offpage *
  page21_i137
#ISCELL
  mstr_standard offpage *
  page21_i145
#ISCELL
  mstr_standard offpage *
  page21_i146
#ISCELL
  mstr_standard offpage *
  page21_i147
#CELL
  mstr_discrete res *
  page21_i149
#ISCELL
  mstr_standard offpage *
  page21_i15
#CELL
  mstr_discrete res *
  page21_i150
#CELL
  mstr_discrete res *
  page21_i151
#CELL
  mstr_discrete res *
  page21_i152
#CELL
  mstr_discrete res *
  page21_i153
#CELL
  mstr_discrete res *
  page21_i154
#ISCELL
  mstr_standard offpage *
  page21_i155
#ISCELL
  mstr_standard offpage *
  page21_i156
#ISCELL
  mstr_standard offpage *
  page21_i157
#ISCELL
  mstr_symbols pvccio_cpu0 *
  page21_i158
#CELL
  mstr_discrete res *
  page21_i159
#CELL
  mstr_discrete res *
  page21_i161
#CELL
  mstr_discrete res *
  page21_i163
#CELL
  mstr_discrete res *
  page21_i164
#ISCELL
  mstr_standard offpage *
  page21_i169
#ISCELL
  mstr_standard offpage *
  page21_i170
#ISCELL
  mstr_standard offpage *
  page21_i172
#ISCELL
  mstr_standard offpage *
  page21_i175
#CELL
  mstr_discrete res *
  page21_i177
#CELL
  mstr_discrete res *
  page21_i178
#CELL
  mstr_discrete res *
  page21_i179
#ISCELL
  mstr_standard offpage *
  page21_i18
#CELL
  mstr_discrete res *
  page21_i180
#CELL
  mstr_discrete res *
  page21_i181
#CELL
  mstr_discrete res *
  page21_i182
#ISCELL
  mstr_symbols gnd *
  page21_i183
#CELL
  mstr_discrete res *
  page21_i184
#CELL
  mstr_discrete res *
  page21_i186
#ISCELL
  mstr_symbols gnd *
  page21_i187
#CELL
  mstr_discrete res *
  page21_i188
#CELL
  mstr_discrete res *
  page21_i189
#ISCELL
  mstr_standard offpage *
  page21_i196
#ISCELL
  mstr_standard offpage *
  page21_i197
#ISCELL
  mstr_standard offpage *
  page21_i2
#ISCELL
  mstr_standard offpage *
  page21_i200
#ISCELL
  mstr_standard offpage *
  page21_i201
#ISCELL
  mstr_standard offpage *
  page21_i202
#CELL
  mstr_discrete res *
  page21_i204
#ISCELL
  mstr_standard offpage *
  page21_i205
#ISCELL
  mstr_standard offpage *
  page21_i209
#ISCELL
  mstr_standard offpage *
  page21_i212
#ISCELL
  mstr_standard offpage *
  page21_i213
#ISCELL
  mstr_standard offpage *
  page21_i214
#ISCELL
  mstr_standard offpage *
  page21_i215
#CELL
  chpset_lib socket_p_mech_a *
  page21_i216
#CELL
  chpset_lib socket_p_mech_a *
  page21_i217
#CELL
  mstr_discrete res *
  page21_i219
#CELL
  mstr_discrete res *
  page21_i227
#ISCELL
  mstr_symbols p3v3_stby *
  page21_i228
#ISCELL
  mstr_standard offpage *
  page21_i233
#ISCELL
  mstr_standard offpage *
  page21_i234
#ISCELL
  mstr_standard offpage *
  page21_i235
#ISCELL
  mstr_standard offpage *
  page21_i236
#ISCELL
  mstr_standard offpage *
  page21_i237
#CELL
  mstr_discrete res *
  page21_i238
#CELL
  mstr_discrete res *
  page21_i239
#CELL
  mstr_discrete res *
  page21_i240
#CELL
  mstr_discrete res *
  page21_i241
#ISCELL
  mstr_symbols p3v3_stby *
  page21_i243
#CELL
  mstr_discrete res *
  page21_i244
#ISCELL
  mstr_standard offpage *
  page21_i247
#ISCELL
  mstr_standard offpage *
  page21_i254
#ISCELL
  mstr_standard offpage *
  page21_i255
#ISCELL
  mstr_standard offpage *
  page21_i256
#ISCELL
  mstr_symbols pvccio_cpu0 *
  page21_i257
#CELL
  mstr_discrete res *
  page21_i258
#CELL
  chpset_lib skx_ext_b *
  page21_i259
#ISCELL
  mstr_standard offpage *
  page21_i260
#ISCELL
  mstr_standard offpage *
  page21_i261
#ISCELL
  mstr_standard offpage *
  page21_i262
#ISCELL
  mstr_standard offpage *
  page21_i263
#ISCELL
  mstr_standard offpage *
  page21_i264
#ISCELL
  mstr_standard offpage *
  page21_i265
#ISCELL
  mstr_standard offpage *
  page21_i266
#ISCELL
  mstr_standard offpage *
  page21_i267
#ISCELL
  mstr_standard offpage *
  page21_i268
#ISCELL
  mstr_standard offpage *
  page21_i270
#ISCELL
  mstr_standard offpage *
  page21_i271
#ISCELL
  mstr_standard offpage *
  page21_i4
#ISCELL
  mstr_standard offpage *
  page21_i43
#ISCELL
  mstr_standard offpage *
  page21_i44
#ISCELL
  mstr_standard offpage *
  page21_i47
#ISCELL
  mstr_standard offpage *
  page21_i48
#ISCELL
  mstr_standard offpage *
  page21_i49
#ISCELL
  mstr_standard offpage *
  page21_i5
#ISCELL
  mstr_standard offpage *
  page21_i50
#ISCELL
  mstr_standard offpage *
  page21_i6
#ISCELL
  mstr_standard offpage *
  page21_i66
#ISCELL
  mstr_standard offpage *
  page21_i67
#ISCELL
  mstr_standard offpage *
  page21_i68
#ISCELL
  mstr_standard offpage *
  page21_i69
#ISCELL
  mstr_standard offpage *
  page21_i7
#ISCELL
  mstr_standard offpage *
  page21_i71
#ISCELL
  mstr_standard offpage *
  page21_i72
#ISCELL
  mstr_standard offpage *
  page21_i74
#ISCELL
  mstr_standard offpage *
  page21_i75
#ISCELL
  mstr_standard offpage *
  page21_i76
#ISCELL
  mstr_standard offpage *
  page21_i77
#ISCELL
  mstr_standard offpage *
  page21_i78
#ISCELL
  mstr_standard offpage *
  page21_i79
#ISCELL
  mstr_standard offpage *
  page21_i8
#ISCELL
  mstr_standard offpage *
  page21_i80
#ISCELL
  mstr_standard offpage *
  page21_i9
#ISCELL
  mstr_misc prelim *
  *
#ISCELL
  mstr_symbols design_note *
  *
#ISCELL
  mstr_symbols intel_corp_bpage *
  *
#ISCELL
  mstr_standard offpage *
  page22_i185
#ISCELL
  mstr_standard offpage *
  page22_i186
#CELL
  mstr_discrete res *
  page22_i188
#ISCELL
  mstr_symbols gnd *
  page22_i189
#CELL
  mstr_discrete res *
  page22_i190
#ISCELL
  mstr_standard offpage *
  page22_i195
#ISCELL
  mstr_standard offpage *
  page22_i196
#ISCELL
  mstr_standard offpage *
  page22_i197
#ISCELL
  mstr_standard offpage *
  page22_i198
#ISCELL
  mstr_standard offpage *
  page22_i199
#ISCELL
  mstr_standard offpage *
  page22_i200
#ISCELL
  mstr_symbols vcc_core *
  page22_i202
#ISCELL
  mstr_symbols vcc_core *
  page22_i203
#CELL
  chpset_lib skx_ext_b *
  page22_i204
#ISCELL
  mstr_standard offpage *
  page22_i205
#ISCELL
  mstr_standard offpage *
  page22_i206
#ISCELL
  mstr_standard offpage *
  page22_i207
#ISCELL
  mstr_misc prelim *
  *
#ISCELL
  mstr_symbols design_note *
  *
#ISCELL
  mstr_symbols intel_corp_bpage *
  *
#ISCELL
  mstr_standard offpage *
  page23_i1
#ISCELL
  mstr_standard tap *
  page23_i10
#ISCELL
  mstr_standard tap *
  page23_i100
#ISCELL
  mstr_standard tap *
  page23_i101
#ISCELL
  mstr_standard tap *
  page23_i102
#ISCELL
  mstr_standard tap *
  page23_i103
#ISCELL
  mstr_standard tap *
  page23_i104
#ISCELL
  mstr_standard tap *
  page23_i105
#ISCELL
  mstr_standard tap *
  page23_i106
#ISCELL
  mstr_standard tap *
  page23_i107
#ISCELL
  mstr_standard tap *
  page23_i108
#ISCELL
  mstr_standard tap *
  page23_i109
#ISCELL
  mstr_standard tap *
  page23_i11
#ISCELL
  mstr_standard tap *
  page23_i110
#ISCELL
  mstr_standard tap *
  page23_i111
#ISCELL
  mstr_standard tap *
  page23_i112
#ISCELL
  mstr_standard tap *
  page23_i113
#ISCELL
  mstr_standard tap *
  page23_i114
#ISCELL
  mstr_standard tap *
  page23_i115
#ISCELL
  mstr_standard tap *
  page23_i116
#ISCELL
  mstr_standard tap *
  page23_i117
#ISCELL
  mstr_standard tap *
  page23_i118
#ISCELL
  mstr_standard tap *
  page23_i119
#ISCELL
  mstr_standard tap *
  page23_i12
#ISCELL
  mstr_standard tap *
  page23_i120
#ISCELL
  mstr_standard tap *
  page23_i121
#ISCELL
  mstr_standard tap *
  page23_i122
#ISCELL
  mstr_standard tap *
  page23_i123
#ISCELL
  mstr_standard tap *
  page23_i124
#ISCELL
  mstr_standard tap *
  page23_i125
#ISCELL
  mstr_standard tap *
  page23_i126
#ISCELL
  mstr_standard tap *
  page23_i127
#ISCELL
  mstr_standard tap *
  page23_i128
#ISCELL
  mstr_standard tap *
  page23_i129
#ISCELL
  mstr_standard tap *
  page23_i13
#ISCELL
  mstr_standard tap *
  page23_i130
#ISCELL
  mstr_standard tap *
  page23_i131
#ISCELL
  mstr_standard tap *
  page23_i132
#ISCELL
  mstr_standard tap *
  page23_i133
#ISCELL
  mstr_standard tap *
  page23_i134
#ISCELL
  mstr_standard tap *
  page23_i135
#ISCELL
  mstr_standard tap *
  page23_i136
#ISCELL
  mstr_standard tap *
  page23_i137
#ISCELL
  mstr_standard tap *
  page23_i138
#ISCELL
  mstr_standard tap *
  page23_i139
#ISCELL
  mstr_standard tap *
  page23_i14
#ISCELL
  mstr_standard tap *
  page23_i140
#ISCELL
  mstr_standard tap *
  page23_i141
#ISCELL
  mstr_standard tap *
  page23_i142
#ISCELL
  mstr_standard tap *
  page23_i143
#ISCELL
  mstr_standard tap *
  page23_i144
#ISCELL
  mstr_standard tap *
  page23_i145
#ISCELL
  mstr_standard tap *
  page23_i146
#ISCELL
  mstr_standard offpage *
  page23_i147
#ISCELL
  mstr_standard offpage *
  page23_i148
#ISCELL
  mstr_standard offpage *
  page23_i149
#ISCELL
  mstr_standard tap *
  page23_i15
#ISCELL
  mstr_standard offpage *
  page23_i150
#ISCELL
  mstr_standard offpage *
  page23_i151
#ISCELL
  mstr_standard offpage *
  page23_i152
#ISCELL
  mstr_standard offpage *
  page23_i153
#ISCELL
  mstr_standard offpage *
  page23_i154
#ISCELL
  mstr_standard offpage *
  page23_i155
#ISCELL
  mstr_standard offpage *
  page23_i156
#ISCELL
  mstr_standard tap *
  page23_i157
#ISCELL
  mstr_standard tap *
  page23_i158
#ISCELL
  mstr_standard tap *
  page23_i159
#ISCELL
  mstr_standard tap *
  page23_i16
#ISCELL
  mstr_standard tap *
  page23_i160
#ISCELL
  mstr_standard tap *
  page23_i161
#ISCELL
  mstr_standard tap *
  page23_i162
#ISCELL
  mstr_standard tap *
  page23_i163
#ISCELL
  mstr_standard tap *
  page23_i164
#ISCELL
  mstr_standard tap *
  page23_i165
#ISCELL
  mstr_standard tap *
  page23_i166
#ISCELL
  mstr_standard tap *
  page23_i167
#ISCELL
  mstr_standard tap *
  page23_i168
#ISCELL
  mstr_standard tap *
  page23_i169
#ISCELL
  mstr_standard tap *
  page23_i17
#ISCELL
  mstr_standard tap *
  page23_i170
#ISCELL
  mstr_standard offpage *
  page23_i171
#CELL
  chpset_lib skx_ext_b *
  page23_i172
#ISCELL
  mstr_standard tap *
  page23_i18
#ISCELL
  mstr_standard tap *
  page23_i19
#ISCELL
  mstr_standard offpage *
  page23_i2
#ISCELL
  mstr_standard tap *
  page23_i20
#ISCELL
  mstr_standard tap *
  page23_i21
#ISCELL
  mstr_standard tap *
  page23_i22
#ISCELL
  mstr_standard tap *
  page23_i23
#ISCELL
  mstr_standard tap *
  page23_i24
#ISCELL
  mstr_standard tap *
  page23_i25
#ISCELL
  mstr_standard tap *
  page23_i26
#ISCELL
  mstr_standard tap *
  page23_i27
#ISCELL
  mstr_standard tap *
  page23_i28
#ISCELL
  mstr_standard tap *
  page23_i29
#ISCELL
  mstr_standard offpage *
  page23_i3
#ISCELL
  mstr_standard tap *
  page23_i31
#ISCELL
  mstr_standard tap *
  page23_i32
#ISCELL
  mstr_standard tap *
  page23_i33
#ISCELL
  mstr_standard tap *
  page23_i34
#ISCELL
  mstr_standard tap *
  page23_i35
#ISCELL
  mstr_standard tap *
  page23_i36
#ISCELL
  mstr_standard tap *
  page23_i37
#ISCELL
  mstr_standard tap *
  page23_i38
#ISCELL
  mstr_standard tap *
  page23_i39
#ISCELL
  mstr_standard offpage *
  page23_i4
#ISCELL
  mstr_standard tap *
  page23_i40
#ISCELL
  mstr_standard tap *
  page23_i41
#ISCELL
  mstr_standard tap *
  page23_i42
#ISCELL
  mstr_standard tap *
  page23_i43
#ISCELL
  mstr_standard tap *
  page23_i44
#ISCELL
  mstr_standard tap *
  page23_i45
#ISCELL
  mstr_standard tap *
  page23_i46
#ISCELL
  mstr_standard tap *
  page23_i47
#ISCELL
  mstr_standard tap *
  page23_i48
#ISCELL
  mstr_standard tap *
  page23_i49
#ISCELL
  mstr_standard tap *
  page23_i5
#ISCELL
  mstr_standard tap *
  page23_i50
#ISCELL
  mstr_standard tap *
  page23_i51
#ISCELL
  mstr_standard tap *
  page23_i52
#ISCELL
  mstr_standard tap *
  page23_i53
#ISCELL
  mstr_standard tap *
  page23_i54
#ISCELL
  mstr_standard tap *
  page23_i55
#ISCELL
  mstr_standard tap *
  page23_i56
#ISCELL
  mstr_standard tap *
  page23_i57
#ISCELL
  mstr_standard tap *
  page23_i58
#ISCELL
  mstr_standard tap *
  page23_i59
#ISCELL
  mstr_standard tap *
  page23_i6
#ISCELL
  mstr_standard tap *
  page23_i60
#ISCELL
  mstr_standard tap *
  page23_i61
#ISCELL
  mstr_standard tap *
  page23_i62
#ISCELL
  mstr_standard tap *
  page23_i63
#ISCELL
  mstr_standard tap *
  page23_i64
#ISCELL
  mstr_standard tap *
  page23_i65
#ISCELL
  mstr_standard tap *
  page23_i66
#ISCELL
  mstr_standard tap *
  page23_i67
#ISCELL
  mstr_standard tap *
  page23_i68
#ISCELL
  mstr_standard tap *
  page23_i69
#ISCELL
  mstr_standard tap *
  page23_i7
#ISCELL
  mstr_standard tap *
  page23_i70
#ISCELL
  mstr_standard tap *
  page23_i71
#ISCELL
  mstr_standard offpage *
  page23_i72
#ISCELL
  mstr_standard tap *
  page23_i73
#ISCELL
  mstr_standard tap *
  page23_i74
#ISCELL
  mstr_standard tap *
  page23_i75
#ISCELL
  mstr_standard tap *
  page23_i76
#ISCELL
  mstr_standard tap *
  page23_i77
#ISCELL
  mstr_standard tap *
  page23_i78
#ISCELL
  mstr_standard tap *
  page23_i79
#ISCELL
  mstr_standard tap *
  page23_i8
#ISCELL
  mstr_standard tap *
  page23_i80
#ISCELL
  mstr_standard tap *
  page23_i81
#ISCELL
  mstr_standard tap *
  page23_i82
#ISCELL
  mstr_standard tap *
  page23_i83
#ISCELL
  mstr_standard tap *
  page23_i84
#ISCELL
  mstr_standard tap *
  page23_i85
#ISCELL
  mstr_standard tap *
  page23_i86
#ISCELL
  mstr_standard tap *
  page23_i87
#ISCELL
  mstr_standard tap *
  page23_i88
#ISCELL
  mstr_standard tap *
  page23_i89
#ISCELL
  mstr_standard tap *
  page23_i9
#ISCELL
  mstr_standard tap *
  page23_i90
#ISCELL
  mstr_standard tap *
  page23_i91
#ISCELL
  mstr_standard tap *
  page23_i92
#ISCELL
  mstr_standard tap *
  page23_i93
#ISCELL
  mstr_standard tap *
  page23_i94
#ISCELL
  mstr_standard tap *
  page23_i95
#ISCELL
  mstr_standard tap *
  page23_i96
#ISCELL
  mstr_standard tap *
  page23_i97
#ISCELL
  mstr_standard tap *
  page23_i98
#ISCELL
  mstr_standard tap *
  page23_i99
#ISCELL
  mstr_misc prelim *
  *
#ISCELL
  mstr_symbols design_note *
  *
#ISCELL
  mstr_symbols intel_corp_bpage *
  *
#ISCELL
  mstr_standard offpage *
  page24_i1
#ISCELL
  mstr_standard tap *
  page24_i10
#ISCELL
  mstr_standard tap *
  page24_i100
#ISCELL
  mstr_standard tap *
  page24_i101
#ISCELL
  mstr_standard tap *
  page24_i102
#ISCELL
  mstr_standard tap *
  page24_i103
#ISCELL
  mstr_standard tap *
  page24_i104
#ISCELL
  mstr_standard tap *
  page24_i105
#ISCELL
  mstr_standard tap *
  page24_i106
#ISCELL
  mstr_standard tap *
  page24_i107
#ISCELL
  mstr_standard tap *
  page24_i108
#ISCELL
  mstr_standard tap *
  page24_i109
#ISCELL
  mstr_standard tap *
  page24_i11
#ISCELL
  mstr_standard tap *
  page24_i110
#ISCELL
  mstr_standard tap *
  page24_i111
#ISCELL
  mstr_standard tap *
  page24_i112
#ISCELL
  mstr_standard tap *
  page24_i113
#ISCELL
  mstr_standard tap *
  page24_i114
#ISCELL
  mstr_standard tap *
  page24_i115
#ISCELL
  mstr_standard tap *
  page24_i116
#ISCELL
  mstr_standard tap *
  page24_i117
#ISCELL
  mstr_standard tap *
  page24_i118
#ISCELL
  mstr_standard tap *
  page24_i119
#ISCELL
  mstr_standard tap *
  page24_i12
#ISCELL
  mstr_standard tap *
  page24_i120
#ISCELL
  mstr_standard tap *
  page24_i121
#ISCELL
  mstr_standard tap *
  page24_i122
#ISCELL
  mstr_standard tap *
  page24_i123
#ISCELL
  mstr_standard tap *
  page24_i124
#ISCELL
  mstr_standard tap *
  page24_i125
#ISCELL
  mstr_standard tap *
  page24_i126
#ISCELL
  mstr_standard tap *
  page24_i127
#ISCELL
  mstr_standard tap *
  page24_i128
#ISCELL
  mstr_standard tap *
  page24_i129
#ISCELL
  mstr_standard tap *
  page24_i13
#ISCELL
  mstr_standard tap *
  page24_i130
#ISCELL
  mstr_standard tap *
  page24_i131
#ISCELL
  mstr_standard tap *
  page24_i132
#ISCELL
  mstr_standard tap *
  page24_i133
#ISCELL
  mstr_standard tap *
  page24_i134
#ISCELL
  mstr_standard tap *
  page24_i135
#ISCELL
  mstr_standard tap *
  page24_i136
#ISCELL
  mstr_standard tap *
  page24_i137
#ISCELL
  mstr_standard tap *
  page24_i138
#ISCELL
  mstr_standard tap *
  page24_i139
#ISCELL
  mstr_standard tap *
  page24_i14
#ISCELL
  mstr_standard tap *
  page24_i140
#ISCELL
  mstr_standard tap *
  page24_i141
#ISCELL
  mstr_standard tap *
  page24_i142
#ISCELL
  mstr_standard tap *
  page24_i143
#ISCELL
  mstr_standard tap *
  page24_i144
#ISCELL
  mstr_standard tap *
  page24_i145
#ISCELL
  mstr_standard tap *
  page24_i146
#ISCELL
  mstr_standard offpage *
  page24_i147
#ISCELL
  mstr_standard offpage *
  page24_i148
#ISCELL
  mstr_standard offpage *
  page24_i149
#ISCELL
  mstr_standard tap *
  page24_i15
#ISCELL
  mstr_standard offpage *
  page24_i150
#ISCELL
  mstr_standard offpage *
  page24_i151
#ISCELL
  mstr_standard offpage *
  page24_i152
#ISCELL
  mstr_standard offpage *
  page24_i153
#ISCELL
  mstr_standard offpage *
  page24_i154
#ISCELL
  mstr_standard offpage *
  page24_i155
#ISCELL
  mstr_standard offpage *
  page24_i156
#ISCELL
  mstr_standard tap *
  page24_i157
#ISCELL
  mstr_standard tap *
  page24_i158
#ISCELL
  mstr_standard tap *
  page24_i159
#ISCELL
  mstr_standard tap *
  page24_i16
#ISCELL
  mstr_standard tap *
  page24_i160
#ISCELL
  mstr_standard tap *
  page24_i161
#ISCELL
  mstr_standard tap *
  page24_i162
#ISCELL
  mstr_standard tap *
  page24_i163
#ISCELL
  mstr_standard tap *
  page24_i164
#ISCELL
  mstr_standard tap *
  page24_i165
#ISCELL
  mstr_standard tap *
  page24_i166
#ISCELL
  mstr_standard tap *
  page24_i167
#ISCELL
  mstr_standard tap *
  page24_i168
#ISCELL
  mstr_standard tap *
  page24_i169
#ISCELL
  mstr_standard tap *
  page24_i17
#ISCELL
  mstr_standard tap *
  page24_i170
#ISCELL
  mstr_standard offpage *
  page24_i171
#CELL
  chpset_lib skx_ext_b *
  page24_i172
#ISCELL
  mstr_standard tap *
  page24_i18
#ISCELL
  mstr_standard tap *
  page24_i19
#ISCELL
  mstr_standard offpage *
  page24_i2
#ISCELL
  mstr_standard tap *
  page24_i20
#ISCELL
  mstr_standard tap *
  page24_i21
#ISCELL
  mstr_standard tap *
  page24_i22
#ISCELL
  mstr_standard tap *
  page24_i23
#ISCELL
  mstr_standard tap *
  page24_i24
#ISCELL
  mstr_standard tap *
  page24_i25
#ISCELL
  mstr_standard tap *
  page24_i26
#ISCELL
  mstr_standard tap *
  page24_i27
#ISCELL
  mstr_standard tap *
  page24_i28
#ISCELL
  mstr_standard tap *
  page24_i29
#ISCELL
  mstr_standard offpage *
  page24_i3
#ISCELL
  mstr_standard tap *
  page24_i31
#ISCELL
  mstr_standard tap *
  page24_i32
#ISCELL
  mstr_standard tap *
  page24_i33
#ISCELL
  mstr_standard tap *
  page24_i34
#ISCELL
  mstr_standard tap *
  page24_i35
#ISCELL
  mstr_standard tap *
  page24_i36
#ISCELL
  mstr_standard tap *
  page24_i37
#ISCELL
  mstr_standard tap *
  page24_i38
#ISCELL
  mstr_standard tap *
  page24_i39
#ISCELL
  mstr_standard offpage *
  page24_i4
#ISCELL
  mstr_standard tap *
  page24_i40
#ISCELL
  mstr_standard tap *
  page24_i41
#ISCELL
  mstr_standard tap *
  page24_i42
#ISCELL
  mstr_standard tap *
  page24_i43
#ISCELL
  mstr_standard tap *
  page24_i44
#ISCELL
  mstr_standard tap *
  page24_i45
#ISCELL
  mstr_standard tap *
  page24_i46
#ISCELL
  mstr_standard tap *
  page24_i47
#ISCELL
  mstr_standard tap *
  page24_i48
#ISCELL
  mstr_standard tap *
  page24_i49
#ISCELL
  mstr_standard tap *
  page24_i5
#ISCELL
  mstr_standard tap *
  page24_i50
#ISCELL
  mstr_standard tap *
  page24_i51
#ISCELL
  mstr_standard tap *
  page24_i52
#ISCELL
  mstr_standard tap *
  page24_i53
#ISCELL
  mstr_standard tap *
  page24_i54
#ISCELL
  mstr_standard tap *
  page24_i55
#ISCELL
  mstr_standard tap *
  page24_i56
#ISCELL
  mstr_standard tap *
  page24_i57
#ISCELL
  mstr_standard tap *
  page24_i58
#ISCELL
  mstr_standard tap *
  page24_i59
#ISCELL
  mstr_standard tap *
  page24_i6
#ISCELL
  mstr_standard tap *
  page24_i60
#ISCELL
  mstr_standard tap *
  page24_i61
#ISCELL
  mstr_standard tap *
  page24_i62
#ISCELL
  mstr_standard tap *
  page24_i63
#ISCELL
  mstr_standard tap *
  page24_i64
#ISCELL
  mstr_standard tap *
  page24_i65
#ISCELL
  mstr_standard tap *
  page24_i66
#ISCELL
  mstr_standard tap *
  page24_i67
#ISCELL
  mstr_standard tap *
  page24_i68
#ISCELL
  mstr_standard tap *
  page24_i69
#ISCELL
  mstr_standard tap *
  page24_i7
#ISCELL
  mstr_standard tap *
  page24_i70
#ISCELL
  mstr_standard tap *
  page24_i71
#ISCELL
  mstr_standard offpage *
  page24_i72
#ISCELL
  mstr_standard tap *
  page24_i73
#ISCELL
  mstr_standard tap *
  page24_i74
#ISCELL
  mstr_standard tap *
  page24_i75
#ISCELL
  mstr_standard tap *
  page24_i76
#ISCELL
  mstr_standard tap *
  page24_i77
#ISCELL
  mstr_standard tap *
  page24_i78
#ISCELL
  mstr_standard tap *
  page24_i79
#ISCELL
  mstr_standard tap *
  page24_i8
#ISCELL
  mstr_standard tap *
  page24_i80
#ISCELL
  mstr_standard tap *
  page24_i81
#ISCELL
  mstr_standard tap *
  page24_i82
#ISCELL
  mstr_standard tap *
  page24_i83
#ISCELL
  mstr_standard tap *
  page24_i84
#ISCELL
  mstr_standard tap *
  page24_i85
#ISCELL
  mstr_standard tap *
  page24_i86
#ISCELL
  mstr_standard tap *
  page24_i87
#ISCELL
  mstr_standard tap *
  page24_i88
#ISCELL
  mstr_standard tap *
  page24_i89
#ISCELL
  mstr_standard tap *
  page24_i9
#ISCELL
  mstr_standard tap *
  page24_i90
#ISCELL
  mstr_standard tap *
  page24_i91
#ISCELL
  mstr_standard tap *
  page24_i92
#ISCELL
  mstr_standard tap *
  page24_i93
#ISCELL
  mstr_standard tap *
  page24_i94
#ISCELL
  mstr_standard tap *
  page24_i95
#ISCELL
  mstr_standard tap *
  page24_i96
#ISCELL
  mstr_standard tap *
  page24_i97
#ISCELL
  mstr_standard tap *
  page24_i98
#ISCELL
  mstr_standard tap *
  page24_i99
#ISCELL
  mstr_misc prelim *
  *
#ISCELL
  mstr_symbols design_note *
  *
#ISCELL
  mstr_symbols intel_corp_bpage *
  *
#ISCELL
  mstr_standard offpage *
  page25_i1
#ISCELL
  mstr_standard tap *
  page25_i10
#ISCELL
  mstr_standard tap *
  page25_i100
#ISCELL
  mstr_standard tap *
  page25_i101
#ISCELL
  mstr_standard tap *
  page25_i102
#ISCELL
  mstr_standard tap *
  page25_i103
#ISCELL
  mstr_standard tap *
  page25_i104
#ISCELL
  mstr_standard tap *
  page25_i105
#ISCELL
  mstr_standard tap *
  page25_i106
#ISCELL
  mstr_standard tap *
  page25_i107
#ISCELL
  mstr_standard tap *
  page25_i108
#ISCELL
  mstr_standard tap *
  page25_i109
#ISCELL
  mstr_standard tap *
  page25_i11
#ISCELL
  mstr_standard tap *
  page25_i110
#ISCELL
  mstr_standard tap *
  page25_i111
#ISCELL
  mstr_standard tap *
  page25_i112
#ISCELL
  mstr_standard tap *
  page25_i113
#ISCELL
  mstr_standard tap *
  page25_i114
#ISCELL
  mstr_standard tap *
  page25_i115
#ISCELL
  mstr_standard tap *
  page25_i116
#ISCELL
  mstr_standard tap *
  page25_i117
#ISCELL
  mstr_standard tap *
  page25_i118
#ISCELL
  mstr_standard tap *
  page25_i119
#ISCELL
  mstr_standard tap *
  page25_i12
#ISCELL
  mstr_standard tap *
  page25_i120
#ISCELL
  mstr_standard tap *
  page25_i121
#ISCELL
  mstr_standard tap *
  page25_i122
#ISCELL
  mstr_standard tap *
  page25_i123
#ISCELL
  mstr_standard tap *
  page25_i124
#ISCELL
  mstr_standard tap *
  page25_i125
#ISCELL
  mstr_standard tap *
  page25_i126
#ISCELL
  mstr_standard tap *
  page25_i127
#ISCELL
  mstr_standard tap *
  page25_i128
#ISCELL
  mstr_standard tap *
  page25_i129
#ISCELL
  mstr_standard tap *
  page25_i13
#ISCELL
  mstr_standard tap *
  page25_i130
#ISCELL
  mstr_standard tap *
  page25_i131
#ISCELL
  mstr_standard tap *
  page25_i132
#ISCELL
  mstr_standard tap *
  page25_i133
#ISCELL
  mstr_standard tap *
  page25_i134
#ISCELL
  mstr_standard tap *
  page25_i135
#ISCELL
  mstr_standard tap *
  page25_i136
#ISCELL
  mstr_standard tap *
  page25_i137
#ISCELL
  mstr_standard tap *
  page25_i138
#ISCELL
  mstr_standard tap *
  page25_i139
#ISCELL
  mstr_standard tap *
  page25_i14
#ISCELL
  mstr_standard tap *
  page25_i140
#ISCELL
  mstr_standard tap *
  page25_i141
#ISCELL
  mstr_standard tap *
  page25_i142
#ISCELL
  mstr_standard tap *
  page25_i143
#ISCELL
  mstr_standard tap *
  page25_i144
#ISCELL
  mstr_standard tap *
  page25_i145
#ISCELL
  mstr_standard tap *
  page25_i146
#ISCELL
  mstr_standard offpage *
  page25_i147
#ISCELL
  mstr_standard offpage *
  page25_i148
#ISCELL
  mstr_standard offpage *
  page25_i149
#ISCELL
  mstr_standard tap *
  page25_i15
#ISCELL
  mstr_standard offpage *
  page25_i150
#ISCELL
  mstr_standard offpage *
  page25_i151
#ISCELL
  mstr_standard offpage *
  page25_i152
#ISCELL
  mstr_standard offpage *
  page25_i153
#ISCELL
  mstr_standard offpage *
  page25_i154
#ISCELL
  mstr_standard offpage *
  page25_i155
#ISCELL
  mstr_standard offpage *
  page25_i156
#ISCELL
  mstr_standard tap *
  page25_i157
#ISCELL
  mstr_standard tap *
  page25_i158
#ISCELL
  mstr_standard tap *
  page25_i159
#ISCELL
  mstr_standard tap *
  page25_i16
#ISCELL
  mstr_standard tap *
  page25_i160
#ISCELL
  mstr_standard tap *
  page25_i161
#ISCELL
  mstr_standard tap *
  page25_i162
#ISCELL
  mstr_standard tap *
  page25_i163
#ISCELL
  mstr_standard tap *
  page25_i164
#ISCELL
  mstr_standard tap *
  page25_i165
#ISCELL
  mstr_standard tap *
  page25_i166
#ISCELL
  mstr_standard tap *
  page25_i167
#ISCELL
  mstr_standard tap *
  page25_i168
#ISCELL
  mstr_standard tap *
  page25_i169
#ISCELL
  mstr_standard tap *
  page25_i17
#ISCELL
  mstr_standard tap *
  page25_i170
#ISCELL
  mstr_standard offpage *
  page25_i171
#CELL
  chpset_lib skx_ext_b *
  page25_i172
#ISCELL
  mstr_standard tap *
  page25_i18
#ISCELL
  mstr_standard tap *
  page25_i19
#ISCELL
  mstr_standard offpage *
  page25_i2
#ISCELL
  mstr_standard tap *
  page25_i20
#ISCELL
  mstr_standard tap *
  page25_i21
#ISCELL
  mstr_standard tap *
  page25_i22
#ISCELL
  mstr_standard tap *
  page25_i23
#ISCELL
  mstr_standard tap *
  page25_i24
#ISCELL
  mstr_standard tap *
  page25_i25
#ISCELL
  mstr_standard tap *
  page25_i26
#ISCELL
  mstr_standard tap *
  page25_i27
#ISCELL
  mstr_standard tap *
  page25_i28
#ISCELL
  mstr_standard tap *
  page25_i29
#ISCELL
  mstr_standard offpage *
  page25_i3
#ISCELL
  mstr_standard tap *
  page25_i31
#ISCELL
  mstr_standard tap *
  page25_i32
#ISCELL
  mstr_standard tap *
  page25_i33
#ISCELL
  mstr_standard tap *
  page25_i34
#ISCELL
  mstr_standard tap *
  page25_i35
#ISCELL
  mstr_standard tap *
  page25_i36
#ISCELL
  mstr_standard tap *
  page25_i37
#ISCELL
  mstr_standard tap *
  page25_i38
#ISCELL
  mstr_standard tap *
  page25_i39
#ISCELL
  mstr_standard offpage *
  page25_i4
#ISCELL
  mstr_standard tap *
  page25_i40
#ISCELL
  mstr_standard tap *
  page25_i41
#ISCELL
  mstr_standard tap *
  page25_i42
#ISCELL
  mstr_standard tap *
  page25_i43
#ISCELL
  mstr_standard tap *
  page25_i44
#ISCELL
  mstr_standard tap *
  page25_i45
#ISCELL
  mstr_standard tap *
  page25_i46
#ISCELL
  mstr_standard tap *
  page25_i47
#ISCELL
  mstr_standard tap *
  page25_i48
#ISCELL
  mstr_standard tap *
  page25_i49
#ISCELL
  mstr_standard tap *
  page25_i5
#ISCELL
  mstr_standard tap *
  page25_i50
#ISCELL
  mstr_standard tap *
  page25_i51
#ISCELL
  mstr_standard tap *
  page25_i52
#ISCELL
  mstr_standard tap *
  page25_i53
#ISCELL
  mstr_standard tap *
  page25_i54
#ISCELL
  mstr_standard tap *
  page25_i55
#ISCELL
  mstr_standard tap *
  page25_i56
#ISCELL
  mstr_standard tap *
  page25_i57
#ISCELL
  mstr_standard tap *
  page25_i58
#ISCELL
  mstr_standard tap *
  page25_i59
#ISCELL
  mstr_standard tap *
  page25_i6
#ISCELL
  mstr_standard tap *
  page25_i60
#ISCELL
  mstr_standard tap *
  page25_i61
#ISCELL
  mstr_standard tap *
  page25_i62
#ISCELL
  mstr_standard tap *
  page25_i63
#ISCELL
  mstr_standard tap *
  page25_i64
#ISCELL
  mstr_standard tap *
  page25_i65
#ISCELL
  mstr_standard tap *
  page25_i66
#ISCELL
  mstr_standard tap *
  page25_i67
#ISCELL
  mstr_standard tap *
  page25_i68
#ISCELL
  mstr_standard tap *
  page25_i69
#ISCELL
  mstr_standard tap *
  page25_i7
#ISCELL
  mstr_standard tap *
  page25_i70
#ISCELL
  mstr_standard tap *
  page25_i71
#ISCELL
  mstr_standard offpage *
  page25_i72
#ISCELL
  mstr_standard tap *
  page25_i73
#ISCELL
  mstr_standard tap *
  page25_i74
#ISCELL
  mstr_standard tap *
  page25_i75
#ISCELL
  mstr_standard tap *
  page25_i76
#ISCELL
  mstr_standard tap *
  page25_i77
#ISCELL
  mstr_standard tap *
  page25_i78
#ISCELL
  mstr_standard tap *
  page25_i79
#ISCELL
  mstr_standard tap *
  page25_i8
#ISCELL
  mstr_standard tap *
  page25_i80
#ISCELL
  mstr_standard tap *
  page25_i81
#ISCELL
  mstr_standard tap *
  page25_i82
#ISCELL
  mstr_standard tap *
  page25_i83
#ISCELL
  mstr_standard tap *
  page25_i84
#ISCELL
  mstr_standard tap *
  page25_i85
#ISCELL
  mstr_standard tap *
  page25_i86
#ISCELL
  mstr_standard tap *
  page25_i87
#ISCELL
  mstr_standard tap *
  page25_i88
#ISCELL
  mstr_standard tap *
  page25_i89
#ISCELL
  mstr_standard tap *
  page25_i9
#ISCELL
  mstr_standard tap *
  page25_i90
#ISCELL
  mstr_standard tap *
  page25_i91
#ISCELL
  mstr_standard tap *
  page25_i92
#ISCELL
  mstr_standard tap *
  page25_i93
#ISCELL
  mstr_standard tap *
  page25_i94
#ISCELL
  mstr_standard tap *
  page25_i95
#ISCELL
  mstr_standard tap *
  page25_i96
#ISCELL
  mstr_standard tap *
  page25_i97
#ISCELL
  mstr_standard tap *
  page25_i98
#ISCELL
  mstr_standard tap *
  page25_i99
#ISCELL
  mstr_misc prelim *
  *
#ISCELL
  mstr_symbols design_note *
  *
#ISCELL
  mstr_symbols intel_corp_bpage *
  *
#ISCELL
  mstr_standard offpage *
  page26_i1
#ISCELL
  mstr_standard tap *
  page26_i10
#ISCELL
  mstr_standard tap *
  page26_i100
#ISCELL
  mstr_standard tap *
  page26_i101
#ISCELL
  mstr_standard tap *
  page26_i102
#ISCELL
  mstr_standard tap *
  page26_i103
#ISCELL
  mstr_standard tap *
  page26_i104
#ISCELL
  mstr_standard tap *
  page26_i105
#ISCELL
  mstr_standard tap *
  page26_i106
#ISCELL
  mstr_standard tap *
  page26_i107
#ISCELL
  mstr_standard tap *
  page26_i108
#ISCELL
  mstr_standard tap *
  page26_i109
#ISCELL
  mstr_standard tap *
  page26_i11
#ISCELL
  mstr_standard tap *
  page26_i110
#ISCELL
  mstr_standard tap *
  page26_i111
#ISCELL
  mstr_standard tap *
  page26_i112
#ISCELL
  mstr_standard tap *
  page26_i113
#ISCELL
  mstr_standard tap *
  page26_i114
#ISCELL
  mstr_standard tap *
  page26_i115
#ISCELL
  mstr_standard tap *
  page26_i116
#ISCELL
  mstr_standard tap *
  page26_i117
#ISCELL
  mstr_standard tap *
  page26_i118
#ISCELL
  mstr_standard tap *
  page26_i119
#ISCELL
  mstr_standard tap *
  page26_i12
#ISCELL
  mstr_standard tap *
  page26_i120
#ISCELL
  mstr_standard tap *
  page26_i121
#ISCELL
  mstr_standard tap *
  page26_i122
#ISCELL
  mstr_standard tap *
  page26_i123
#ISCELL
  mstr_standard tap *
  page26_i124
#ISCELL
  mstr_standard tap *
  page26_i125
#ISCELL
  mstr_standard tap *
  page26_i126
#ISCELL
  mstr_standard tap *
  page26_i127
#ISCELL
  mstr_standard tap *
  page26_i128
#ISCELL
  mstr_standard tap *
  page26_i129
#ISCELL
  mstr_standard tap *
  page26_i13
#ISCELL
  mstr_standard tap *
  page26_i130
#ISCELL
  mstr_standard tap *
  page26_i131
#ISCELL
  mstr_standard tap *
  page26_i132
#ISCELL
  mstr_standard tap *
  page26_i133
#ISCELL
  mstr_standard tap *
  page26_i134
#ISCELL
  mstr_standard tap *
  page26_i135
#ISCELL
  mstr_standard tap *
  page26_i136
#ISCELL
  mstr_standard tap *
  page26_i137
#ISCELL
  mstr_standard tap *
  page26_i138
#ISCELL
  mstr_standard tap *
  page26_i139
#ISCELL
  mstr_standard tap *
  page26_i14
#ISCELL
  mstr_standard tap *
  page26_i140
#ISCELL
  mstr_standard tap *
  page26_i141
#ISCELL
  mstr_standard tap *
  page26_i142
#ISCELL
  mstr_standard tap *
  page26_i143
#ISCELL
  mstr_standard tap *
  page26_i144
#ISCELL
  mstr_standard tap *
  page26_i145
#ISCELL
  mstr_standard tap *
  page26_i146
#ISCELL
  mstr_standard offpage *
  page26_i147
#ISCELL
  mstr_standard offpage *
  page26_i148
#ISCELL
  mstr_standard offpage *
  page26_i149
#ISCELL
  mstr_standard tap *
  page26_i15
#ISCELL
  mstr_standard offpage *
  page26_i150
#ISCELL
  mstr_standard offpage *
  page26_i151
#ISCELL
  mstr_standard offpage *
  page26_i152
#ISCELL
  mstr_standard offpage *
  page26_i153
#ISCELL
  mstr_standard offpage *
  page26_i154
#ISCELL
  mstr_standard offpage *
  page26_i155
#ISCELL
  mstr_standard offpage *
  page26_i156
#ISCELL
  mstr_standard tap *
  page26_i157
#ISCELL
  mstr_standard tap *
  page26_i158
#ISCELL
  mstr_standard tap *
  page26_i159
#ISCELL
  mstr_standard tap *
  page26_i16
#ISCELL
  mstr_standard tap *
  page26_i160
#ISCELL
  mstr_standard tap *
  page26_i161
#ISCELL
  mstr_standard tap *
  page26_i162
#ISCELL
  mstr_standard tap *
  page26_i163
#ISCELL
  mstr_standard tap *
  page26_i164
#ISCELL
  mstr_standard tap *
  page26_i165
#ISCELL
  mstr_standard tap *
  page26_i166
#ISCELL
  mstr_standard tap *
  page26_i167
#ISCELL
  mstr_standard tap *
  page26_i168
#ISCELL
  mstr_standard tap *
  page26_i169
#ISCELL
  mstr_standard tap *
  page26_i17
#ISCELL
  mstr_standard tap *
  page26_i170
#ISCELL
  mstr_standard offpage *
  page26_i171
#CELL
  chpset_lib skx_ext_b *
  page26_i172
#ISCELL
  mstr_standard tap *
  page26_i18
#ISCELL
  mstr_standard tap *
  page26_i19
#ISCELL
  mstr_standard offpage *
  page26_i2
#ISCELL
  mstr_standard tap *
  page26_i20
#ISCELL
  mstr_standard tap *
  page26_i21
#ISCELL
  mstr_standard tap *
  page26_i22
#ISCELL
  mstr_standard tap *
  page26_i23
#ISCELL
  mstr_standard tap *
  page26_i24
#ISCELL
  mstr_standard tap *
  page26_i25
#ISCELL
  mstr_standard tap *
  page26_i26
#ISCELL
  mstr_standard tap *
  page26_i27
#ISCELL
  mstr_standard tap *
  page26_i28
#ISCELL
  mstr_standard tap *
  page26_i29
#ISCELL
  mstr_standard offpage *
  page26_i3
#ISCELL
  mstr_standard tap *
  page26_i31
#ISCELL
  mstr_standard tap *
  page26_i32
#ISCELL
  mstr_standard tap *
  page26_i33
#ISCELL
  mstr_standard tap *
  page26_i34
#ISCELL
  mstr_standard tap *
  page26_i35
#ISCELL
  mstr_standard tap *
  page26_i36
#ISCELL
  mstr_standard tap *
  page26_i37
#ISCELL
  mstr_standard tap *
  page26_i38
#ISCELL
  mstr_standard tap *
  page26_i39
#ISCELL
  mstr_standard offpage *
  page26_i4
#ISCELL
  mstr_standard tap *
  page26_i40
#ISCELL
  mstr_standard tap *
  page26_i41
#ISCELL
  mstr_standard tap *
  page26_i42
#ISCELL
  mstr_standard tap *
  page26_i43
#ISCELL
  mstr_standard tap *
  page26_i44
#ISCELL
  mstr_standard tap *
  page26_i45
#ISCELL
  mstr_standard tap *
  page26_i46
#ISCELL
  mstr_standard tap *
  page26_i47
#ISCELL
  mstr_standard tap *
  page26_i48
#ISCELL
  mstr_standard tap *
  page26_i49
#ISCELL
  mstr_standard tap *
  page26_i5
#ISCELL
  mstr_standard tap *
  page26_i50
#ISCELL
  mstr_standard tap *
  page26_i51
#ISCELL
  mstr_standard tap *
  page26_i52
#ISCELL
  mstr_standard tap *
  page26_i53
#ISCELL
  mstr_standard tap *
  page26_i54
#ISCELL
  mstr_standard tap *
  page26_i55
#ISCELL
  mstr_standard tap *
  page26_i56
#ISCELL
  mstr_standard tap *
  page26_i57
#ISCELL
  mstr_standard tap *
  page26_i58
#ISCELL
  mstr_standard tap *
  page26_i59
#ISCELL
  mstr_standard tap *
  page26_i6
#ISCELL
  mstr_standard tap *
  page26_i60
#ISCELL
  mstr_standard tap *
  page26_i61
#ISCELL
  mstr_standard tap *
  page26_i62
#ISCELL
  mstr_standard tap *
  page26_i63
#ISCELL
  mstr_standard tap *
  page26_i64
#ISCELL
  mstr_standard tap *
  page26_i65
#ISCELL
  mstr_standard tap *
  page26_i66
#ISCELL
  mstr_standard tap *
  page26_i67
#ISCELL
  mstr_standard tap *
  page26_i68
#ISCELL
  mstr_standard tap *
  page26_i69
#ISCELL
  mstr_standard tap *
  page26_i7
#ISCELL
  mstr_standard tap *
  page26_i70
#ISCELL
  mstr_standard tap *
  page26_i71
#ISCELL
  mstr_standard offpage *
  page26_i72
#ISCELL
  mstr_standard tap *
  page26_i73
#ISCELL
  mstr_standard tap *
  page26_i74
#ISCELL
  mstr_standard tap *
  page26_i75
#ISCELL
  mstr_standard tap *
  page26_i76
#ISCELL
  mstr_standard tap *
  page26_i77
#ISCELL
  mstr_standard tap *
  page26_i78
#ISCELL
  mstr_standard tap *
  page26_i79
#ISCELL
  mstr_standard tap *
  page26_i8
#ISCELL
  mstr_standard tap *
  page26_i80
#ISCELL
  mstr_standard tap *
  page26_i81
#ISCELL
  mstr_standard tap *
  page26_i82
#ISCELL
  mstr_standard tap *
  page26_i83
#ISCELL
  mstr_standard tap *
  page26_i84
#ISCELL
  mstr_standard tap *
  page26_i85
#ISCELL
  mstr_standard tap *
  page26_i86
#ISCELL
  mstr_standard tap *
  page26_i87
#ISCELL
  mstr_standard tap *
  page26_i88
#ISCELL
  mstr_standard tap *
  page26_i89
#ISCELL
  mstr_standard tap *
  page26_i9
#ISCELL
  mstr_standard tap *
  page26_i90
#ISCELL
  mstr_standard tap *
  page26_i91
#ISCELL
  mstr_standard tap *
  page26_i92
#ISCELL
  mstr_standard tap *
  page26_i93
#ISCELL
  mstr_standard tap *
  page26_i94
#ISCELL
  mstr_standard tap *
  page26_i95
#ISCELL
  mstr_standard tap *
  page26_i96
#ISCELL
  mstr_standard tap *
  page26_i97
#ISCELL
  mstr_standard tap *
  page26_i98
#ISCELL
  mstr_standard tap *
  page26_i99
#ISCELL
  mstr_misc prelim *
  *
#ISCELL
  mstr_symbols design_note *
  *
#ISCELL
  mstr_symbols intel_corp_bpage *
  *
#ISCELL
  mstr_standard offpage *
  page27_i1
#ISCELL
  mstr_standard tap *
  page27_i10
#ISCELL
  mstr_standard tap *
  page27_i100
#ISCELL
  mstr_standard tap *
  page27_i101
#ISCELL
  mstr_standard tap *
  page27_i102
#ISCELL
  mstr_standard tap *
  page27_i103
#ISCELL
  mstr_standard tap *
  page27_i104
#ISCELL
  mstr_standard tap *
  page27_i105
#ISCELL
  mstr_standard tap *
  page27_i106
#ISCELL
  mstr_standard tap *
  page27_i107
#ISCELL
  mstr_standard tap *
  page27_i108
#ISCELL
  mstr_standard tap *
  page27_i109
#ISCELL
  mstr_standard tap *
  page27_i11
#ISCELL
  mstr_standard tap *
  page27_i110
#ISCELL
  mstr_standard tap *
  page27_i111
#ISCELL
  mstr_standard tap *
  page27_i112
#ISCELL
  mstr_standard tap *
  page27_i113
#ISCELL
  mstr_standard tap *
  page27_i114
#ISCELL
  mstr_standard tap *
  page27_i115
#ISCELL
  mstr_standard tap *
  page27_i116
#ISCELL
  mstr_standard tap *
  page27_i117
#ISCELL
  mstr_standard tap *
  page27_i118
#ISCELL
  mstr_standard tap *
  page27_i119
#ISCELL
  mstr_standard tap *
  page27_i12
#ISCELL
  mstr_standard tap *
  page27_i120
#ISCELL
  mstr_standard tap *
  page27_i121
#ISCELL
  mstr_standard tap *
  page27_i122
#ISCELL
  mstr_standard tap *
  page27_i123
#ISCELL
  mstr_standard tap *
  page27_i124
#ISCELL
  mstr_standard tap *
  page27_i125
#ISCELL
  mstr_standard tap *
  page27_i126
#ISCELL
  mstr_standard tap *
  page27_i127
#ISCELL
  mstr_standard tap *
  page27_i128
#ISCELL
  mstr_standard tap *
  page27_i129
#ISCELL
  mstr_standard tap *
  page27_i13
#ISCELL
  mstr_standard tap *
  page27_i130
#ISCELL
  mstr_standard tap *
  page27_i131
#ISCELL
  mstr_standard tap *
  page27_i132
#ISCELL
  mstr_standard tap *
  page27_i133
#ISCELL
  mstr_standard tap *
  page27_i134
#ISCELL
  mstr_standard tap *
  page27_i135
#ISCELL
  mstr_standard tap *
  page27_i136
#ISCELL
  mstr_standard tap *
  page27_i137
#ISCELL
  mstr_standard tap *
  page27_i138
#ISCELL
  mstr_standard tap *
  page27_i139
#ISCELL
  mstr_standard tap *
  page27_i14
#ISCELL
  mstr_standard tap *
  page27_i140
#ISCELL
  mstr_standard tap *
  page27_i141
#ISCELL
  mstr_standard tap *
  page27_i142
#ISCELL
  mstr_standard tap *
  page27_i143
#ISCELL
  mstr_standard tap *
  page27_i144
#ISCELL
  mstr_standard tap *
  page27_i145
#ISCELL
  mstr_standard tap *
  page27_i146
#ISCELL
  mstr_standard tap *
  page27_i147
#ISCELL
  mstr_standard offpage *
  page27_i148
#ISCELL
  mstr_standard offpage *
  page27_i149
#ISCELL
  mstr_standard tap *
  page27_i15
#ISCELL
  mstr_standard offpage *
  page27_i150
#ISCELL
  mstr_standard offpage *
  page27_i151
#ISCELL
  mstr_standard offpage *
  page27_i152
#ISCELL
  mstr_standard offpage *
  page27_i153
#ISCELL
  mstr_standard offpage *
  page27_i154
#ISCELL
  mstr_standard offpage *
  page27_i155
#ISCELL
  mstr_standard offpage *
  page27_i156
#ISCELL
  mstr_standard offpage *
  page27_i157
#ISCELL
  mstr_standard tap *
  page27_i158
#ISCELL
  mstr_standard tap *
  page27_i159
#ISCELL
  mstr_standard tap *
  page27_i16
#ISCELL
  mstr_standard tap *
  page27_i160
#ISCELL
  mstr_standard tap *
  page27_i161
#ISCELL
  mstr_standard tap *
  page27_i162
#ISCELL
  mstr_standard tap *
  page27_i163
#ISCELL
  mstr_standard tap *
  page27_i164
#ISCELL
  mstr_standard tap *
  page27_i165
#ISCELL
  mstr_standard tap *
  page27_i166
#ISCELL
  mstr_standard tap *
  page27_i167
#ISCELL
  mstr_standard tap *
  page27_i168
#ISCELL
  mstr_standard tap *
  page27_i169
#ISCELL
  mstr_standard tap *
  page27_i17
#ISCELL
  mstr_standard tap *
  page27_i170
#ISCELL
  mstr_standard offpage *
  page27_i171
#CELL
  chpset_lib skx_ext_b *
  page27_i172
#ISCELL
  mstr_standard tap *
  page27_i18
#ISCELL
  mstr_standard tap *
  page27_i19
#ISCELL
  mstr_standard offpage *
  page27_i2
#ISCELL
  mstr_standard tap *
  page27_i20
#ISCELL
  mstr_standard tap *
  page27_i21
#ISCELL
  mstr_standard tap *
  page27_i22
#ISCELL
  mstr_standard tap *
  page27_i23
#ISCELL
  mstr_standard tap *
  page27_i24
#ISCELL
  mstr_standard tap *
  page27_i25
#ISCELL
  mstr_standard tap *
  page27_i26
#ISCELL
  mstr_standard tap *
  page27_i27
#ISCELL
  mstr_standard tap *
  page27_i28
#ISCELL
  mstr_standard tap *
  page27_i29
#ISCELL
  mstr_standard offpage *
  page27_i3
#ISCELL
  mstr_standard tap *
  page27_i30
#ISCELL
  mstr_standard tap *
  page27_i32
#ISCELL
  mstr_standard tap *
  page27_i33
#ISCELL
  mstr_standard tap *
  page27_i34
#ISCELL
  mstr_standard tap *
  page27_i35
#ISCELL
  mstr_standard tap *
  page27_i36
#ISCELL
  mstr_standard tap *
  page27_i37
#ISCELL
  mstr_standard tap *
  page27_i38
#ISCELL
  mstr_standard tap *
  page27_i39
#ISCELL
  mstr_standard offpage *
  page27_i4
#ISCELL
  mstr_standard tap *
  page27_i40
#ISCELL
  mstr_standard tap *
  page27_i41
#ISCELL
  mstr_standard tap *
  page27_i42
#ISCELL
  mstr_standard tap *
  page27_i43
#ISCELL
  mstr_standard tap *
  page27_i44
#ISCELL
  mstr_standard tap *
  page27_i45
#ISCELL
  mstr_standard tap *
  page27_i46
#ISCELL
  mstr_standard tap *
  page27_i47
#ISCELL
  mstr_standard tap *
  page27_i48
#ISCELL
  mstr_standard tap *
  page27_i49
#ISCELL
  mstr_standard tap *
  page27_i5
#ISCELL
  mstr_standard tap *
  page27_i50
#ISCELL
  mstr_standard tap *
  page27_i51
#ISCELL
  mstr_standard tap *
  page27_i52
#ISCELL
  mstr_standard tap *
  page27_i53
#ISCELL
  mstr_standard tap *
  page27_i54
#ISCELL
  mstr_standard tap *
  page27_i55
#ISCELL
  mstr_standard tap *
  page27_i56
#ISCELL
  mstr_standard tap *
  page27_i57
#ISCELL
  mstr_standard tap *
  page27_i58
#ISCELL
  mstr_standard tap *
  page27_i59
#ISCELL
  mstr_standard tap *
  page27_i6
#ISCELL
  mstr_standard tap *
  page27_i60
#ISCELL
  mstr_standard tap *
  page27_i61
#ISCELL
  mstr_standard tap *
  page27_i62
#ISCELL
  mstr_standard tap *
  page27_i63
#ISCELL
  mstr_standard tap *
  page27_i64
#ISCELL
  mstr_standard tap *
  page27_i65
#ISCELL
  mstr_standard tap *
  page27_i66
#ISCELL
  mstr_standard tap *
  page27_i67
#ISCELL
  mstr_standard tap *
  page27_i68
#ISCELL
  mstr_standard tap *
  page27_i69
#ISCELL
  mstr_standard tap *
  page27_i7
#ISCELL
  mstr_standard tap *
  page27_i70
#ISCELL
  mstr_standard tap *
  page27_i71
#ISCELL
  mstr_standard tap *
  page27_i72
#ISCELL
  mstr_standard offpage *
  page27_i73
#ISCELL
  mstr_standard tap *
  page27_i74
#ISCELL
  mstr_standard tap *
  page27_i75
#ISCELL
  mstr_standard tap *
  page27_i76
#ISCELL
  mstr_standard tap *
  page27_i77
#ISCELL
  mstr_standard tap *
  page27_i78
#ISCELL
  mstr_standard tap *
  page27_i79
#ISCELL
  mstr_standard tap *
  page27_i8
#ISCELL
  mstr_standard tap *
  page27_i80
#ISCELL
  mstr_standard tap *
  page27_i81
#ISCELL
  mstr_standard tap *
  page27_i82
#ISCELL
  mstr_standard tap *
  page27_i83
#ISCELL
  mstr_standard tap *
  page27_i84
#ISCELL
  mstr_standard tap *
  page27_i85
#ISCELL
  mstr_standard tap *
  page27_i86
#ISCELL
  mstr_standard tap *
  page27_i87
#ISCELL
  mstr_standard tap *
  page27_i88
#ISCELL
  mstr_standard tap *
  page27_i89
#ISCELL
  mstr_standard tap *
  page27_i9
#ISCELL
  mstr_standard tap *
  page27_i90
#ISCELL
  mstr_standard tap *
  page27_i91
#ISCELL
  mstr_standard tap *
  page27_i92
#ISCELL
  mstr_standard tap *
  page27_i93
#ISCELL
  mstr_standard tap *
  page27_i94
#ISCELL
  mstr_standard tap *
  page27_i95
#ISCELL
  mstr_standard tap *
  page27_i96
#ISCELL
  mstr_standard tap *
  page27_i97
#ISCELL
  mstr_standard tap *
  page27_i98
#ISCELL
  mstr_standard tap *
  page27_i99
#ISCELL
  mstr_misc prelim *
  *
#ISCELL
  mstr_symbols design_note *
  *
#ISCELL
  mstr_symbols intel_corp_bpage *
  *
#ISCELL
  mstr_standard offpage *
  page28_i1
#ISCELL
  mstr_standard tap *
  page28_i10
#ISCELL
  mstr_standard tap *
  page28_i100
#ISCELL
  mstr_standard tap *
  page28_i101
#ISCELL
  mstr_standard tap *
  page28_i102
#ISCELL
  mstr_standard tap *
  page28_i103
#ISCELL
  mstr_standard tap *
  page28_i104
#ISCELL
  mstr_standard tap *
  page28_i105
#ISCELL
  mstr_standard tap *
  page28_i106
#ISCELL
  mstr_standard tap *
  page28_i107
#ISCELL
  mstr_standard tap *
  page28_i108
#ISCELL
  mstr_standard tap *
  page28_i109
#ISCELL
  mstr_standard tap *
  page28_i11
#ISCELL
  mstr_standard tap *
  page28_i110
#ISCELL
  mstr_standard tap *
  page28_i111
#ISCELL
  mstr_standard tap *
  page28_i112
#ISCELL
  mstr_standard tap *
  page28_i113
#ISCELL
  mstr_standard tap *
  page28_i114
#ISCELL
  mstr_standard tap *
  page28_i115
#ISCELL
  mstr_standard tap *
  page28_i116
#ISCELL
  mstr_standard tap *
  page28_i117
#ISCELL
  mstr_standard tap *
  page28_i118
#ISCELL
  mstr_standard tap *
  page28_i119
#ISCELL
  mstr_standard tap *
  page28_i12
#ISCELL
  mstr_standard tap *
  page28_i120
#ISCELL
  mstr_standard tap *
  page28_i121
#ISCELL
  mstr_standard tap *
  page28_i122
#ISCELL
  mstr_standard tap *
  page28_i123
#ISCELL
  mstr_standard tap *
  page28_i124
#ISCELL
  mstr_standard tap *
  page28_i125
#ISCELL
  mstr_standard tap *
  page28_i126
#ISCELL
  mstr_standard tap *
  page28_i127
#ISCELL
  mstr_standard tap *
  page28_i128
#ISCELL
  mstr_standard tap *
  page28_i129
#ISCELL
  mstr_standard tap *
  page28_i13
#ISCELL
  mstr_standard tap *
  page28_i130
#ISCELL
  mstr_standard tap *
  page28_i131
#ISCELL
  mstr_standard tap *
  page28_i132
#ISCELL
  mstr_standard tap *
  page28_i133
#ISCELL
  mstr_standard tap *
  page28_i134
#ISCELL
  mstr_standard tap *
  page28_i135
#ISCELL
  mstr_standard tap *
  page28_i136
#ISCELL
  mstr_standard tap *
  page28_i137
#ISCELL
  mstr_standard tap *
  page28_i138
#ISCELL
  mstr_standard tap *
  page28_i139
#ISCELL
  mstr_standard tap *
  page28_i14
#ISCELL
  mstr_standard tap *
  page28_i140
#ISCELL
  mstr_standard tap *
  page28_i141
#ISCELL
  mstr_standard tap *
  page28_i142
#ISCELL
  mstr_standard tap *
  page28_i143
#ISCELL
  mstr_standard tap *
  page28_i144
#ISCELL
  mstr_standard tap *
  page28_i145
#ISCELL
  mstr_standard tap *
  page28_i146
#ISCELL
  mstr_standard tap *
  page28_i147
#ISCELL
  mstr_standard offpage *
  page28_i148
#ISCELL
  mstr_standard offpage *
  page28_i149
#ISCELL
  mstr_standard tap *
  page28_i15
#ISCELL
  mstr_standard offpage *
  page28_i150
#ISCELL
  mstr_standard offpage *
  page28_i151
#ISCELL
  mstr_standard offpage *
  page28_i152
#ISCELL
  mstr_standard offpage *
  page28_i153
#ISCELL
  mstr_standard offpage *
  page28_i154
#ISCELL
  mstr_standard offpage *
  page28_i155
#ISCELL
  mstr_standard offpage *
  page28_i156
#ISCELL
  mstr_standard offpage *
  page28_i157
#ISCELL
  mstr_standard tap *
  page28_i158
#ISCELL
  mstr_standard tap *
  page28_i159
#ISCELL
  mstr_standard tap *
  page28_i16
#ISCELL
  mstr_standard tap *
  page28_i160
#ISCELL
  mstr_standard tap *
  page28_i161
#ISCELL
  mstr_standard tap *
  page28_i162
#ISCELL
  mstr_standard tap *
  page28_i163
#ISCELL
  mstr_standard tap *
  page28_i164
#ISCELL
  mstr_standard tap *
  page28_i165
#ISCELL
  mstr_standard tap *
  page28_i166
#ISCELL
  mstr_standard tap *
  page28_i167
#ISCELL
  mstr_standard tap *
  page28_i168
#ISCELL
  mstr_standard tap *
  page28_i169
#ISCELL
  mstr_standard tap *
  page28_i17
#ISCELL
  mstr_standard tap *
  page28_i170
#ISCELL
  mstr_standard offpage *
  page28_i171
#CELL
  chpset_lib skx_ext_b *
  page28_i172
#ISCELL
  mstr_standard tap *
  page28_i18
#ISCELL
  mstr_standard tap *
  page28_i19
#ISCELL
  mstr_standard offpage *
  page28_i2
#ISCELL
  mstr_standard tap *
  page28_i20
#ISCELL
  mstr_standard tap *
  page28_i21
#ISCELL
  mstr_standard tap *
  page28_i22
#ISCELL
  mstr_standard tap *
  page28_i23
#ISCELL
  mstr_standard tap *
  page28_i24
#ISCELL
  mstr_standard tap *
  page28_i25
#ISCELL
  mstr_standard tap *
  page28_i26
#ISCELL
  mstr_standard tap *
  page28_i27
#ISCELL
  mstr_standard tap *
  page28_i28
#ISCELL
  mstr_standard tap *
  page28_i29
#ISCELL
  mstr_standard offpage *
  page28_i3
#ISCELL
  mstr_standard tap *
  page28_i30
#ISCELL
  mstr_standard tap *
  page28_i32
#ISCELL
  mstr_standard tap *
  page28_i33
#ISCELL
  mstr_standard tap *
  page28_i34
#ISCELL
  mstr_standard tap *
  page28_i35
#ISCELL
  mstr_standard tap *
  page28_i36
#ISCELL
  mstr_standard tap *
  page28_i37
#ISCELL
  mstr_standard tap *
  page28_i38
#ISCELL
  mstr_standard tap *
  page28_i39
#ISCELL
  mstr_standard offpage *
  page28_i4
#ISCELL
  mstr_standard tap *
  page28_i40
#ISCELL
  mstr_standard tap *
  page28_i41
#ISCELL
  mstr_standard tap *
  page28_i42
#ISCELL
  mstr_standard tap *
  page28_i43
#ISCELL
  mstr_standard tap *
  page28_i44
#ISCELL
  mstr_standard tap *
  page28_i45
#ISCELL
  mstr_standard tap *
  page28_i46
#ISCELL
  mstr_standard tap *
  page28_i47
#ISCELL
  mstr_standard tap *
  page28_i48
#ISCELL
  mstr_standard tap *
  page28_i49
#ISCELL
  mstr_standard tap *
  page28_i5
#ISCELL
  mstr_standard tap *
  page28_i50
#ISCELL
  mstr_standard tap *
  page28_i51
#ISCELL
  mstr_standard tap *
  page28_i52
#ISCELL
  mstr_standard tap *
  page28_i53
#ISCELL
  mstr_standard tap *
  page28_i54
#ISCELL
  mstr_standard tap *
  page28_i55
#ISCELL
  mstr_standard tap *
  page28_i56
#ISCELL
  mstr_standard tap *
  page28_i57
#ISCELL
  mstr_standard tap *
  page28_i58
#ISCELL
  mstr_standard tap *
  page28_i59
#ISCELL
  mstr_standard tap *
  page28_i6
#ISCELL
  mstr_standard tap *
  page28_i60
#ISCELL
  mstr_standard tap *
  page28_i61
#ISCELL
  mstr_standard tap *
  page28_i62
#ISCELL
  mstr_standard tap *
  page28_i63
#ISCELL
  mstr_standard tap *
  page28_i64
#ISCELL
  mstr_standard tap *
  page28_i65
#ISCELL
  mstr_standard tap *
  page28_i66
#ISCELL
  mstr_standard tap *
  page28_i67
#ISCELL
  mstr_standard tap *
  page28_i68
#ISCELL
  mstr_standard tap *
  page28_i69
#ISCELL
  mstr_standard tap *
  page28_i7
#ISCELL
  mstr_standard tap *
  page28_i70
#ISCELL
  mstr_standard tap *
  page28_i71
#ISCELL
  mstr_standard tap *
  page28_i72
#ISCELL
  mstr_standard offpage *
  page28_i73
#ISCELL
  mstr_standard tap *
  page28_i74
#ISCELL
  mstr_standard tap *
  page28_i75
#ISCELL
  mstr_standard tap *
  page28_i76
#ISCELL
  mstr_standard tap *
  page28_i77
#ISCELL
  mstr_standard tap *
  page28_i78
#ISCELL
  mstr_standard tap *
  page28_i79
#ISCELL
  mstr_standard tap *
  page28_i8
#ISCELL
  mstr_standard tap *
  page28_i80
#ISCELL
  mstr_standard tap *
  page28_i81
#ISCELL
  mstr_standard tap *
  page28_i82
#ISCELL
  mstr_standard tap *
  page28_i83
#ISCELL
  mstr_standard tap *
  page28_i84
#ISCELL
  mstr_standard tap *
  page28_i85
#ISCELL
  mstr_standard tap *
  page28_i86
#ISCELL
  mstr_standard tap *
  page28_i87
#ISCELL
  mstr_standard tap *
  page28_i88
#ISCELL
  mstr_standard tap *
  page28_i89
#ISCELL
  mstr_standard tap *
  page28_i9
#ISCELL
  mstr_standard tap *
  page28_i90
#ISCELL
  mstr_standard tap *
  page28_i91
#ISCELL
  mstr_standard tap *
  page28_i92
#ISCELL
  mstr_standard tap *
  page28_i93
#ISCELL
  mstr_standard tap *
  page28_i94
#ISCELL
  mstr_standard tap *
  page28_i95
#ISCELL
  mstr_standard tap *
  page28_i96
#ISCELL
  mstr_standard tap *
  page28_i97
#ISCELL
  mstr_standard tap *
  page28_i98
#ISCELL
  mstr_standard tap *
  page28_i99
#ISCELL
  mstr_misc prelim *
  *
#ISCELL
  mstr_symbols design_note *
  *
#ISCELL
  mstr_symbols intel_corp_bpage *
  *
#ISCELL
  mstr_standard tap *
  page29_i10
#ISCELL
  mstr_standard tap *
  page29_i11
#ISCELL
  mstr_standard tap *
  page29_i12
#ISCELL
  mstr_standard tap *
  page29_i13
#ISCELL
  mstr_standard tap *
  page29_i14
#ISCELL
  mstr_standard tap *
  page29_i16
#ISCELL
  mstr_standard tap *
  page29_i17
#ISCELL
  mstr_standard tap *
  page29_i18
#ISCELL
  mstr_standard tap *
  page29_i19
#ISCELL
  mstr_standard tap *
  page29_i20
#ISCELL
  mstr_standard tap *
  page29_i21
#ISCELL
  mstr_standard tap *
  page29_i22
#ISCELL
  mstr_standard tap *
  page29_i23
#ISCELL
  mstr_standard offpage *
  page29_i25
#ISCELL
  mstr_standard offpage *
  page29_i26
#ISCELL
  mstr_standard offpage *
  page29_i27
#ISCELL
  mstr_standard offpage *
  page29_i28
#ISCELL
  mstr_standard offpage *
  page29_i29
#ISCELL
  mstr_standard offpage *
  page29_i31
#ISCELL
  mstr_standard offpage *
  page29_i35
#ISCELL
  mstr_standard offpage *
  page29_i36
#ISCELL
  mstr_standard offpage *
  page29_i40
#ISCELL
  mstr_standard offpage *
  page29_i41
#ISCELL
  mstr_standard offpage *
  page29_i42
#ISCELL
  mstr_standard offpage *
  page29_i43
#ISCELL
  mstr_standard offpage *
  page29_i44
#ISCELL
  mstr_standard offpage *
  page29_i45
#ISCELL
  mstr_standard offpage *
  page29_i46
#ISCELL
  mstr_standard offpage *
  page29_i47
#ISCELL
  mstr_standard offpage *
  page29_i48
#ISCELL
  mstr_standard offpage *
  page29_i49
#ISCELL
  mstr_standard offpage *
  page29_i5
#ISCELL
  mstr_standard offpage *
  page29_i50
#ISCELL
  mstr_standard offpage *
  page29_i51
#ISCELL
  mstr_standard offpage *
  page29_i52
#ISCELL
  mstr_standard offpage *
  page29_i53
#ISCELL
  mstr_standard offpage *
  page29_i54
#ISCELL
  mstr_standard offpage *
  page29_i58
#ISCELL
  mstr_standard offpage *
  page29_i6
#ISCELL
  mstr_symbols vcc_core *
  page29_i60
#CELL
  chpset_lib skx_ext_b *
  page29_i61
#ISCELL
  mstr_standard tap *
  page29_i7
#ISCELL
  mstr_standard tap *
  page29_i8
#ISCELL
  mstr_standard tap *
  page29_i9
#ISCELL
  mstr_misc prelim *
  *
#ISCELL
  mstr_symbols design_note *
  *
#ISCELL
  mstr_symbols intel_corp_bpage *
  *
#ISCELL
  mstr_standard tap *
  page30_i1
#ISCELL
  mstr_standard tap *
  page30_i10
#ISCELL
  mstr_standard tap *
  page30_i11
#ISCELL
  mstr_standard tap *
  page30_i12
#ISCELL
  mstr_standard tap *
  page30_i13
#ISCELL
  mstr_standard tap *
  page30_i14
#ISCELL
  mstr_standard tap *
  page30_i15
#ISCELL
  mstr_standard tap *
  page30_i16
#ISCELL
  mstr_standard tap *
  page30_i17
#ISCELL
  mstr_standard tap *
  page30_i18
#ISCELL
  mstr_standard tap *
  page30_i19
#ISCELL
  mstr_standard tap *
  page30_i2
#ISCELL
  mstr_standard tap *
  page30_i20
#ISCELL
  mstr_standard tap *
  page30_i21
#ISCELL
  mstr_standard tap *
  page30_i22
#ISCELL
  mstr_standard tap *
  page30_i24
#ISCELL
  mstr_standard tap *
  page30_i25
#ISCELL
  mstr_standard tap *
  page30_i26
#ISCELL
  mstr_standard tap *
  page30_i27
#ISCELL
  mstr_standard tap *
  page30_i28
#ISCELL
  mstr_standard tap *
  page30_i29
#ISCELL
  mstr_standard tap *
  page30_i3
#ISCELL
  mstr_standard tap *
  page30_i30
#ISCELL
  mstr_standard tap *
  page30_i31
#ISCELL
  mstr_standard tap *
  page30_i32
#ISCELL
  mstr_standard tap *
  page30_i33
#ISCELL
  mstr_standard tap *
  page30_i34
#ISCELL
  mstr_standard tap *
  page30_i35
#ISCELL
  mstr_standard tap *
  page30_i36
#ISCELL
  mstr_standard tap *
  page30_i37
#ISCELL
  mstr_standard tap *
  page30_i38
#ISCELL
  mstr_standard tap *
  page30_i39
#ISCELL
  mstr_standard tap *
  page30_i40
#ISCELL
  mstr_standard tap *
  page30_i41
#ISCELL
  mstr_standard tap *
  page30_i42
#ISCELL
  mstr_standard tap *
  page30_i43
#ISCELL
  mstr_standard tap *
  page30_i44
#ISCELL
  mstr_standard tap *
  page30_i45
#ISCELL
  mstr_standard tap *
  page30_i46
#ISCELL
  mstr_standard tap *
  page30_i47
#ISCELL
  mstr_standard tap *
  page30_i48
#ISCELL
  mstr_standard tap *
  page30_i49
#ISCELL
  mstr_standard tap *
  page30_i51
#ISCELL
  mstr_standard tap *
  page30_i52
#ISCELL
  mstr_standard tap *
  page30_i53
#ISCELL
  mstr_standard tap *
  page30_i54
#ISCELL
  mstr_standard tap *
  page30_i55
#ISCELL
  mstr_standard tap *
  page30_i56
#ISCELL
  mstr_standard tap *
  page30_i57
#ISCELL
  mstr_standard tap *
  page30_i58
#ISCELL
  mstr_standard tap *
  page30_i59
#ISCELL
  mstr_standard tap *
  page30_i6
#ISCELL
  mstr_standard tap *
  page30_i60
#ISCELL
  mstr_standard tap *
  page30_i61
#ISCELL
  mstr_standard tap *
  page30_i62
#ISCELL
  mstr_standard tap *
  page30_i64
#ISCELL
  mstr_standard tap *
  page30_i65
#ISCELL
  mstr_standard tap *
  page30_i66
#ISCELL
  mstr_standard tap *
  page30_i67
#ISCELL
  mstr_standard tap *
  page30_i7
#ISCELL
  mstr_standard offpage *
  page30_i70
#ISCELL
  mstr_standard offpage *
  page30_i71
#ISCELL
  mstr_standard offpage *
  page30_i74
#ISCELL
  mstr_standard offpage *
  page30_i75
#ISCELL
  mstr_standard tap *
  page30_i78
#ISCELL
  mstr_standard tap *
  page30_i79
#ISCELL
  mstr_standard tap *
  page30_i8
#ISCELL
  mstr_standard offpage *
  page30_i80
#ISCELL
  mstr_standard offpage *
  page30_i81
#ISCELL
  mstr_standard offpage *
  page30_i82
#ISCELL
  mstr_standard offpage *
  page30_i83
#CELL
  chpset_lib skx_ext_b *
  page30_i84
#ISCELL
  mstr_standard tap *
  page30_i9
#ISCELL
  mstr_misc prelim *
  *
#ISCELL
  mstr_symbols design_note *
  *
#ISCELL
  mstr_symbols intel_corp_bpage *
  *
#ISCELL
  mstr_standard tap *
  page31_i10
#ISCELL
  mstr_standard tap *
  page31_i100
#ISCELL
  mstr_standard tap *
  page31_i101
#ISCELL
  mstr_standard tap *
  page31_i102
#ISCELL
  mstr_standard tap *
  page31_i103
#ISCELL
  mstr_standard offpage *
  page31_i104
#ISCELL
  mstr_standard offpage *
  page31_i105
#CELL
  chpset_lib skx_ext_b *
  page31_i106
#ISCELL
  mstr_standard tap *
  page31_i11
#ISCELL
  mstr_standard tap *
  page31_i12
#ISCELL
  mstr_standard tap *
  page31_i13
#ISCELL
  mstr_standard tap *
  page31_i14
#ISCELL
  mstr_standard tap *
  page31_i15
#ISCELL
  mstr_standard tap *
  page31_i16
#ISCELL
  mstr_standard tap *
  page31_i17
#ISCELL
  mstr_standard tap *
  page31_i18
#ISCELL
  mstr_standard tap *
  page31_i19
#ISCELL
  mstr_standard tap *
  page31_i3
#ISCELL
  mstr_standard tap *
  page31_i36
#ISCELL
  mstr_standard tap *
  page31_i37
#ISCELL
  mstr_standard tap *
  page31_i38
#ISCELL
  mstr_standard tap *
  page31_i39
#ISCELL
  mstr_standard tap *
  page31_i4
#ISCELL
  mstr_standard tap *
  page31_i40
#ISCELL
  mstr_standard tap *
  page31_i41
#ISCELL
  mstr_standard tap *
  page31_i42
#ISCELL
  mstr_standard tap *
  page31_i43
#ISCELL
  mstr_standard tap *
  page31_i44
#ISCELL
  mstr_standard tap *
  page31_i45
#ISCELL
  mstr_standard tap *
  page31_i46
#ISCELL
  mstr_standard tap *
  page31_i47
#ISCELL
  mstr_standard tap *
  page31_i48
#ISCELL
  mstr_standard tap *
  page31_i49
#ISCELL
  mstr_standard tap *
  page31_i5
#ISCELL
  mstr_standard tap *
  page31_i50
#ISCELL
  mstr_standard tap *
  page31_i51
#ISCELL
  mstr_standard tap *
  page31_i6
#ISCELL
  mstr_standard tap *
  page31_i7
#ISCELL
  mstr_standard offpage *
  page31_i70
#ISCELL
  mstr_standard offpage *
  page31_i71
#ISCELL
  mstr_standard tap *
  page31_i72
#ISCELL
  mstr_standard tap *
  page31_i73
#ISCELL
  mstr_standard tap *
  page31_i74
#ISCELL
  mstr_standard tap *
  page31_i75
#ISCELL
  mstr_standard tap *
  page31_i76
#ISCELL
  mstr_standard tap *
  page31_i77
#ISCELL
  mstr_standard tap *
  page31_i78
#ISCELL
  mstr_standard tap *
  page31_i79
#ISCELL
  mstr_standard tap *
  page31_i80
#ISCELL
  mstr_standard tap *
  page31_i81
#ISCELL
  mstr_standard tap *
  page31_i82
#ISCELL
  mstr_standard tap *
  page31_i83
#ISCELL
  mstr_standard tap *
  page31_i84
#ISCELL
  mstr_standard tap *
  page31_i85
#ISCELL
  mstr_standard tap *
  page31_i86
#ISCELL
  mstr_standard tap *
  page31_i87
#ISCELL
  mstr_standard tap *
  page31_i88
#ISCELL
  mstr_standard tap *
  page31_i89
#ISCELL
  mstr_standard tap *
  page31_i9
#ISCELL
  mstr_standard tap *
  page31_i90
#ISCELL
  mstr_standard tap *
  page31_i91
#ISCELL
  mstr_standard tap *
  page31_i92
#ISCELL
  mstr_standard tap *
  page31_i93
#ISCELL
  mstr_standard tap *
  page31_i94
#ISCELL
  mstr_standard tap *
  page31_i95
#ISCELL
  mstr_standard tap *
  page31_i96
#ISCELL
  mstr_standard tap *
  page31_i97
#ISCELL
  mstr_standard tap *
  page31_i98
#ISCELL
  mstr_standard tap *
  page31_i99
#ISCELL
  mstr_misc prelim *
  *
#ISCELL
  mstr_symbols design_note *
  *
#ISCELL
  mstr_symbols intel_corp_bpage *
  *
#ISCELL
  mstr_standard offpage *
  page32_i1
#ISCELL
  mstr_standard tap *
  page32_i15
#ISCELL
  mstr_standard offpage *
  page32_i2
#ISCELL
  mstr_standard tap *
  page32_i20
#ISCELL
  mstr_standard tap *
  page32_i21
#ISCELL
  mstr_standard tap *
  page32_i22
#ISCELL
  mstr_standard tap *
  page32_i23
#ISCELL
  mstr_standard tap *
  page32_i24
#ISCELL
  mstr_standard tap *
  page32_i25
#ISCELL
  mstr_standard tap *
  page32_i26
#ISCELL
  mstr_standard tap *
  page32_i27
#ISCELL
  mstr_standard tap *
  page32_i28
#ISCELL
  mstr_standard tap *
  page32_i29
#ISCELL
  mstr_standard tap *
  page32_i3
#ISCELL
  mstr_standard tap *
  page32_i30
#ISCELL
  mstr_standard tap *
  page32_i31
#ISCELL
  mstr_standard tap *
  page32_i32
#ISCELL
  mstr_standard tap *
  page32_i33
#ISCELL
  mstr_standard tap *
  page32_i34
#ISCELL
  mstr_standard tap *
  page32_i35
#ISCELL
  mstr_standard tap *
  page32_i36
#ISCELL
  mstr_standard tap *
  page32_i37
#ISCELL
  mstr_standard tap *
  page32_i38
#ISCELL
  mstr_standard tap *
  page32_i39
#ISCELL
  mstr_standard tap *
  page32_i4
#ISCELL
  mstr_standard tap *
  page32_i40
#ISCELL
  mstr_standard tap *
  page32_i41
#ISCELL
  mstr_standard tap *
  page32_i42
#ISCELL
  mstr_standard tap *
  page32_i43
#ISCELL
  mstr_standard tap *
  page32_i44
#ISCELL
  mstr_standard tap *
  page32_i45
#ISCELL
  mstr_standard tap *
  page32_i46
#ISCELL
  mstr_standard tap *
  page32_i47
#ISCELL
  mstr_standard tap *
  page32_i48
#ISCELL
  mstr_standard tap *
  page32_i49
#ISCELL
  mstr_standard tap *
  page32_i5
#ISCELL
  mstr_standard tap *
  page32_i50
#ISCELL
  mstr_standard tap *
  page32_i51
#ISCELL
  mstr_standard tap *
  page32_i52
#ISCELL
  mstr_standard tap *
  page32_i53
#ISCELL
  mstr_standard tap *
  page32_i54
#ISCELL
  mstr_standard tap *
  page32_i55
#ISCELL
  mstr_standard tap *
  page32_i56
#ISCELL
  mstr_standard tap *
  page32_i57
#ISCELL
  mstr_standard tap *
  page32_i58
#ISCELL
  mstr_standard tap *
  page32_i59
#ISCELL
  mstr_standard tap *
  page32_i6
#ISCELL
  mstr_standard tap *
  page32_i60
#ISCELL
  mstr_standard tap *
  page32_i61
#ISCELL
  mstr_standard tap *
  page32_i62
#ISCELL
  mstr_standard tap *
  page32_i63
#ISCELL
  mstr_standard tap *
  page32_i64
#ISCELL
  mstr_standard tap *
  page32_i65
#ISCELL
  mstr_standard tap *
  page32_i66
#ISCELL
  mstr_standard tap *
  page32_i67
#ISCELL
  mstr_standard offpage *
  page32_i68
#ISCELL
  mstr_standard offpage *
  page32_i69
#ISCELL
  mstr_standard tap *
  page32_i7
#ISCELL
  mstr_standard tap *
  page32_i8
#ISCELL
  mstr_standard tap *
  page32_i81
#ISCELL
  mstr_standard tap *
  page32_i82
#ISCELL
  mstr_standard tap *
  page32_i83
#ISCELL
  mstr_standard tap *
  page32_i84
#ISCELL
  mstr_standard tap *
  page32_i85
#ISCELL
  mstr_standard tap *
  page32_i86
#ISCELL
  mstr_standard tap *
  page32_i87
#ISCELL
  mstr_standard tap *
  page32_i88
#CELL
  chpset_lib skx_ext_b *
  page32_i89
#ISCELL
  mstr_standard tap *
  page32_i9
#ISCELL
  mstr_misc prelim *
  *
#ISCELL
  mstr_symbols design_note *
  *
#ISCELL
  mstr_symbols intel_corp_bpage *
  *
#ISCELL
  mstr_standard offpage *
  page33_i1
#ISCELL
  mstr_standard tap *
  page33_i10
#ISCELL
  mstr_standard tap *
  page33_i11
#ISCELL
  mstr_standard tap *
  page33_i13
#ISCELL
  mstr_standard tap *
  page33_i14
#ISCELL
  mstr_standard tap *
  page33_i15
#ISCELL
  mstr_standard tap *
  page33_i16
#ISCELL
  mstr_standard tap *
  page33_i17
#ISCELL
  mstr_standard tap *
  page33_i18
#ISCELL
  mstr_standard tap *
  page33_i19
#ISCELL
  mstr_standard offpage *
  page33_i2
#ISCELL
  mstr_standard tap *
  page33_i20
#ISCELL
  mstr_standard tap *
  page33_i21
#ISCELL
  mstr_standard tap *
  page33_i22
#ISCELL
  mstr_standard tap *
  page33_i23
#ISCELL
  mstr_standard tap *
  page33_i24
#ISCELL
  mstr_standard tap *
  page33_i25
#ISCELL
  mstr_standard tap *
  page33_i26
#ISCELL
  mstr_standard tap *
  page33_i27
#ISCELL
  mstr_standard tap *
  page33_i28
#ISCELL
  mstr_standard tap *
  page33_i29
#ISCELL
  mstr_standard tap *
  page33_i3
#ISCELL
  mstr_standard tap *
  page33_i30
#ISCELL
  mstr_standard tap *
  page33_i31
#ISCELL
  mstr_standard tap *
  page33_i32
#ISCELL
  mstr_standard tap *
  page33_i33
#ISCELL
  mstr_standard tap *
  page33_i34
#ISCELL
  mstr_standard tap *
  page33_i35
#ISCELL
  mstr_standard tap *
  page33_i36
#ISCELL
  mstr_standard tap *
  page33_i37
#ISCELL
  mstr_standard tap *
  page33_i38
#ISCELL
  mstr_standard tap *
  page33_i39
#ISCELL
  mstr_standard tap *
  page33_i4
#ISCELL
  mstr_standard tap *
  page33_i40
#ISCELL
  mstr_standard tap *
  page33_i41
#ISCELL
  mstr_standard tap *
  page33_i42
#ISCELL
  mstr_standard tap *
  page33_i43
#ISCELL
  mstr_standard tap *
  page33_i44
#ISCELL
  mstr_standard tap *
  page33_i45
#ISCELL
  mstr_standard tap *
  page33_i46
#ISCELL
  mstr_standard tap *
  page33_i47
#ISCELL
  mstr_standard tap *
  page33_i48
#ISCELL
  mstr_standard tap *
  page33_i49
#ISCELL
  mstr_standard tap *
  page33_i5
#ISCELL
  mstr_standard tap *
  page33_i50
#ISCELL
  mstr_standard tap *
  page33_i51
#ISCELL
  mstr_standard tap *
  page33_i52
#ISCELL
  mstr_standard tap *
  page33_i53
#ISCELL
  mstr_standard tap *
  page33_i54
#ISCELL
  mstr_standard tap *
  page33_i55
#ISCELL
  mstr_standard tap *
  page33_i56
#ISCELL
  mstr_standard tap *
  page33_i57
#ISCELL
  mstr_standard tap *
  page33_i58
#ISCELL
  mstr_standard tap *
  page33_i59
#ISCELL
  mstr_standard tap *
  page33_i6
#ISCELL
  mstr_standard tap *
  page33_i60
#ISCELL
  mstr_standard tap *
  page33_i61
#ISCELL
  mstr_standard tap *
  page33_i62
#ISCELL
  mstr_standard tap *
  page33_i63
#ISCELL
  mstr_standard tap *
  page33_i64
#ISCELL
  mstr_standard tap *
  page33_i65
#ISCELL
  mstr_standard tap *
  page33_i66
#ISCELL
  mstr_standard tap *
  page33_i67
#ISCELL
  mstr_standard tap *
  page33_i68
#ISCELL
  mstr_standard tap *
  page33_i69
#ISCELL
  mstr_standard tap *
  page33_i7
#ISCELL
  mstr_standard tap *
  page33_i70
#ISCELL
  mstr_standard tap *
  page33_i71
#ISCELL
  mstr_standard tap *
  page33_i72
#ISCELL
  mstr_standard tap *
  page33_i73
#ISCELL
  mstr_standard tap *
  page33_i74
#ISCELL
  mstr_standard tap *
  page33_i75
#ISCELL
  mstr_standard tap *
  page33_i76
#ISCELL
  mstr_standard tap *
  page33_i77
#ISCELL
  mstr_standard tap *
  page33_i78
#ISCELL
  mstr_standard tap *
  page33_i79
#ISCELL
  mstr_standard tap *
  page33_i8
#ISCELL
  mstr_standard tap *
  page33_i80
#ISCELL
  mstr_standard tap *
  page33_i81
#ISCELL
  mstr_standard tap *
  page33_i82
#ISCELL
  mstr_standard tap *
  page33_i83
#ISCELL
  mstr_standard offpage *
  page33_i84
#ISCELL
  mstr_standard offpage *
  page33_i85
#CELL
  chpset_lib skx_ext_b *
  page33_i86
#ISCELL
  mstr_standard tap *
  page33_i9
#ISCELL
  mstr_misc prelim *
  *
#ISCELL
  mstr_symbols design_note *
  *
#ISCELL
  mstr_symbols intel_corp_bpage *
  *
#ISCELL
  mstr_standard offpage *
  page34_i1
#ISCELL
  mstr_standard tap *
  page34_i10
#ISCELL
  mstr_standard tap *
  page34_i11
#ISCELL
  mstr_standard tap *
  page34_i12
#ISCELL
  mstr_standard tap *
  page34_i13
#ISCELL
  mstr_standard tap *
  page34_i14
#ISCELL
  mstr_standard tap *
  page34_i15
#ISCELL
  mstr_standard tap *
  page34_i16
#ISCELL
  mstr_standard tap *
  page34_i17
#ISCELL
  mstr_standard tap *
  page34_i18
#ISCELL
  mstr_standard tap *
  page34_i19
#ISCELL
  mstr_standard offpage *
  page34_i2
#ISCELL
  mstr_standard tap *
  page34_i20
#ISCELL
  mstr_standard tap *
  page34_i21
#ISCELL
  mstr_standard tap *
  page34_i22
#ISCELL
  mstr_standard tap *
  page34_i23
#ISCELL
  mstr_standard tap *
  page34_i24
#ISCELL
  mstr_standard tap *
  page34_i25
#ISCELL
  mstr_standard tap *
  page34_i26
#ISCELL
  mstr_standard tap *
  page34_i27
#ISCELL
  mstr_standard tap *
  page34_i28
#ISCELL
  mstr_standard tap *
  page34_i29
#ISCELL
  mstr_standard tap *
  page34_i3
#ISCELL
  mstr_standard tap *
  page34_i30
#ISCELL
  mstr_standard tap *
  page34_i31
#ISCELL
  mstr_standard tap *
  page34_i32
#ISCELL
  mstr_standard tap *
  page34_i33
#ISCELL
  mstr_standard tap *
  page34_i34
#ISCELL
  mstr_standard tap *
  page34_i35
#ISCELL
  mstr_standard tap *
  page34_i36
#ISCELL
  mstr_standard tap *
  page34_i37
#ISCELL
  mstr_standard tap *
  page34_i38
#ISCELL
  mstr_standard tap *
  page34_i39
#ISCELL
  mstr_standard tap *
  page34_i4
#ISCELL
  mstr_standard tap *
  page34_i40
#ISCELL
  mstr_standard tap *
  page34_i41
#ISCELL
  mstr_standard tap *
  page34_i42
#ISCELL
  mstr_standard tap *
  page34_i43
#ISCELL
  mstr_standard tap *
  page34_i44
#ISCELL
  mstr_standard tap *
  page34_i45
#ISCELL
  mstr_standard tap *
  page34_i46
#ISCELL
  mstr_standard tap *
  page34_i47
#ISCELL
  mstr_standard tap *
  page34_i48
#ISCELL
  mstr_standard tap *
  page34_i49
#ISCELL
  mstr_standard tap *
  page34_i5
#ISCELL
  mstr_standard tap *
  page34_i50
#ISCELL
  mstr_standard tap *
  page34_i51
#ISCELL
  mstr_standard tap *
  page34_i52
#ISCELL
  mstr_standard tap *
  page34_i53
#ISCELL
  mstr_standard tap *
  page34_i54
#ISCELL
  mstr_standard tap *
  page34_i55
#ISCELL
  mstr_standard tap *
  page34_i56
#ISCELL
  mstr_standard tap *
  page34_i57
#ISCELL
  mstr_standard tap *
  page34_i58
#ISCELL
  mstr_standard tap *
  page34_i59
#ISCELL
  mstr_standard tap *
  page34_i6
#ISCELL
  mstr_standard tap *
  page34_i60
#ISCELL
  mstr_standard tap *
  page34_i61
#ISCELL
  mstr_standard tap *
  page34_i62
#ISCELL
  mstr_standard tap *
  page34_i63
#ISCELL
  mstr_standard tap *
  page34_i64
#ISCELL
  mstr_standard tap *
  page34_i65
#ISCELL
  mstr_standard tap *
  page34_i66
#ISCELL
  mstr_standard tap *
  page34_i67
#ISCELL
  mstr_standard tap *
  page34_i68
#ISCELL
  mstr_standard tap *
  page34_i69
#ISCELL
  mstr_standard tap *
  page34_i7
#ISCELL
  mstr_standard tap *
  page34_i70
#ISCELL
  mstr_standard tap *
  page34_i71
#ISCELL
  mstr_standard tap *
  page34_i72
#ISCELL
  mstr_standard tap *
  page34_i73
#ISCELL
  mstr_standard tap *
  page34_i74
#ISCELL
  mstr_standard tap *
  page34_i75
#ISCELL
  mstr_standard tap *
  page34_i76
#ISCELL
  mstr_standard tap *
  page34_i77
#ISCELL
  mstr_standard tap *
  page34_i78
#ISCELL
  mstr_standard tap *
  page34_i79
#ISCELL
  mstr_standard tap *
  page34_i80
#ISCELL
  mstr_standard tap *
  page34_i81
#ISCELL
  mstr_standard tap *
  page34_i82
#ISCELL
  mstr_standard tap *
  page34_i83
#ISCELL
  mstr_standard offpage *
  page34_i84
#ISCELL
  mstr_standard offpage *
  page34_i85
#CELL
  chpset_lib skx_ext_b *
  page34_i86
#ISCELL
  mstr_standard tap *
  page34_i9
#ISCELL
  mstr_symbols design_note *
  *
#ISCELL
  mstr_symbols intel_corp_bpage *
  *
#ISCELL
  mstr_symbols gnd *
  page35_i2
#CELL
  chpset_lib skx_ext_b *
  page35_i3
#ISCELL
  mstr_symbols design_note *
  *
#ISCELL
  mstr_symbols intel_corp_bpage *
  *
#ISCELL
  mstr_symbols vcc_core *
  page36_i12
#ISCELL
  mstr_symbols vcc_core *
  page36_i13
#ISCELL
  mstr_symbols vcc_core *
  page36_i14
#CELL
  chpset_lib skx_ext_b *
  page36_i15
#CELL
  chpset_lib skx_ext_b *
  page36_i16
#ISCELL
  mstr_symbols vcc_core *
  page36_i17
#ISCELL
  mstr_standard offpage *
  page36_i5
#ISCELL
  mstr_standard offpage *
  page36_i8
#ISCELL
  mstr_misc dns *
  *
#ISCELL
  mstr_misc prelim *
  *
#ISCELL
  mstr_symbols design_note *
  *
#ISCELL
  mstr_symbols intel_corp_bpage *
  *
#ISCELL
  mstr_symbols pvccin_cpu0 *
  page37_i295
#ISCELL
  mstr_symbols pvccin_cpu0 *
  page37_i296
#ISCELL
  mstr_standard offpage *
  page37_i298
#ISCELL
  mstr_standard offpage *
  page37_i299
#ISCELL
  mstr_symbols pvccin_cpu0 *
  page37_i300
#ISCELL
  mstr_symbols pvccin_cpu0 *
  page37_i301
#ISCELL
  mstr_symbols gnd *
  page37_i302
#CELL
  mstr_discrete res *
  page37_i303
#ISCELL
  mstr_symbols pvccin_cpu0 *
  page37_i305
#CELL
  mstr_discrete res *
  page37_i309
#CELL
  chpset_lib skx_ext_b *
  page37_i310
#CELL
  chpset_lib skx_ext_b *
  page37_i311
#CELL
  mstr_discrete res *
  page37_i312
#ISCELL
  mstr_symbols pvccio_cpu0 *
  page37_i313
#ISCELL
  mstr_symbols design_note *
  *
#ISCELL
  mstr_symbols intel_corp_bpage *
  *
#ISCELL
  mstr_symbols pvddq_abc *
  page38_i11
#ISCELL
  mstr_symbols pvddq_def *
  page38_i12
#ISCELL
  mstr_symbols pvccio_cpu0 *
  page38_i14
#ISCELL
  mstr_symbols gnd *
  page38_i16
#ISCELL
  mstr_symbols pvccio_cpu0 *
  page38_i17
#CELL
  mstr_discrete cap *
  page38_i19
#ISCELL
  mstr_symbols pvsa_cpu0 *
  page38_i24
#ISCELL
  mstr_symbols vcc_core *
  page38_i25
#ISCELL
  mstr_symbols vcc_core *
  page38_i26
#ISCELL
  mstr_symbols pvpp_abc *
  page38_i31
#CELL
  chpset_lib skx_ext_b *
  page38_i33
#CELL
  chpset_lib skx_ext_b *
  page38_i34
#ISCELL
  mstr_symbols vcc_core *
  page38_i35
#ISCELL
  mstr_symbols p3v3_stby *
  page38_i36
#ISCELL
  mstr_misc prelim *
  *
#ISCELL
  mstr_symbols design_note *
  *
#ISCELL
  mstr_symbols intel_corp_bpage *
  *
#ISCELL
  mstr_standard offpage *
  page39_i122
#ISCELL
  mstr_symbols vcc_core *
  page39_i123
#ISCELL
  mstr_symbols vcc_core *
  page39_i125
#ISCELL
  mstr_symbols vcc_core *
  page39_i126
#CELL
  chpset_lib skx_ext_b *
  page39_i127
#ISCELL
  mstr_symbols pvccio_cpu0 *
  page39_i23
#ISCELL
  mstr_standard offpage *
  page39_i33
#ISCELL
  mstr_standard offpage *
  page39_i34
#ISCELL
  mstr_standard offpage *
  page39_i35
#ISCELL
  mstr_standard offpage *
  page39_i36
#ISCELL
  mstr_standard offpage *
  page39_i37
#ISCELL
  mstr_standard offpage *
  page39_i38
#ISCELL
  mstr_standard offpage *
  page39_i39
#ISCELL
  mstr_standard offpage *
  page39_i40
#ISCELL
  mstr_misc prelim *
  *
#ISCELL
  mstr_symbols design_note *
  *
#ISCELL
  mstr_symbols intel_corp_bpage *
  *
#ISCELL
  mstr_symbols gnd *
  page40_i11
#ISCELL
  mstr_symbols gnd *
  page40_i13
#ISCELL
  mstr_symbols gnd *
  page40_i14
#CELL
  chpset_lib skx_ext_b *
  page40_i20
#CELL
  chpset_lib skx_ext_b *
  page40_i21
#CELL
  chpset_lib skx_ext_b *
  page40_i22
#CELL
  chpset_lib skx_ext_b *
  page40_i23
#ISCELL
  mstr_symbols gnd *
  page40_i3
#ISCELL
  mstr_symbols gnd *
  page40_i4
#ISCELL
  mstr_symbols gnd *
  page40_i5
#ISCELL
  mstr_symbols gnd *
  page40_i6
#ISCELL
  mstr_symbols gnd *
  page40_i9
#ISCELL
  mstr_symbols design_note *
  *
#ISCELL
  mstr_symbols intel_corp_bpage *
  *
#ISCELL
  mstr_symbols gnd *
  page41_i275
#ISCELL
  mstr_symbols gnd *
  page41_i276
#ISCELL
  mstr_symbols gnd *
  page41_i277
#ISCELL
  mstr_symbols gnd *
  page41_i278
#ISCELL
  mstr_symbols gnd *
  page41_i279
#ISCELL
  mstr_symbols gnd *
  page41_i280
#ISCELL
  mstr_symbols gnd *
  page41_i281
#ISCELL
  mstr_symbols gnd *
  page41_i282
#CELL
  chpset_lib skx_ext_b *
  page41_i283
#CELL
  chpset_lib skx_ext_b *
  page41_i284
#CELL
  chpset_lib skx_ext_b *
  page41_i285
#CELL
  chpset_lib skx_ext_b *
  page41_i286
#ISCELL
  mstr_symbols design_note *
  *
#ISCELL
  mstr_symbols intel_corp_bpage *
  *
#CELL
  mstr_discrete cap *
  page42_i10
#CELL
  dev_discrete cap_a *
  page42_i100
#ISCELL
  mstr_symbols gnd *
  page42_i101
#CELL
  dev_discrete cap_a *
  page42_i102
#CELL
  dev_discrete cap_a *
  page42_i103
#CELL
  dev_discrete cap_a *
  page42_i104
#ISCELL
  mstr_symbols gnd *
  page42_i105
#CELL
  dev_discrete cap_a *
  page42_i106
#CELL
  dev_discrete cap_a *
  page42_i107
#CELL
  mstr_discrete cap *
  page42_i108
#CELL
  dev_discrete cap_a *
  page42_i109
#ISCELL
  mstr_symbols gnd *
  page42_i110
#CELL
  dev_discrete cap_a *
  page42_i111
#CELL
  dev_discrete cap_a *
  page42_i114
#CELL
  dev_discrete cap_a *
  page42_i115
#ISCELL
  mstr_symbols pvccin_cpu0 *
  page42_i116
#CELL
  dev_discrete cap_a *
  page42_i117
#CELL
  dev_discrete cap_a *
  page42_i118
#ISCELL
  mstr_symbols pvccin_cpu0 *
  page42_i119
#CELL
  mstr_discrete cap *
  page42_i12
#ISCELL
  mstr_symbols pvccin_cpu0 *
  page42_i121
#ISCELL
  mstr_symbols gnd *
  page42_i122
#CELL
  dev_discrete cap_a *
  page42_i123
#ISCELL
  mstr_symbols gnd *
  page42_i124
#CELL
  dev_discrete cap_a *
  page42_i125
#CELL
  dev_discrete cap_a *
  page42_i128
#CELL
  dev_discrete cap_a *
  page42_i131
#CELL
  dev_discrete cap_a *
  page42_i132
#ISCELL
  mstr_symbols gnd *
  page42_i133
#CELL
  dev_discrete cap_a *
  page42_i134
#CELL
  dev_discrete cap_a *
  page42_i135
#ISCELL
  mstr_symbols pvccin_cpu0 *
  page42_i137
#CELL
  dev_discrete cap_a *
  page42_i138
#ISCELL
  mstr_symbols pvccin_cpu0 *
  page42_i139
#CELL
  dev_discrete cap_a *
  page42_i140
#ISCELL
  mstr_symbols pvccin_cpu0 *
  page42_i141
#CELL
  dev_discrete cap_a *
  page42_i142
#ISCELL
  mstr_symbols vcc_core *
  page42_i144
#CELL
  dev_discrete cap_a *
  page42_i145
#CELL
  dev_discrete cap_a *
  page42_i147
#CELL
  dev_discrete cap_a *
  page42_i151
#CELL
  dev_discrete cap_a *
  page42_i152
#CELL
  dev_discrete cap_a *
  page42_i153
#CELL
  dev_discrete cap_a *
  page42_i154
#CELL
  dev_discrete cap_a *
  page42_i155
#CELL
  dev_discrete cap_a *
  page42_i156
#ISCELL
  mstr_symbols vcc_core *
  page42_i159
#ISCELL
  mstr_symbols pvccio_cpu0 *
  page42_i16
#CELL
  dev_discrete cap_a *
  page42_i164
#CELL
  mstr_discrete cap *
  page42_i17
#CELL
  dev_discrete cap_a *
  page42_i173
#CELL
  dev_discrete cap_a *
  page42_i174
#CELL
  dev_discrete cap_a *
  page42_i175
#CELL
  dev_discrete cap_a *
  page42_i176
#CELL
  dev_discrete cap_a *
  page42_i178
#CELL
  dev_discrete cap_a *
  page42_i179
#CELL
  dev_discrete cap_a *
  page42_i180
#ISCELL
  mstr_symbols vcc_core *
  page42_i181
#CELL
  mstr_discrete cap *
  page42_i187
#CELL
  mstr_discrete cap *
  page42_i188
#CELL
  mstr_discrete cap *
  page42_i190
#ISCELL
  mstr_symbols pvccin_cpu0 *
  page42_i196
#ISCELL
  mstr_symbols gnd *
  page42_i20
#ISCELL
  mstr_symbols pvccin_cpu0 *
  page42_i203
#ISCELL
  mstr_symbols gnd *
  page42_i206
#ISCELL
  mstr_symbols pvccin_cpu0 *
  page42_i208
#ISCELL
  mstr_symbols gnd *
  page42_i21
#ISCELL
  mstr_symbols gnd *
  page42_i210
#CELL
  mstr_discrete cap *
  page42_i211
#ISCELL
  mstr_symbols gnd *
  page42_i212
#ISCELL
  mstr_symbols pvccin_cpu0 *
  page42_i213
#CELL
  mstr_discrete cap *
  page42_i214
#CELL
  mstr_discrete cap *
  page42_i215
#ISCELL
  mstr_symbols vcc_core *
  page42_i216
#CELL
  dev_discrete cap_a *
  page42_i217
#CELL
  dev_discrete cap_a *
  page42_i218
#ISCELL
  mstr_symbols gnd *
  page42_i219
#CELL
  mstr_discrete cap *
  page42_i220
#CELL
  mstr_discrete cap *
  page42_i221
#CELL
  mstr_discrete cap *
  page42_i222
#CELL
  mstr_discrete cap *
  page42_i223
#CELL
  mstr_discrete cap *
  page42_i224
#CELL
  mstr_discrete cap *
  page42_i225
#CELL
  mstr_discrete cap *
  page42_i226
#CELL
  mstr_discrete cap *
  page42_i227
#CELL
  mstr_discrete cap *
  page42_i228
#CELL
  mstr_discrete cap *
  page42_i229
#CELL
  mstr_discrete cap *
  page42_i230
#CELL
  mstr_discrete cap *
  page42_i231
#CELL
  mstr_discrete cap *
  page42_i232
#CELL
  mstr_discrete cap *
  page42_i233
#CELL
  mstr_discrete cap *
  page42_i234
#CELL
  mstr_discrete cap *
  page42_i235
#CELL
  mstr_discrete cap *
  page42_i236
#ISCELL
  mstr_symbols gnd *
  page42_i237
#ISCELL
  mstr_symbols pvsa_cpu0 *
  page42_i24
#CELL
  mstr_discrete cap *
  page42_i25
#CELL
  mstr_discrete cap *
  page42_i28
#ISCELL
  mstr_symbols gnd *
  page42_i32
#CELL
  mstr_discrete cap *
  page42_i33
#ISCELL
  mstr_symbols gnd *
  page42_i35
#CELL
  mstr_discrete cap *
  page42_i37
#CELL
  mstr_discrete cap *
  page42_i41
#ISCELL
  mstr_symbols pvccin_cpu0 *
  page42_i43
#CELL
  mstr_discrete cap *
  page42_i44
#ISCELL
  mstr_symbols pvccin_cpu0 *
  page42_i45
#ISCELL
  mstr_symbols gnd *
  page42_i46
#ISCELL
  mstr_symbols gnd *
  page42_i48
#ISCELL
  mstr_symbols gnd *
  page42_i5
#CELL
  mstr_discrete cap *
  page42_i50
#CELL
  mstr_discrete cap *
  page42_i51
#CELL
  mstr_discrete cap *
  page42_i53
#CELL
  mstr_discrete cap *
  page42_i54
#CELL
  mstr_discrete cap *
  page42_i55
#CELL
  mstr_discrete cap *
  page42_i56
#CELL
  mstr_discrete cap *
  page42_i57
#ISCELL
  mstr_symbols gnd *
  page42_i58
#ISCELL
  mstr_symbols pvccin_cpu0 *
  page42_i62
#CELL
  mstr_discrete cap *
  page42_i63
#ISCELL
  mstr_symbols pvccin_cpu0 *
  page42_i64
#CELL
  mstr_discrete cap *
  page42_i65
#CELL
  dev_discrete cap_a *
  page42_i68
#CELL
  dev_discrete cap_a *
  page42_i69
#CELL
  dev_discrete cap_a *
  page42_i70
#ISCELL
  mstr_symbols gnd *
  page42_i71
#CELL
  dev_discrete cap_a *
  page42_i72
#ISCELL
  mstr_symbols gnd *
  page42_i73
#CELL
  dev_discrete cap_a *
  page42_i74
#CELL
  dev_discrete cap_a *
  page42_i75
#CELL
  dev_discrete cap_a *
  page42_i77
#ISCELL
  mstr_symbols pvccio_cpu0 *
  page42_i79
#CELL
  dev_discrete cap_a *
  page42_i80
#CELL
  dev_discrete cap_a *
  page42_i81
#CELL
  dev_discrete cap_a *
  page42_i83
#CELL
  dev_discrete cap_a *
  page42_i88
#CELL
  dev_discrete cap_a *
  page42_i89
#CELL
  dev_discrete cap_a *
  page42_i90
#CELL
  mstr_discrete cap *
  page42_i91
#ISCELL
  mstr_symbols gnd *
  page42_i92
#CELL
  mstr_discrete cap *
  page42_i93
#CELL
  mstr_discrete cap *
  page42_i94
#CELL
  dev_discrete cap_a *
  page42_i98
#ISCELL
  mstr_symbols pvsa_cpu0 *
  page42_i99
#ISCELL
  mstr_symbols bom_note *
  *
#ISCELL
  mstr_symbols intel_corp_bpage *
  *
#CELL
  mstr_sconn sconn288_h44441004 *
  page43_i1
#ISCELL
  mstr_standard tap *
  page43_i127
#ISCELL
  mstr_standard tap *
  page43_i128
#ISCELL
  mstr_standard tap *
  page43_i129
#ISCELL
  mstr_standard tap *
  page43_i130
#ISCELL
  mstr_standard tap *
  page43_i131
#ISCELL
  mstr_standard tap *
  page43_i132
#ISCELL
  mstr_standard tap *
  page43_i133
#ISCELL
  mstr_standard tap *
  page43_i134
#ISCELL
  mstr_standard tap *
  page43_i135
#ISCELL
  mstr_standard tap *
  page43_i136
#ISCELL
  mstr_standard tap *
  page43_i137
#ISCELL
  mstr_standard tap *
  page43_i138
#ISCELL
  mstr_standard tap *
  page43_i139
#ISCELL
  mstr_standard tap *
  page43_i140
#ISCELL
  mstr_standard tap *
  page43_i141
#ISCELL
  mstr_standard tap *
  page43_i142
#ISCELL
  mstr_standard tap *
  page43_i143
#ISCELL
  mstr_standard tap *
  page43_i144
#ISCELL
  mstr_standard tap *
  page43_i145
#ISCELL
  mstr_standard tap *
  page43_i146
#ISCELL
  mstr_standard tap *
  page43_i147
#ISCELL
  mstr_standard tap *
  page43_i148
#ISCELL
  mstr_standard tap *
  page43_i149
#ISCELL
  mstr_standard tap *
  page43_i150
#ISCELL
  mstr_standard tap *
  page43_i151
#ISCELL
  mstr_standard tap *
  page43_i152
#ISCELL
  mstr_standard tap *
  page43_i153
#ISCELL
  mstr_standard tap *
  page43_i154
#ISCELL
  mstr_standard tap *
  page43_i155
#ISCELL
  mstr_standard tap *
  page43_i156
#ISCELL
  mstr_standard tap *
  page43_i157
#ISCELL
  mstr_standard tap *
  page43_i158
#ISCELL
  mstr_standard tap *
  page43_i159
#ISCELL
  mstr_standard tap *
  page43_i160
#ISCELL
  mstr_standard tap *
  page43_i161
#ISCELL
  mstr_standard tap *
  page43_i162
#ISCELL
  mstr_standard tap *
  page43_i163
#ISCELL
  mstr_standard tap *
  page43_i164
#ISCELL
  mstr_standard tap *
  page43_i165
#ISCELL
  mstr_standard tap *
  page43_i166
#ISCELL
  mstr_standard tap *
  page43_i167
#ISCELL
  mstr_standard tap *
  page43_i168
#ISCELL
  mstr_standard tap *
  page43_i169
#ISCELL
  mstr_standard tap *
  page43_i170
#ISCELL
  mstr_standard tap *
  page43_i171
#ISCELL
  mstr_standard tap *
  page43_i172
#ISCELL
  mstr_standard tap *
  page43_i173
#ISCELL
  mstr_standard tap *
  page43_i174
#ISCELL
  mstr_standard tap *
  page43_i175
#ISCELL
  mstr_standard tap *
  page43_i176
#ISCELL
  mstr_standard tap *
  page43_i177
#ISCELL
  mstr_standard tap *
  page43_i178
#ISCELL
  mstr_standard tap *
  page43_i179
#ISCELL
  mstr_standard tap *
  page43_i180
#ISCELL
  mstr_standard tap *
  page43_i181
#ISCELL
  mstr_standard tap *
  page43_i182
#ISCELL
  mstr_standard tap *
  page43_i183
#ISCELL
  mstr_standard tap *
  page43_i184
#ISCELL
  mstr_standard tap *
  page43_i185
#ISCELL
  mstr_standard tap *
  page43_i186
#ISCELL
  mstr_standard tap *
  page43_i187
#ISCELL
  mstr_standard tap *
  page43_i188
#ISCELL
  mstr_standard tap *
  page43_i189
#ISCELL
  mstr_standard tap *
  page43_i190
#ISCELL
  mstr_standard offpage *
  page43_i191
#ISCELL
  mstr_standard tap *
  page43_i192
#ISCELL
  mstr_standard tap *
  page43_i193
#ISCELL
  mstr_standard tap *
  page43_i194
#ISCELL
  mstr_standard tap *
  page43_i195
#ISCELL
  mstr_standard tap *
  page43_i196
#ISCELL
  mstr_standard tap *
  page43_i197
#ISCELL
  mstr_standard tap *
  page43_i198
#ISCELL
  mstr_standard tap *
  page43_i199
#CELL
  mstr_sconn sconn288_h44441004 *
  page43_i2
#ISCELL
  mstr_standard tap *
  page43_i200
#ISCELL
  mstr_standard tap *
  page43_i201
#ISCELL
  mstr_standard tap *
  page43_i202
#ISCELL
  mstr_standard tap *
  page43_i203
#ISCELL
  mstr_standard offpage *
  page43_i204
#ISCELL
  mstr_standard tap *
  page43_i205
#ISCELL
  mstr_standard tap *
  page43_i206
#ISCELL
  mstr_standard tap *
  page43_i207
#ISCELL
  mstr_standard tap *
  page43_i208
#ISCELL
  mstr_standard tap *
  page43_i209
#ISCELL
  mstr_standard tap *
  page43_i210
#ISCELL
  mstr_standard offpage *
  page43_i211
#ISCELL
  mstr_standard tap *
  page43_i212
#ISCELL
  mstr_standard tap *
  page43_i213
#ISCELL
  mstr_standard tap *
  page43_i214
#ISCELL
  mstr_standard tap *
  page43_i215
#ISCELL
  mstr_standard tap *
  page43_i216
#ISCELL
  mstr_standard tap *
  page43_i217
#ISCELL
  mstr_standard tap *
  page43_i218
#ISCELL
  mstr_standard tap *
  page43_i219
#ISCELL
  mstr_standard tap *
  page43_i22
#ISCELL
  mstr_standard tap *
  page43_i220
#ISCELL
  mstr_standard tap *
  page43_i221
#ISCELL
  mstr_standard tap *
  page43_i222
#ISCELL
  mstr_standard tap *
  page43_i223
#ISCELL
  mstr_standard tap *
  page43_i224
#ISCELL
  mstr_standard tap *
  page43_i225
#ISCELL
  mstr_standard tap *
  page43_i226
#ISCELL
  mstr_standard tap *
  page43_i227
#ISCELL
  mstr_standard tap *
  page43_i228
#ISCELL
  mstr_standard tap *
  page43_i229
#ISCELL
  mstr_standard tap *
  page43_i23
#ISCELL
  mstr_standard tap *
  page43_i235
#ISCELL
  mstr_standard tap *
  page43_i236
#ISCELL
  mstr_standard offpage *
  page43_i237
#ISCELL
  mstr_standard tap *
  page43_i238
#ISCELL
  mstr_standard tap *
  page43_i239
#ISCELL
  mstr_standard tap *
  page43_i24
#ISCELL
  mstr_standard offpage *
  page43_i240
#ISCELL
  mstr_standard tap *
  page43_i241
#ISCELL
  mstr_standard tap *
  page43_i242
#ISCELL
  mstr_standard tap *
  page43_i243
#ISCELL
  mstr_standard tap *
  page43_i244
#ISCELL
  mstr_standard offpage *
  page43_i245
#ISCELL
  mstr_standard tap *
  page43_i247
#ISCELL
  mstr_standard tap *
  page43_i25
#ISCELL
  mstr_standard tap *
  page43_i250
#ISCELL
  mstr_standard tap *
  page43_i252
#ISCELL
  mstr_standard tap *
  page43_i254
#ISCELL
  mstr_standard offpage *
  page43_i255
#ISCELL
  mstr_standard offpage *
  page43_i256
#ISCELL
  mstr_standard offpage *
  page43_i257
#ISCELL
  mstr_standard offpage *
  page43_i258
#CELL
  mstr_sconn sconn288_h44441004 *
  page43_i259
#ISCELL
  mstr_standard tap *
  page43_i26
#CELL
  mstr_sconn sconn288_h44441004 *
  page43_i260
#ISCELL
  mstr_symbols pvddq_abc *
  page43_i263
#ISCELL
  mstr_symbols gnd *
  page43_i264
#ISCELL
  mstr_symbols gnd *
  page43_i265
#ISCELL
  mstr_symbols gnd *
  page43_i267
#ISCELL
  mstr_standard offpage *
  page43_i269
#ISCELL
  mstr_standard tap *
  page43_i27
#ISCELL
  mstr_standard offpage *
  page43_i270
#ISCELL
  mstr_symbols gnd *
  page43_i271
#CELL
  dev_discrete cap_a *
  page43_i272
#ISCELL
  mstr_symbols pvpp_abc *
  page43_i273
#ISCELL
  mstr_symbols pvpp_abc *
  page43_i274
#ISCELL
  mstr_symbols pvtt_abc *
  page43_i275
#ISCELL
  mstr_standard offpage *
  page43_i276
#ISCELL
  mstr_standard tap *
  page43_i28
#ISCELL
  mstr_symbols p12v_nvdimm_abc *
  page43_i289
#ISCELL
  mstr_standard tap *
  page43_i29
#ISCELL
  mstr_standard tap *
  page43_i30
#ISCELL
  mstr_standard tap *
  page43_i31
#ISCELL
  mstr_standard tap *
  page43_i32
#ISCELL
  mstr_standard tap *
  page43_i33
#ISCELL
  mstr_standard tap *
  page43_i34
#ISCELL
  mstr_standard tap *
  page43_i35
#ISCELL
  mstr_standard tap *
  page43_i36
#ISCELL
  mstr_standard tap *
  page43_i37
#ISCELL
  mstr_standard tap *
  page43_i38
#ISCELL
  mstr_standard tap *
  page43_i39
#ISCELL
  mstr_standard offpage *
  page43_i40
#ISCELL
  mstr_standard offpage *
  page43_i41
#ISCELL
  mstr_standard offpage *
  page43_i42
#ISCELL
  mstr_standard tap *
  page43_i43
#ISCELL
  mstr_standard tap *
  page43_i44
#ISCELL
  mstr_standard tap *
  page43_i45
#ISCELL
  mstr_standard tap *
  page43_i46
#ISCELL
  mstr_standard offpage *
  page43_i47
#ISCELL
  mstr_standard offpage *
  page43_i48
#ISCELL
  mstr_standard tap *
  page43_i49
#ISCELL
  mstr_standard tap *
  page43_i50
#ISCELL
  mstr_standard tap *
  page43_i51
#ISCELL
  mstr_standard tap *
  page43_i52
#ISCELL
  mstr_standard tap *
  page43_i53
#ISCELL
  mstr_standard tap *
  page43_i54
#ISCELL
  mstr_standard tap *
  page43_i55
#ISCELL
  mstr_standard tap *
  page43_i56
#ISCELL
  mstr_standard offpage *
  page43_i57
#ISCELL
  mstr_standard offpage *
  page43_i59
#ISCELL
  mstr_standard offpage *
  page43_i60
#ISCELL
  mstr_standard offpage *
  page43_i61
#ISCELL
  mstr_symbols bom_note *
  *
#ISCELL
  mstr_symbols intel_corp_bpage *
  *
#ISCELL
  mstr_symbols gnd *
  page44_i1
#ISCELL
  mstr_standard offpage *
  page44_i10
#ISCELL
  mstr_standard tap *
  page44_i100
#ISCELL
  mstr_standard tap *
  page44_i101
#ISCELL
  mstr_standard tap *
  page44_i102
#ISCELL
  mstr_standard tap *
  page44_i103
#ISCELL
  mstr_standard tap *
  page44_i104
#ISCELL
  mstr_standard tap *
  page44_i105
#ISCELL
  mstr_standard tap *
  page44_i106
#ISCELL
  mstr_standard tap *
  page44_i107
#ISCELL
  mstr_standard tap *
  page44_i108
#ISCELL
  mstr_standard tap *
  page44_i109
#ISCELL
  mstr_standard offpage *
  page44_i11
#ISCELL
  mstr_standard tap *
  page44_i110
#ISCELL
  mstr_standard tap *
  page44_i111
#ISCELL
  mstr_standard tap *
  page44_i112
#ISCELL
  mstr_standard tap *
  page44_i113
#ISCELL
  mstr_standard tap *
  page44_i114
#ISCELL
  mstr_standard tap *
  page44_i115
#ISCELL
  mstr_standard tap *
  page44_i116
#ISCELL
  mstr_standard tap *
  page44_i117
#ISCELL
  mstr_symbols pvtt_abc *
  page44_i118
#ISCELL
  mstr_symbols pvpp_abc *
  page44_i119
#ISCELL
  mstr_standard tap *
  page44_i12
#CELL
  mstr_sconn sconn288_h44441003 *
  page44_i120
#ISCELL
  mstr_standard offpage *
  page44_i121
#ISCELL
  mstr_standard tap *
  page44_i122
#ISCELL
  mstr_standard tap *
  page44_i123
#ISCELL
  mstr_standard tap *
  page44_i124
#ISCELL
  mstr_standard tap *
  page44_i125
#ISCELL
  mstr_standard tap *
  page44_i126
#ISCELL
  mstr_standard tap *
  page44_i127
#ISCELL
  mstr_standard tap *
  page44_i128
#ISCELL
  mstr_standard tap *
  page44_i129
#CELL
  mstr_sconn sconn288_h44441003 *
  page44_i13
#ISCELL
  mstr_standard tap *
  page44_i130
#ISCELL
  mstr_standard tap *
  page44_i131
#ISCELL
  mstr_standard tap *
  page44_i132
#ISCELL
  mstr_standard tap *
  page44_i133
#ISCELL
  mstr_standard tap *
  page44_i134
#ISCELL
  mstr_standard tap *
  page44_i135
#ISCELL
  mstr_standard offpage *
  page44_i136
#ISCELL
  mstr_symbols gnd *
  page44_i138
#CELL
  mstr_sconn sconn288_h44441003 *
  page44_i139
#ISCELL
  mstr_standard offpage *
  page44_i14
#ISCELL
  mstr_standard tap *
  page44_i142
#ISCELL
  mstr_standard tap *
  page44_i143
#ISCELL
  mstr_standard tap *
  page44_i144
#ISCELL
  mstr_standard tap *
  page44_i145
#ISCELL
  mstr_standard tap *
  page44_i146
#ISCELL
  mstr_standard tap *
  page44_i147
#ISCELL
  mstr_standard tap *
  page44_i148
#ISCELL
  mstr_standard tap *
  page44_i149
#ISCELL
  mstr_standard offpage *
  page44_i15
#ISCELL
  mstr_standard tap *
  page44_i150
#ISCELL
  mstr_standard tap *
  page44_i151
#ISCELL
  mstr_standard tap *
  page44_i152
#ISCELL
  mstr_standard tap *
  page44_i153
#ISCELL
  mstr_standard tap *
  page44_i154
#ISCELL
  mstr_standard tap *
  page44_i155
#ISCELL
  mstr_standard tap *
  page44_i156
#ISCELL
  mstr_standard tap *
  page44_i157
#ISCELL
  mstr_standard tap *
  page44_i158
#ISCELL
  mstr_standard tap *
  page44_i159
#ISCELL
  mstr_standard offpage *
  page44_i16
#ISCELL
  mstr_standard tap *
  page44_i160
#ISCELL
  mstr_symbols gnd *
  page44_i162
#ISCELL
  mstr_standard tap *
  page44_i163
#ISCELL
  mstr_standard tap *
  page44_i164
#ISCELL
  mstr_standard tap *
  page44_i165
#ISCELL
  mstr_standard tap *
  page44_i166
#ISCELL
  mstr_standard tap *
  page44_i167
#ISCELL
  mstr_standard tap *
  page44_i168
#ISCELL
  mstr_standard tap *
  page44_i169
#ISCELL
  mstr_standard offpage *
  page44_i17
#ISCELL
  mstr_standard tap *
  page44_i170
#ISCELL
  mstr_standard tap *
  page44_i171
#ISCELL
  mstr_standard tap *
  page44_i172
#ISCELL
  mstr_standard tap *
  page44_i173
#ISCELL
  mstr_standard tap *
  page44_i174
#ISCELL
  mstr_standard tap *
  page44_i175
#ISCELL
  mstr_standard tap *
  page44_i176
#ISCELL
  mstr_standard tap *
  page44_i177
#ISCELL
  mstr_standard tap *
  page44_i178
#ISCELL
  mstr_standard tap *
  page44_i179
#ISCELL
  mstr_standard offpage *
  page44_i18
#ISCELL
  mstr_standard offpage *
  page44_i182
#ISCELL
  mstr_standard offpage *
  page44_i183
#ISCELL
  mstr_symbols p12v_nvdimm_abc *
  page44_i184
#ISCELL
  mstr_standard offpage *
  page44_i19
#CELL
  dev_discrete cap_a *
  page44_i2
#ISCELL
  mstr_standard offpage *
  page44_i20
#ISCELL
  mstr_standard tap *
  page44_i21
#ISCELL
  mstr_standard tap *
  page44_i22
#ISCELL
  mstr_standard tap *
  page44_i23
#ISCELL
  mstr_standard tap *
  page44_i24
#ISCELL
  mstr_standard tap *
  page44_i25
#ISCELL
  mstr_standard tap *
  page44_i26
#ISCELL
  mstr_standard tap *
  page44_i27
#ISCELL
  mstr_standard tap *
  page44_i28
#ISCELL
  mstr_standard tap *
  page44_i29
#ISCELL
  mstr_symbols gnd *
  page44_i3
#ISCELL
  mstr_standard tap *
  page44_i30
#ISCELL
  mstr_standard tap *
  page44_i31
#ISCELL
  mstr_standard tap *
  page44_i32
#ISCELL
  mstr_standard tap *
  page44_i33
#ISCELL
  mstr_standard tap *
  page44_i34
#ISCELL
  mstr_standard tap *
  page44_i35
#ISCELL
  mstr_standard tap *
  page44_i36
#ISCELL
  mstr_standard offpage *
  page44_i37
#ISCELL
  mstr_standard offpage *
  page44_i38
#ISCELL
  mstr_standard offpage *
  page44_i39
#ISCELL
  mstr_standard offpage *
  page44_i4
#ISCELL
  mstr_standard offpage *
  page44_i40
#ISCELL
  mstr_standard tap *
  page44_i41
#ISCELL
  mstr_standard tap *
  page44_i42
#ISCELL
  mstr_standard tap *
  page44_i43
#ISCELL
  mstr_standard tap *
  page44_i44
#ISCELL
  mstr_standard tap *
  page44_i45
#ISCELL
  mstr_standard tap *
  page44_i46
#ISCELL
  mstr_standard tap *
  page44_i47
#ISCELL
  mstr_standard tap *
  page44_i48
#ISCELL
  mstr_standard tap *
  page44_i49
#ISCELL
  mstr_symbols pvpp_abc *
  page44_i5
#ISCELL
  mstr_standard tap *
  page44_i50
#ISCELL
  mstr_standard tap *
  page44_i51
#ISCELL
  mstr_standard tap *
  page44_i52
#ISCELL
  mstr_standard tap *
  page44_i53
#ISCELL
  mstr_standard tap *
  page44_i54
#ISCELL
  mstr_standard tap *
  page44_i55
#ISCELL
  mstr_standard tap *
  page44_i56
#ISCELL
  mstr_standard tap *
  page44_i57
#ISCELL
  mstr_standard tap *
  page44_i58
#ISCELL
  mstr_standard tap *
  page44_i59
#ISCELL
  mstr_standard offpage *
  page44_i6
#ISCELL
  mstr_standard tap *
  page44_i60
#ISCELL
  mstr_standard tap *
  page44_i61
#ISCELL
  mstr_standard tap *
  page44_i62
#ISCELL
  mstr_standard tap *
  page44_i63
#ISCELL
  mstr_standard tap *
  page44_i64
#ISCELL
  mstr_standard tap *
  page44_i65
#ISCELL
  mstr_standard tap *
  page44_i66
#ISCELL
  mstr_standard tap *
  page44_i67
#ISCELL
  mstr_standard tap *
  page44_i68
#ISCELL
  mstr_standard tap *
  page44_i69
#ISCELL
  mstr_standard offpage *
  page44_i7
#ISCELL
  mstr_standard tap *
  page44_i70
#ISCELL
  mstr_standard tap *
  page44_i71
#ISCELL
  mstr_standard tap *
  page44_i72
#ISCELL
  mstr_standard tap *
  page44_i73
#ISCELL
  mstr_standard tap *
  page44_i74
#CELL
  mstr_sconn sconn288_h44441003 *
  page44_i75
#ISCELL
  mstr_standard tap *
  page44_i76
#ISCELL
  mstr_standard tap *
  page44_i77
#ISCELL
  mstr_standard tap *
  page44_i78
#ISCELL
  mstr_standard tap *
  page44_i79
#ISCELL
  mstr_standard offpage *
  page44_i8
#ISCELL
  mstr_standard tap *
  page44_i80
#ISCELL
  mstr_standard tap *
  page44_i81
#ISCELL
  mstr_standard tap *
  page44_i82
#ISCELL
  mstr_standard tap *
  page44_i83
#ISCELL
  mstr_standard tap *
  page44_i84
#ISCELL
  mstr_standard tap *
  page44_i85
#ISCELL
  mstr_standard tap *
  page44_i86
#ISCELL
  mstr_standard tap *
  page44_i87
#ISCELL
  mstr_standard tap *
  page44_i88
#ISCELL
  mstr_standard tap *
  page44_i89
#ISCELL
  mstr_standard offpage *
  page44_i9
#ISCELL
  mstr_standard tap *
  page44_i90
#ISCELL
  mstr_standard tap *
  page44_i91
#ISCELL
  mstr_standard tap *
  page44_i92
#ISCELL
  mstr_standard tap *
  page44_i93
#ISCELL
  mstr_standard tap *
  page44_i94
#ISCELL
  mstr_standard tap *
  page44_i95
#ISCELL
  mstr_standard tap *
  page44_i96
#ISCELL
  mstr_symbols pvddq_abc *
  page44_i97
#ISCELL
  mstr_standard tap *
  page44_i98
#ISCELL
  mstr_standard tap *
  page44_i99
#ISCELL
  mstr_symbols bom_note *
  *
#ISCELL
  mstr_symbols intel_corp_bpage *
  *
#ISCELL
  mstr_standard offpage *
  page45_i1
#ISCELL
  mstr_standard tap *
  page45_i10
#ISCELL
  mstr_standard tap *
  page45_i100
#ISCELL
  mstr_standard tap *
  page45_i101
#ISCELL
  mstr_standard tap *
  page45_i102
#ISCELL
  mstr_standard tap *
  page45_i103
#ISCELL
  mstr_standard tap *
  page45_i104
#ISCELL
  mstr_standard tap *
  page45_i105
#ISCELL
  mstr_standard tap *
  page45_i106
#ISCELL
  mstr_standard tap *
  page45_i107
#ISCELL
  mstr_standard tap *
  page45_i108
#ISCELL
  mstr_standard tap *
  page45_i109
#ISCELL
  mstr_standard tap *
  page45_i110
#CELL
  mstr_sconn sconn288_h44441004 *
  page45_i111
#ISCELL
  mstr_standard tap *
  page45_i112
#ISCELL
  mstr_standard tap *
  page45_i113
#ISCELL
  mstr_standard tap *
  page45_i114
#ISCELL
  mstr_standard tap *
  page45_i115
#ISCELL
  mstr_standard tap *
  page45_i116
#ISCELL
  mstr_standard tap *
  page45_i117
#ISCELL
  mstr_standard tap *
  page45_i118
#ISCELL
  mstr_standard tap *
  page45_i119
#ISCELL
  mstr_symbols pvtt_abc *
  page45_i12
#ISCELL
  mstr_standard tap *
  page45_i120
#ISCELL
  mstr_standard tap *
  page45_i121
#ISCELL
  mstr_standard tap *
  page45_i122
#ISCELL
  mstr_standard tap *
  page45_i123
#ISCELL
  mstr_standard tap *
  page45_i124
#ISCELL
  mstr_standard tap *
  page45_i125
#ISCELL
  mstr_standard tap *
  page45_i126
#ISCELL
  mstr_standard offpage *
  page45_i127
#ISCELL
  mstr_standard tap *
  page45_i128
#ISCELL
  mstr_standard tap *
  page45_i129
#ISCELL
  mstr_symbols pvddq_abc *
  page45_i13
#ISCELL
  mstr_standard tap *
  page45_i130
#ISCELL
  mstr_standard tap *
  page45_i131
#ISCELL
  mstr_standard tap *
  page45_i132
#ISCELL
  mstr_standard tap *
  page45_i133
#ISCELL
  mstr_standard tap *
  page45_i134
#ISCELL
  mstr_standard offpage *
  page45_i135
#ISCELL
  mstr_standard offpage *
  page45_i136
#ISCELL
  mstr_standard offpage *
  page45_i137
#ISCELL
  mstr_standard tap *
  page45_i138
#ISCELL
  mstr_standard tap *
  page45_i139
#ISCELL
  mstr_standard tap *
  page45_i14
#ISCELL
  mstr_standard tap *
  page45_i140
#ISCELL
  mstr_standard tap *
  page45_i141
#ISCELL
  mstr_standard tap *
  page45_i142
#ISCELL
  mstr_standard tap *
  page45_i143
#ISCELL
  mstr_standard tap *
  page45_i144
#ISCELL
  mstr_standard tap *
  page45_i145
#ISCELL
  mstr_standard offpage *
  page45_i146
#ISCELL
  mstr_standard offpage *
  page45_i147
#ISCELL
  mstr_standard offpage *
  page45_i148
#ISCELL
  mstr_standard offpage *
  page45_i149
#ISCELL
  mstr_standard tap *
  page45_i15
#ISCELL
  mstr_standard offpage *
  page45_i150
#ISCELL
  mstr_standard offpage *
  page45_i151
#ISCELL
  mstr_standard tap *
  page45_i152
#ISCELL
  mstr_standard tap *
  page45_i153
#ISCELL
  mstr_standard offpage *
  page45_i154
#ISCELL
  mstr_standard tap *
  page45_i155
#ISCELL
  mstr_standard tap *
  page45_i156
#ISCELL
  mstr_standard offpage *
  page45_i157
#ISCELL
  mstr_standard tap *
  page45_i158
#ISCELL
  mstr_standard offpage *
  page45_i159
#ISCELL
  mstr_standard tap *
  page45_i16
#ISCELL
  mstr_standard tap *
  page45_i160
#ISCELL
  mstr_standard tap *
  page45_i161
#ISCELL
  mstr_standard tap *
  page45_i162
#ISCELL
  mstr_standard tap *
  page45_i163
#ISCELL
  mstr_standard tap *
  page45_i164
#ISCELL
  mstr_standard tap *
  page45_i165
#ISCELL
  mstr_standard tap *
  page45_i166
#ISCELL
  mstr_standard offpage *
  page45_i167
#ISCELL
  mstr_standard offpage *
  page45_i168
#CELL
  mstr_sconn sconn288_h44441004 *
  page45_i169
#ISCELL
  mstr_standard tap *
  page45_i17
#ISCELL
  mstr_symbols gnd *
  page45_i174
#ISCELL
  mstr_standard offpage *
  page45_i175
#ISCELL
  mstr_standard offpage *
  page45_i176
#ISCELL
  mstr_standard offpage *
  page45_i177
#ISCELL
  mstr_symbols gnd *
  page45_i178
#CELL
  dev_discrete cap_a *
  page45_i179
#ISCELL
  mstr_standard tap *
  page45_i18
#ISCELL
  mstr_symbols pvpp_abc *
  page45_i180
#ISCELL
  mstr_symbols pvpp_abc *
  page45_i181
#ISCELL
  mstr_standard offpage *
  page45_i182
#ISCELL
  mstr_symbols p12v_nvdimm_abc *
  page45_i183
#ISCELL
  mstr_standard tap *
  page45_i19
#ISCELL
  mstr_standard offpage *
  page45_i2
#ISCELL
  mstr_standard tap *
  page45_i20
#ISCELL
  mstr_standard tap *
  page45_i21
#ISCELL
  mstr_standard tap *
  page45_i22
#ISCELL
  mstr_standard tap *
  page45_i23
#ISCELL
  mstr_standard tap *
  page45_i24
#ISCELL
  mstr_standard tap *
  page45_i25
#ISCELL
  mstr_standard tap *
  page45_i26
#ISCELL
  mstr_standard tap *
  page45_i27
#ISCELL
  mstr_standard tap *
  page45_i28
#ISCELL
  mstr_standard tap *
  page45_i29
#ISCELL
  mstr_standard tap *
  page45_i3
#ISCELL
  mstr_standard tap *
  page45_i30
#ISCELL
  mstr_standard tap *
  page45_i31
#ISCELL
  mstr_standard tap *
  page45_i32
#ISCELL
  mstr_standard tap *
  page45_i33
#ISCELL
  mstr_standard tap *
  page45_i34
#ISCELL
  mstr_standard tap *
  page45_i35
#ISCELL
  mstr_standard tap *
  page45_i36
#ISCELL
  mstr_standard tap *
  page45_i37
#ISCELL
  mstr_standard tap *
  page45_i38
#ISCELL
  mstr_standard tap *
  page45_i39
#ISCELL
  mstr_standard tap *
  page45_i4
#ISCELL
  mstr_standard tap *
  page45_i40
#ISCELL
  mstr_standard tap *
  page45_i41
#ISCELL
  mstr_symbols gnd *
  page45_i42
#CELL
  mstr_sconn sconn288_h44441004 *
  page45_i43
#ISCELL
  mstr_symbols gnd *
  page45_i44
#ISCELL
  mstr_standard offpage *
  page45_i45
#ISCELL
  mstr_standard tap *
  page45_i46
#ISCELL
  mstr_standard tap *
  page45_i47
#ISCELL
  mstr_standard tap *
  page45_i48
#ISCELL
  mstr_standard tap *
  page45_i49
#ISCELL
  mstr_standard tap *
  page45_i5
#ISCELL
  mstr_standard tap *
  page45_i50
#ISCELL
  mstr_standard tap *
  page45_i51
#ISCELL
  mstr_standard tap *
  page45_i52
#ISCELL
  mstr_standard tap *
  page45_i53
#ISCELL
  mstr_standard tap *
  page45_i54
#ISCELL
  mstr_standard tap *
  page45_i55
#ISCELL
  mstr_standard tap *
  page45_i56
#ISCELL
  mstr_standard tap *
  page45_i57
#ISCELL
  mstr_standard tap *
  page45_i58
#ISCELL
  mstr_standard tap *
  page45_i59
#ISCELL
  mstr_standard tap *
  page45_i6
#ISCELL
  mstr_standard tap *
  page45_i60
#CELL
  mstr_sconn sconn288_h44441004 *
  page45_i61
#ISCELL
  mstr_standard tap *
  page45_i62
#ISCELL
  mstr_standard tap *
  page45_i63
#ISCELL
  mstr_standard tap *
  page45_i64
#ISCELL
  mstr_standard tap *
  page45_i65
#ISCELL
  mstr_standard tap *
  page45_i66
#ISCELL
  mstr_standard tap *
  page45_i67
#ISCELL
  mstr_standard tap *
  page45_i68
#ISCELL
  mstr_standard tap *
  page45_i69
#ISCELL
  mstr_standard tap *
  page45_i7
#ISCELL
  mstr_standard tap *
  page45_i70
#ISCELL
  mstr_standard tap *
  page45_i71
#ISCELL
  mstr_standard tap *
  page45_i72
#ISCELL
  mstr_standard tap *
  page45_i73
#ISCELL
  mstr_standard tap *
  page45_i74
#ISCELL
  mstr_standard tap *
  page45_i75
#ISCELL
  mstr_standard tap *
  page45_i76
#ISCELL
  mstr_standard tap *
  page45_i77
#ISCELL
  mstr_standard tap *
  page45_i78
#ISCELL
  mstr_standard tap *
  page45_i79
#ISCELL
  mstr_standard tap *
  page45_i8
#ISCELL
  mstr_standard tap *
  page45_i80
#ISCELL
  mstr_standard tap *
  page45_i81
#ISCELL
  mstr_standard tap *
  page45_i82
#ISCELL
  mstr_standard tap *
  page45_i83
#ISCELL
  mstr_standard tap *
  page45_i84
#ISCELL
  mstr_standard tap *
  page45_i85
#ISCELL
  mstr_standard tap *
  page45_i86
#ISCELL
  mstr_standard tap *
  page45_i87
#ISCELL
  mstr_standard tap *
  page45_i88
#ISCELL
  mstr_standard tap *
  page45_i89
#ISCELL
  mstr_standard tap *
  page45_i9
#ISCELL
  mstr_standard tap *
  page45_i90
#ISCELL
  mstr_standard tap *
  page45_i91
#ISCELL
  mstr_standard tap *
  page45_i92
#ISCELL
  mstr_standard tap *
  page45_i93
#ISCELL
  mstr_standard tap *
  page45_i94
#ISCELL
  mstr_standard tap *
  page45_i95
#ISCELL
  mstr_standard tap *
  page45_i96
#ISCELL
  mstr_standard tap *
  page45_i97
#ISCELL
  mstr_standard tap *
  page45_i98
#ISCELL
  mstr_standard tap *
  page45_i99
#ISCELL
  mstr_symbols bom_note *
  *
#ISCELL
  mstr_symbols intel_corp_bpage *
  *
#ISCELL
  mstr_symbols gnd *
  page46_i1
#ISCELL
  mstr_standard offpage *
  page46_i10
#ISCELL
  mstr_standard tap *
  page46_i100
#ISCELL
  mstr_standard tap *
  page46_i101
#ISCELL
  mstr_standard tap *
  page46_i102
#ISCELL
  mstr_standard tap *
  page46_i103
#ISCELL
  mstr_standard tap *
  page46_i104
#ISCELL
  mstr_standard tap *
  page46_i105
#ISCELL
  mstr_standard tap *
  page46_i106
#ISCELL
  mstr_standard tap *
  page46_i107
#ISCELL
  mstr_standard tap *
  page46_i108
#ISCELL
  mstr_symbols pvddq_abc *
  page46_i109
#ISCELL
  mstr_standard offpage *
  page46_i11
#ISCELL
  mstr_symbols pvtt_abc *
  page46_i110
#ISCELL
  mstr_symbols pvpp_abc *
  page46_i111
#CELL
  mstr_sconn sconn288_h44441003 *
  page46_i112
#ISCELL
  mstr_standard offpage *
  page46_i113
#ISCELL
  mstr_standard tap *
  page46_i114
#ISCELL
  mstr_standard tap *
  page46_i115
#ISCELL
  mstr_standard tap *
  page46_i116
#ISCELL
  mstr_standard tap *
  page46_i117
#ISCELL
  mstr_standard tap *
  page46_i118
#ISCELL
  mstr_standard tap *
  page46_i119
#ISCELL
  mstr_standard offpage *
  page46_i12
#ISCELL
  mstr_standard tap *
  page46_i120
#ISCELL
  mstr_standard tap *
  page46_i121
#ISCELL
  mstr_standard tap *
  page46_i122
#ISCELL
  mstr_standard tap *
  page46_i123
#ISCELL
  mstr_standard tap *
  page46_i124
#ISCELL
  mstr_standard tap *
  page46_i125
#ISCELL
  mstr_standard tap *
  page46_i126
#ISCELL
  mstr_standard tap *
  page46_i127
#ISCELL
  mstr_standard tap *
  page46_i128
#ISCELL
  mstr_standard tap *
  page46_i129
#ISCELL
  mstr_standard offpage *
  page46_i13
#ISCELL
  mstr_standard tap *
  page46_i130
#ISCELL
  mstr_standard tap *
  page46_i131
#ISCELL
  mstr_standard tap *
  page46_i132
#ISCELL
  mstr_standard tap *
  page46_i133
#ISCELL
  mstr_standard tap *
  page46_i134
#ISCELL
  mstr_standard tap *
  page46_i135
#ISCELL
  mstr_standard offpage *
  page46_i136
#ISCELL
  mstr_symbols gnd *
  page46_i137
#CELL
  mstr_sconn sconn288_h44441003 *
  page46_i138
#CELL
  mstr_sconn sconn288_h44441003 *
  page46_i14
#ISCELL
  mstr_standard tap *
  page46_i142
#ISCELL
  mstr_standard tap *
  page46_i143
#ISCELL
  mstr_standard tap *
  page46_i144
#ISCELL
  mstr_standard tap *
  page46_i145
#ISCELL
  mstr_standard tap *
  page46_i146
#ISCELL
  mstr_standard tap *
  page46_i147
#ISCELL
  mstr_standard tap *
  page46_i148
#ISCELL
  mstr_standard tap *
  page46_i149
#ISCELL
  mstr_standard offpage *
  page46_i15
#ISCELL
  mstr_standard tap *
  page46_i150
#ISCELL
  mstr_standard tap *
  page46_i151
#ISCELL
  mstr_standard tap *
  page46_i152
#ISCELL
  mstr_standard tap *
  page46_i153
#ISCELL
  mstr_standard tap *
  page46_i154
#ISCELL
  mstr_standard tap *
  page46_i155
#ISCELL
  mstr_symbols gnd *
  page46_i156
#ISCELL
  mstr_standard tap *
  page46_i157
#ISCELL
  mstr_standard tap *
  page46_i158
#ISCELL
  mstr_standard tap *
  page46_i159
#ISCELL
  mstr_standard offpage *
  page46_i16
#ISCELL
  mstr_standard tap *
  page46_i160
#ISCELL
  mstr_standard tap *
  page46_i161
#ISCELL
  mstr_standard tap *
  page46_i162
#ISCELL
  mstr_standard tap *
  page46_i163
#ISCELL
  mstr_standard tap *
  page46_i164
#ISCELL
  mstr_standard tap *
  page46_i165
#ISCELL
  mstr_standard tap *
  page46_i166
#ISCELL
  mstr_standard tap *
  page46_i167
#ISCELL
  mstr_standard tap *
  page46_i168
#ISCELL
  mstr_standard tap *
  page46_i169
#ISCELL
  mstr_standard offpage *
  page46_i17
#ISCELL
  mstr_standard tap *
  page46_i170
#ISCELL
  mstr_standard tap *
  page46_i171
#ISCELL
  mstr_standard tap *
  page46_i172
#ISCELL
  mstr_standard tap *
  page46_i173
#ISCELL
  mstr_standard tap *
  page46_i174
#ISCELL
  mstr_standard tap *
  page46_i175
#ISCELL
  mstr_standard tap *
  page46_i176
#ISCELL
  mstr_standard tap *
  page46_i177
#ISCELL
  mstr_standard tap *
  page46_i178
#ISCELL
  mstr_standard offpage *
  page46_i179
#ISCELL
  mstr_standard offpage *
  page46_i18
#ISCELL
  mstr_standard offpage *
  page46_i180
#ISCELL
  mstr_symbols p12v_nvdimm_abc *
  page46_i181
#ISCELL
  mstr_standard offpage *
  page46_i19
#ISCELL
  mstr_standard offpage *
  page46_i2
#ISCELL
  mstr_standard tap *
  page46_i20
#ISCELL
  mstr_standard tap *
  page46_i21
#ISCELL
  mstr_standard tap *
  page46_i22
#ISCELL
  mstr_standard tap *
  page46_i23
#ISCELL
  mstr_standard tap *
  page46_i24
#ISCELL
  mstr_standard tap *
  page46_i25
#ISCELL
  mstr_standard tap *
  page46_i26
#ISCELL
  mstr_standard tap *
  page46_i27
#ISCELL
  mstr_standard tap *
  page46_i28
#ISCELL
  mstr_standard tap *
  page46_i29
#ISCELL
  mstr_symbols gnd *
  page46_i3
#ISCELL
  mstr_standard tap *
  page46_i30
#ISCELL
  mstr_standard tap *
  page46_i31
#ISCELL
  mstr_standard tap *
  page46_i32
#ISCELL
  mstr_standard tap *
  page46_i33
#ISCELL
  mstr_standard tap *
  page46_i34
#ISCELL
  mstr_standard offpage *
  page46_i35
#ISCELL
  mstr_standard offpage *
  page46_i36
#ISCELL
  mstr_standard offpage *
  page46_i37
#ISCELL
  mstr_standard offpage *
  page46_i38
#ISCELL
  mstr_standard tap *
  page46_i39
#ISCELL
  mstr_symbols pvpp_abc *
  page46_i4
#ISCELL
  mstr_standard tap *
  page46_i40
#ISCELL
  mstr_standard tap *
  page46_i41
#ISCELL
  mstr_standard tap *
  page46_i42
#ISCELL
  mstr_standard tap *
  page46_i43
#ISCELL
  mstr_standard tap *
  page46_i44
#ISCELL
  mstr_standard tap *
  page46_i45
#ISCELL
  mstr_standard tap *
  page46_i46
#ISCELL
  mstr_standard tap *
  page46_i47
#ISCELL
  mstr_standard tap *
  page46_i48
#ISCELL
  mstr_standard tap *
  page46_i49
#CELL
  dev_discrete cap_a *
  page46_i5
#ISCELL
  mstr_standard tap *
  page46_i50
#ISCELL
  mstr_standard tap *
  page46_i51
#ISCELL
  mstr_standard tap *
  page46_i52
#ISCELL
  mstr_standard tap *
  page46_i53
#ISCELL
  mstr_standard tap *
  page46_i54
#ISCELL
  mstr_standard tap *
  page46_i55
#ISCELL
  mstr_standard tap *
  page46_i56
#ISCELL
  mstr_standard tap *
  page46_i57
#ISCELL
  mstr_standard tap *
  page46_i58
#ISCELL
  mstr_standard tap *
  page46_i59
#ISCELL
  mstr_standard offpage *
  page46_i6
#ISCELL
  mstr_standard tap *
  page46_i60
#ISCELL
  mstr_standard tap *
  page46_i61
#ISCELL
  mstr_standard tap *
  page46_i62
#ISCELL
  mstr_standard tap *
  page46_i63
#ISCELL
  mstr_standard tap *
  page46_i64
#ISCELL
  mstr_standard tap *
  page46_i65
#ISCELL
  mstr_standard tap *
  page46_i66
#CELL
  mstr_sconn sconn288_h44441003 *
  page46_i67
#ISCELL
  mstr_standard tap *
  page46_i68
#ISCELL
  mstr_standard tap *
  page46_i69
#ISCELL
  mstr_standard offpage *
  page46_i7
#ISCELL
  mstr_standard tap *
  page46_i70
#ISCELL
  mstr_standard tap *
  page46_i71
#ISCELL
  mstr_standard tap *
  page46_i72
#ISCELL
  mstr_standard tap *
  page46_i73
#ISCELL
  mstr_standard tap *
  page46_i74
#ISCELL
  mstr_standard tap *
  page46_i75
#ISCELL
  mstr_standard tap *
  page46_i76
#ISCELL
  mstr_standard tap *
  page46_i77
#ISCELL
  mstr_standard tap *
  page46_i78
#ISCELL
  mstr_standard tap *
  page46_i79
#ISCELL
  mstr_standard offpage *
  page46_i8
#ISCELL
  mstr_standard tap *
  page46_i80
#ISCELL
  mstr_standard tap *
  page46_i81
#ISCELL
  mstr_standard tap *
  page46_i82
#ISCELL
  mstr_standard tap *
  page46_i83
#ISCELL
  mstr_standard tap *
  page46_i84
#ISCELL
  mstr_standard tap *
  page46_i85
#ISCELL
  mstr_standard tap *
  page46_i86
#ISCELL
  mstr_standard tap *
  page46_i87
#ISCELL
  mstr_standard tap *
  page46_i88
#ISCELL
  mstr_standard tap *
  page46_i89
#ISCELL
  mstr_standard offpage *
  page46_i9
#ISCELL
  mstr_standard tap *
  page46_i90
#ISCELL
  mstr_standard tap *
  page46_i91
#ISCELL
  mstr_standard tap *
  page46_i92
#ISCELL
  mstr_standard tap *
  page46_i93
#ISCELL
  mstr_standard tap *
  page46_i94
#ISCELL
  mstr_standard tap *
  page46_i95
#ISCELL
  mstr_standard tap *
  page46_i96
#ISCELL
  mstr_standard tap *
  page46_i97
#ISCELL
  mstr_standard tap *
  page46_i98
#ISCELL
  mstr_standard tap *
  page46_i99
#ISCELL
  mstr_symbols bom_note *
  *
#ISCELL
  mstr_symbols intel_corp_bpage *
  *
#ISCELL
  mstr_standard offpage *
  page47_i1
#ISCELL
  mstr_standard tap *
  page47_i10
#ISCELL
  mstr_standard tap *
  page47_i100
#ISCELL
  mstr_standard tap *
  page47_i101
#ISCELL
  mstr_standard tap *
  page47_i102
#ISCELL
  mstr_standard tap *
  page47_i103
#ISCELL
  mstr_standard tap *
  page47_i104
#ISCELL
  mstr_standard tap *
  page47_i105
#ISCELL
  mstr_standard tap *
  page47_i106
#ISCELL
  mstr_standard tap *
  page47_i107
#ISCELL
  mstr_standard tap *
  page47_i108
#ISCELL
  mstr_standard tap *
  page47_i109
#ISCELL
  mstr_standard tap *
  page47_i110
#CELL
  mstr_sconn sconn288_h44441004 *
  page47_i111
#ISCELL
  mstr_standard tap *
  page47_i112
#ISCELL
  mstr_standard tap *
  page47_i113
#ISCELL
  mstr_standard tap *
  page47_i114
#ISCELL
  mstr_standard tap *
  page47_i115
#ISCELL
  mstr_standard tap *
  page47_i116
#ISCELL
  mstr_standard tap *
  page47_i117
#ISCELL
  mstr_standard tap *
  page47_i118
#ISCELL
  mstr_standard tap *
  page47_i119
#ISCELL
  mstr_symbols pvtt_abc *
  page47_i12
#ISCELL
  mstr_standard tap *
  page47_i120
#ISCELL
  mstr_standard tap *
  page47_i121
#ISCELL
  mstr_standard tap *
  page47_i122
#ISCELL
  mstr_standard tap *
  page47_i123
#ISCELL
  mstr_standard tap *
  page47_i124
#ISCELL
  mstr_standard tap *
  page47_i125
#ISCELL
  mstr_standard tap *
  page47_i126
#ISCELL
  mstr_standard offpage *
  page47_i127
#ISCELL
  mstr_standard tap *
  page47_i128
#ISCELL
  mstr_standard tap *
  page47_i129
#ISCELL
  mstr_symbols pvddq_abc *
  page47_i13
#ISCELL
  mstr_standard tap *
  page47_i130
#ISCELL
  mstr_standard tap *
  page47_i131
#ISCELL
  mstr_standard tap *
  page47_i132
#ISCELL
  mstr_standard tap *
  page47_i133
#ISCELL
  mstr_standard tap *
  page47_i134
#ISCELL
  mstr_standard offpage *
  page47_i135
#ISCELL
  mstr_standard offpage *
  page47_i136
#ISCELL
  mstr_standard offpage *
  page47_i137
#ISCELL
  mstr_standard tap *
  page47_i138
#ISCELL
  mstr_standard tap *
  page47_i139
#ISCELL
  mstr_standard tap *
  page47_i14
#ISCELL
  mstr_standard tap *
  page47_i140
#ISCELL
  mstr_standard tap *
  page47_i141
#ISCELL
  mstr_standard tap *
  page47_i142
#ISCELL
  mstr_standard tap *
  page47_i143
#ISCELL
  mstr_standard tap *
  page47_i144
#ISCELL
  mstr_standard tap *
  page47_i145
#ISCELL
  mstr_standard offpage *
  page47_i146
#ISCELL
  mstr_standard offpage *
  page47_i147
#ISCELL
  mstr_standard offpage *
  page47_i148
#ISCELL
  mstr_standard offpage *
  page47_i149
#ISCELL
  mstr_standard tap *
  page47_i15
#ISCELL
  mstr_standard offpage *
  page47_i150
#ISCELL
  mstr_standard offpage *
  page47_i151
#ISCELL
  mstr_standard tap *
  page47_i152
#ISCELL
  mstr_standard tap *
  page47_i153
#ISCELL
  mstr_standard offpage *
  page47_i154
#ISCELL
  mstr_standard tap *
  page47_i155
#ISCELL
  mstr_standard tap *
  page47_i156
#ISCELL
  mstr_standard offpage *
  page47_i157
#ISCELL
  mstr_standard tap *
  page47_i158
#ISCELL
  mstr_standard offpage *
  page47_i159
#ISCELL
  mstr_standard tap *
  page47_i16
#ISCELL
  mstr_standard tap *
  page47_i160
#ISCELL
  mstr_standard tap *
  page47_i161
#ISCELL
  mstr_standard tap *
  page47_i162
#ISCELL
  mstr_standard tap *
  page47_i17
#ISCELL
  mstr_standard tap *
  page47_i174
#ISCELL
  mstr_standard tap *
  page47_i175
#ISCELL
  mstr_standard offpage *
  page47_i177
#ISCELL
  mstr_standard offpage *
  page47_i178
#CELL
  mstr_sconn sconn288_h44441004 *
  page47_i179
#ISCELL
  mstr_standard tap *
  page47_i18
#ISCELL
  mstr_symbols gnd *
  page47_i180
#ISCELL
  mstr_standard offpage *
  page47_i183
#ISCELL
  mstr_symbols gnd *
  page47_i184
#ISCELL
  mstr_standard offpage *
  page47_i186
#ISCELL
  mstr_standard offpage *
  page47_i187
#CELL
  dev_discrete cap_a *
  page47_i188
#ISCELL
  mstr_symbols gnd *
  page47_i189
#ISCELL
  mstr_standard tap *
  page47_i19
#ISCELL
  mstr_symbols pvpp_abc *
  page47_i190
#ISCELL
  mstr_symbols pvpp_abc *
  page47_i191
#ISCELL
  mstr_standard offpage *
  page47_i192
#ISCELL
  mstr_standard tap *
  page47_i196
#ISCELL
  mstr_standard tap *
  page47_i197
#ISCELL
  mstr_symbols p12v_nvdimm_abc *
  page47_i198
#ISCELL
  mstr_standard offpage *
  page47_i2
#ISCELL
  mstr_standard tap *
  page47_i20
#ISCELL
  mstr_standard tap *
  page47_i21
#ISCELL
  mstr_standard tap *
  page47_i22
#ISCELL
  mstr_standard tap *
  page47_i23
#ISCELL
  mstr_standard tap *
  page47_i24
#ISCELL
  mstr_standard tap *
  page47_i25
#ISCELL
  mstr_standard tap *
  page47_i26
#ISCELL
  mstr_standard tap *
  page47_i27
#ISCELL
  mstr_standard tap *
  page47_i28
#ISCELL
  mstr_standard tap *
  page47_i29
#ISCELL
  mstr_standard tap *
  page47_i3
#ISCELL
  mstr_standard tap *
  page47_i30
#ISCELL
  mstr_standard tap *
  page47_i31
#ISCELL
  mstr_standard tap *
  page47_i32
#ISCELL
  mstr_standard tap *
  page47_i33
#ISCELL
  mstr_standard tap *
  page47_i34
#ISCELL
  mstr_standard tap *
  page47_i35
#ISCELL
  mstr_standard tap *
  page47_i36
#ISCELL
  mstr_standard tap *
  page47_i37
#ISCELL
  mstr_standard tap *
  page47_i38
#ISCELL
  mstr_standard tap *
  page47_i39
#ISCELL
  mstr_standard tap *
  page47_i4
#ISCELL
  mstr_standard tap *
  page47_i40
#ISCELL
  mstr_standard tap *
  page47_i41
#CELL
  mstr_sconn sconn288_h44441004 *
  page47_i43
#ISCELL
  mstr_symbols gnd *
  page47_i44
#ISCELL
  mstr_standard offpage *
  page47_i45
#ISCELL
  mstr_standard tap *
  page47_i46
#ISCELL
  mstr_standard tap *
  page47_i47
#ISCELL
  mstr_standard tap *
  page47_i48
#ISCELL
  mstr_standard tap *
  page47_i49
#ISCELL
  mstr_standard tap *
  page47_i5
#ISCELL
  mstr_standard tap *
  page47_i50
#ISCELL
  mstr_standard tap *
  page47_i51
#ISCELL
  mstr_standard tap *
  page47_i52
#ISCELL
  mstr_standard tap *
  page47_i53
#ISCELL
  mstr_standard tap *
  page47_i54
#ISCELL
  mstr_standard tap *
  page47_i55
#ISCELL
  mstr_standard tap *
  page47_i56
#ISCELL
  mstr_standard tap *
  page47_i57
#ISCELL
  mstr_standard tap *
  page47_i58
#ISCELL
  mstr_standard tap *
  page47_i59
#ISCELL
  mstr_standard tap *
  page47_i6
#ISCELL
  mstr_standard tap *
  page47_i60
#CELL
  mstr_sconn sconn288_h44441004 *
  page47_i61
#ISCELL
  mstr_standard tap *
  page47_i62
#ISCELL
  mstr_standard tap *
  page47_i63
#ISCELL
  mstr_standard tap *
  page47_i64
#ISCELL
  mstr_standard tap *
  page47_i65
#ISCELL
  mstr_standard tap *
  page47_i66
#ISCELL
  mstr_standard tap *
  page47_i67
#ISCELL
  mstr_standard tap *
  page47_i68
#ISCELL
  mstr_standard tap *
  page47_i69
#ISCELL
  mstr_standard tap *
  page47_i7
#ISCELL
  mstr_standard tap *
  page47_i70
#ISCELL
  mstr_standard tap *
  page47_i71
#ISCELL
  mstr_standard tap *
  page47_i72
#ISCELL
  mstr_standard tap *
  page47_i73
#ISCELL
  mstr_standard tap *
  page47_i74
#ISCELL
  mstr_standard tap *
  page47_i75
#ISCELL
  mstr_standard tap *
  page47_i76
#ISCELL
  mstr_standard tap *
  page47_i77
#ISCELL
  mstr_standard tap *
  page47_i78
#ISCELL
  mstr_standard tap *
  page47_i79
#ISCELL
  mstr_standard tap *
  page47_i8
#ISCELL
  mstr_standard tap *
  page47_i80
#ISCELL
  mstr_standard tap *
  page47_i81
#ISCELL
  mstr_standard tap *
  page47_i82
#ISCELL
  mstr_standard tap *
  page47_i83
#ISCELL
  mstr_standard tap *
  page47_i84
#ISCELL
  mstr_standard tap *
  page47_i85
#ISCELL
  mstr_standard tap *
  page47_i86
#ISCELL
  mstr_standard tap *
  page47_i87
#ISCELL
  mstr_standard tap *
  page47_i88
#ISCELL
  mstr_standard tap *
  page47_i89
#ISCELL
  mstr_standard tap *
  page47_i9
#ISCELL
  mstr_standard tap *
  page47_i90
#ISCELL
  mstr_standard tap *
  page47_i91
#ISCELL
  mstr_standard tap *
  page47_i92
#ISCELL
  mstr_standard tap *
  page47_i93
#ISCELL
  mstr_standard tap *
  page47_i94
#ISCELL
  mstr_standard tap *
  page47_i95
#ISCELL
  mstr_standard tap *
  page47_i96
#ISCELL
  mstr_standard tap *
  page47_i97
#ISCELL
  mstr_standard tap *
  page47_i98
#ISCELL
  mstr_standard tap *
  page47_i99
#ISCELL
  mstr_symbols bom_note *
  *
#ISCELL
  mstr_symbols intel_corp_bpage *
  *
#ISCELL
  mstr_standard offpage *
  page48_i1
#ISCELL
  mstr_standard tap *
  page48_i10
#ISCELL
  mstr_standard tap *
  page48_i100
#ISCELL
  mstr_standard tap *
  page48_i101
#ISCELL
  mstr_standard tap *
  page48_i102
#ISCELL
  mstr_standard tap *
  page48_i103
#ISCELL
  mstr_standard tap *
  page48_i104
#ISCELL
  mstr_standard tap *
  page48_i105
#ISCELL
  mstr_standard tap *
  page48_i106
#ISCELL
  mstr_standard tap *
  page48_i107
#ISCELL
  mstr_standard tap *
  page48_i108
#ISCELL
  mstr_standard tap *
  page48_i109
#ISCELL
  mstr_standard tap *
  page48_i110
#CELL
  mstr_sconn sconn288_h44441003 *
  page48_i111
#ISCELL
  mstr_standard tap *
  page48_i112
#ISCELL
  mstr_standard tap *
  page48_i113
#ISCELL
  mstr_standard tap *
  page48_i114
#ISCELL
  mstr_standard tap *
  page48_i115
#ISCELL
  mstr_standard tap *
  page48_i116
#ISCELL
  mstr_standard tap *
  page48_i117
#ISCELL
  mstr_standard tap *
  page48_i118
#ISCELL
  mstr_standard tap *
  page48_i119
#ISCELL
  mstr_symbols pvtt_abc *
  page48_i12
#ISCELL
  mstr_standard tap *
  page48_i120
#ISCELL
  mstr_standard tap *
  page48_i121
#ISCELL
  mstr_standard tap *
  page48_i122
#ISCELL
  mstr_standard tap *
  page48_i123
#ISCELL
  mstr_standard tap *
  page48_i124
#ISCELL
  mstr_standard tap *
  page48_i125
#ISCELL
  mstr_standard tap *
  page48_i126
#ISCELL
  mstr_standard offpage *
  page48_i127
#ISCELL
  mstr_standard tap *
  page48_i128
#ISCELL
  mstr_standard tap *
  page48_i129
#ISCELL
  mstr_symbols pvddq_abc *
  page48_i13
#ISCELL
  mstr_standard tap *
  page48_i130
#ISCELL
  mstr_standard tap *
  page48_i131
#ISCELL
  mstr_standard tap *
  page48_i132
#ISCELL
  mstr_standard tap *
  page48_i133
#ISCELL
  mstr_standard tap *
  page48_i134
#ISCELL
  mstr_standard offpage *
  page48_i135
#ISCELL
  mstr_standard offpage *
  page48_i136
#ISCELL
  mstr_standard offpage *
  page48_i137
#ISCELL
  mstr_standard tap *
  page48_i138
#ISCELL
  mstr_standard tap *
  page48_i139
#ISCELL
  mstr_standard tap *
  page48_i14
#ISCELL
  mstr_standard tap *
  page48_i140
#ISCELL
  mstr_standard tap *
  page48_i141
#ISCELL
  mstr_standard tap *
  page48_i142
#ISCELL
  mstr_standard tap *
  page48_i143
#ISCELL
  mstr_standard tap *
  page48_i144
#ISCELL
  mstr_standard tap *
  page48_i145
#ISCELL
  mstr_standard offpage *
  page48_i146
#ISCELL
  mstr_standard offpage *
  page48_i147
#ISCELL
  mstr_standard offpage *
  page48_i148
#ISCELL
  mstr_standard offpage *
  page48_i149
#ISCELL
  mstr_standard tap *
  page48_i15
#ISCELL
  mstr_standard offpage *
  page48_i150
#ISCELL
  mstr_standard offpage *
  page48_i151
#ISCELL
  mstr_standard tap *
  page48_i152
#ISCELL
  mstr_standard offpage *
  page48_i153
#ISCELL
  mstr_standard tap *
  page48_i154
#ISCELL
  mstr_standard tap *
  page48_i155
#ISCELL
  mstr_standard offpage *
  page48_i156
#ISCELL
  mstr_standard tap *
  page48_i157
#ISCELL
  mstr_standard tap *
  page48_i158
#ISCELL
  mstr_standard tap *
  page48_i159
#ISCELL
  mstr_standard tap *
  page48_i16
#ISCELL
  mstr_standard tap *
  page48_i160
#ISCELL
  mstr_standard tap *
  page48_i161
#ISCELL
  mstr_standard offpage *
  page48_i162
#ISCELL
  mstr_standard tap *
  page48_i163
#ISCELL
  mstr_standard tap *
  page48_i164
#ISCELL
  mstr_standard tap *
  page48_i165
#ISCELL
  mstr_standard tap *
  page48_i166
#ISCELL
  mstr_standard offpage *
  page48_i167
#ISCELL
  mstr_standard offpage *
  page48_i168
#ISCELL
  mstr_standard offpage *
  page48_i169
#ISCELL
  mstr_standard tap *
  page48_i17
#ISCELL
  mstr_standard offpage *
  page48_i170
#CELL
  mstr_sconn sconn288_h44441003 *
  page48_i171
#ISCELL
  mstr_symbols gnd *
  page48_i172
#ISCELL
  mstr_standard offpage *
  page48_i173
#CELL
  dev_discrete cap_a *
  page48_i176
#ISCELL
  mstr_symbols gnd *
  page48_i177
#ISCELL
  mstr_symbols pvpp_abc *
  page48_i178
#ISCELL
  mstr_symbols pvpp_abc *
  page48_i179
#ISCELL
  mstr_standard tap *
  page48_i18
#ISCELL
  mstr_standard offpage *
  page48_i180
#ISCELL
  mstr_symbols gnd *
  page48_i184
#ISCELL
  mstr_symbols p12v_nvdimm_abc *
  page48_i185
#ISCELL
  mstr_standard tap *
  page48_i19
#ISCELL
  mstr_standard offpage *
  page48_i2
#ISCELL
  mstr_standard tap *
  page48_i20
#ISCELL
  mstr_standard tap *
  page48_i21
#ISCELL
  mstr_standard tap *
  page48_i22
#ISCELL
  mstr_standard tap *
  page48_i23
#ISCELL
  mstr_standard tap *
  page48_i24
#ISCELL
  mstr_standard tap *
  page48_i25
#ISCELL
  mstr_standard tap *
  page48_i26
#ISCELL
  mstr_standard tap *
  page48_i27
#ISCELL
  mstr_standard tap *
  page48_i28
#ISCELL
  mstr_standard tap *
  page48_i29
#ISCELL
  mstr_standard tap *
  page48_i3
#ISCELL
  mstr_standard tap *
  page48_i30
#ISCELL
  mstr_standard tap *
  page48_i31
#ISCELL
  mstr_standard tap *
  page48_i32
#ISCELL
  mstr_standard tap *
  page48_i33
#ISCELL
  mstr_standard tap *
  page48_i34
#ISCELL
  mstr_standard tap *
  page48_i35
#ISCELL
  mstr_standard tap *
  page48_i36
#ISCELL
  mstr_standard tap *
  page48_i37
#ISCELL
  mstr_standard tap *
  page48_i38
#ISCELL
  mstr_standard tap *
  page48_i39
#ISCELL
  mstr_standard tap *
  page48_i4
#ISCELL
  mstr_standard tap *
  page48_i40
#ISCELL
  mstr_standard tap *
  page48_i41
#CELL
  mstr_sconn sconn288_h44441003 *
  page48_i43
#ISCELL
  mstr_symbols gnd *
  page48_i44
#ISCELL
  mstr_standard offpage *
  page48_i45
#ISCELL
  mstr_standard tap *
  page48_i46
#ISCELL
  mstr_standard tap *
  page48_i47
#ISCELL
  mstr_standard tap *
  page48_i48
#ISCELL
  mstr_standard tap *
  page48_i49
#ISCELL
  mstr_standard tap *
  page48_i5
#ISCELL
  mstr_standard tap *
  page48_i50
#ISCELL
  mstr_standard tap *
  page48_i51
#ISCELL
  mstr_standard tap *
  page48_i52
#ISCELL
  mstr_standard tap *
  page48_i53
#ISCELL
  mstr_standard tap *
  page48_i54
#ISCELL
  mstr_standard tap *
  page48_i55
#ISCELL
  mstr_standard tap *
  page48_i56
#ISCELL
  mstr_standard tap *
  page48_i57
#ISCELL
  mstr_standard tap *
  page48_i58
#ISCELL
  mstr_standard tap *
  page48_i59
#ISCELL
  mstr_standard tap *
  page48_i6
#ISCELL
  mstr_standard tap *
  page48_i60
#CELL
  mstr_sconn sconn288_h44441003 *
  page48_i61
#ISCELL
  mstr_standard tap *
  page48_i62
#ISCELL
  mstr_standard tap *
  page48_i63
#ISCELL
  mstr_standard tap *
  page48_i64
#ISCELL
  mstr_standard tap *
  page48_i65
#ISCELL
  mstr_standard tap *
  page48_i66
#ISCELL
  mstr_standard tap *
  page48_i67
#ISCELL
  mstr_standard tap *
  page48_i68
#ISCELL
  mstr_standard tap *
  page48_i69
#ISCELL
  mstr_standard tap *
  page48_i7
#ISCELL
  mstr_standard tap *
  page48_i70
#ISCELL
  mstr_standard tap *
  page48_i71
#ISCELL
  mstr_standard tap *
  page48_i72
#ISCELL
  mstr_standard tap *
  page48_i73
#ISCELL
  mstr_standard tap *
  page48_i74
#ISCELL
  mstr_standard tap *
  page48_i75
#ISCELL
  mstr_standard tap *
  page48_i76
#ISCELL
  mstr_standard tap *
  page48_i77
#ISCELL
  mstr_standard tap *
  page48_i78
#ISCELL
  mstr_standard tap *
  page48_i79
#ISCELL
  mstr_standard tap *
  page48_i8
#ISCELL
  mstr_standard tap *
  page48_i80
#ISCELL
  mstr_standard tap *
  page48_i81
#ISCELL
  mstr_standard tap *
  page48_i82
#ISCELL
  mstr_standard tap *
  page48_i83
#ISCELL
  mstr_standard tap *
  page48_i84
#ISCELL
  mstr_standard tap *
  page48_i85
#ISCELL
  mstr_standard tap *
  page48_i86
#ISCELL
  mstr_standard tap *
  page48_i87
#ISCELL
  mstr_standard tap *
  page48_i88
#ISCELL
  mstr_standard tap *
  page48_i89
#ISCELL
  mstr_standard tap *
  page48_i9
#ISCELL
  mstr_standard tap *
  page48_i90
#ISCELL
  mstr_standard tap *
  page48_i91
#ISCELL
  mstr_standard tap *
  page48_i92
#ISCELL
  mstr_standard tap *
  page48_i93
#ISCELL
  mstr_standard tap *
  page48_i94
#ISCELL
  mstr_standard tap *
  page48_i95
#ISCELL
  mstr_standard tap *
  page48_i96
#ISCELL
  mstr_standard tap *
  page48_i97
#ISCELL
  mstr_standard tap *
  page48_i98
#ISCELL
  mstr_standard tap *
  page48_i99
#ISCELL
  mstr_symbols bom_note *
  *
#ISCELL
  mstr_symbols intel_corp_bpage *
  *
#ISCELL
  mstr_standard offpage *
  page49_i1
#ISCELL
  mstr_standard tap *
  page49_i10
#ISCELL
  mstr_standard tap *
  page49_i100
#ISCELL
  mstr_standard tap *
  page49_i101
#ISCELL
  mstr_standard tap *
  page49_i102
#ISCELL
  mstr_standard tap *
  page49_i103
#ISCELL
  mstr_standard tap *
  page49_i104
#ISCELL
  mstr_standard tap *
  page49_i105
#ISCELL
  mstr_standard tap *
  page49_i106
#ISCELL
  mstr_standard tap *
  page49_i107
#ISCELL
  mstr_standard tap *
  page49_i108
#ISCELL
  mstr_standard tap *
  page49_i109
#ISCELL
  mstr_standard tap *
  page49_i11
#ISCELL
  mstr_standard tap *
  page49_i110
#CELL
  mstr_sconn sconn288_h44441004 *
  page49_i111
#ISCELL
  mstr_standard tap *
  page49_i112
#ISCELL
  mstr_standard tap *
  page49_i113
#ISCELL
  mstr_standard tap *
  page49_i114
#ISCELL
  mstr_standard tap *
  page49_i115
#ISCELL
  mstr_standard tap *
  page49_i116
#ISCELL
  mstr_standard tap *
  page49_i117
#ISCELL
  mstr_standard tap *
  page49_i118
#ISCELL
  mstr_standard tap *
  page49_i119
#ISCELL
  mstr_standard tap *
  page49_i12
#ISCELL
  mstr_standard tap *
  page49_i120
#ISCELL
  mstr_standard tap *
  page49_i121
#ISCELL
  mstr_standard tap *
  page49_i122
#ISCELL
  mstr_standard tap *
  page49_i123
#ISCELL
  mstr_standard tap *
  page49_i124
#ISCELL
  mstr_standard tap *
  page49_i125
#ISCELL
  mstr_standard tap *
  page49_i126
#ISCELL
  mstr_standard tap *
  page49_i127
#ISCELL
  mstr_standard tap *
  page49_i128
#ISCELL
  mstr_standard tap *
  page49_i129
#ISCELL
  mstr_standard tap *
  page49_i13
#ISCELL
  mstr_standard tap *
  page49_i130
#ISCELL
  mstr_standard offpage *
  page49_i131
#ISCELL
  mstr_standard offpage *
  page49_i132
#ISCELL
  mstr_standard tap *
  page49_i133
#ISCELL
  mstr_standard tap *
  page49_i134
#ISCELL
  mstr_standard tap *
  page49_i135
#ISCELL
  mstr_standard offpage *
  page49_i136
#ISCELL
  mstr_standard offpage *
  page49_i137
#ISCELL
  mstr_standard tap *
  page49_i138
#ISCELL
  mstr_standard tap *
  page49_i139
#ISCELL
  mstr_standard tap *
  page49_i14
#ISCELL
  mstr_standard tap *
  page49_i140
#ISCELL
  mstr_standard tap *
  page49_i141
#ISCELL
  mstr_standard tap *
  page49_i142
#ISCELL
  mstr_standard tap *
  page49_i143
#ISCELL
  mstr_standard tap *
  page49_i144
#ISCELL
  mstr_standard tap *
  page49_i145
#ISCELL
  mstr_standard offpage *
  page49_i146
#ISCELL
  mstr_standard offpage *
  page49_i147
#ISCELL
  mstr_standard offpage *
  page49_i148
#ISCELL
  mstr_standard offpage *
  page49_i149
#ISCELL
  mstr_standard tap *
  page49_i15
#ISCELL
  mstr_standard offpage *
  page49_i150
#ISCELL
  mstr_standard offpage *
  page49_i151
#ISCELL
  mstr_standard tap *
  page49_i152
#ISCELL
  mstr_standard tap *
  page49_i153
#ISCELL
  mstr_standard tap *
  page49_i154
#ISCELL
  mstr_standard tap *
  page49_i155
#ISCELL
  mstr_standard offpage *
  page49_i156
#ISCELL
  mstr_standard offpage *
  page49_i157
#ISCELL
  mstr_standard tap *
  page49_i158
#ISCELL
  mstr_standard tap *
  page49_i159
#ISCELL
  mstr_symbols pvddq_def *
  page49_i16
#ISCELL
  mstr_standard tap *
  page49_i160
#ISCELL
  mstr_standard tap *
  page49_i161
#ISCELL
  mstr_standard tap *
  page49_i162
#ISCELL
  mstr_standard tap *
  page49_i163
#ISCELL
  mstr_standard offpage *
  page49_i164
#ISCELL
  mstr_standard offpage *
  page49_i165
#ISCELL
  mstr_standard offpage *
  page49_i166
#ISCELL
  mstr_standard tap *
  page49_i167
#ISCELL
  mstr_standard tap *
  page49_i168
#CELL
  mstr_sconn sconn288_h44441004 *
  page49_i169
#ISCELL
  mstr_symbols pvtt_def *
  page49_i170
#ISCELL
  mstr_symbols gnd *
  page49_i171
#ISCELL
  mstr_standard offpage *
  page49_i174
#ISCELL
  mstr_standard offpage *
  page49_i175
#ISCELL
  mstr_standard offpage *
  page49_i176
#ISCELL
  mstr_symbols gnd *
  page49_i178
#CELL
  dev_discrete cap_a *
  page49_i179
#ISCELL
  mstr_symbols gnd *
  page49_i180
#ISCELL
  mstr_symbols pvpp_def *
  page49_i181
#ISCELL
  mstr_symbols pvpp_def *
  page49_i182
#ISCELL
  mstr_standard offpage *
  page49_i183
#ISCELL
  mstr_symbols p12v_nvdimm_def *
  page49_i184
#ISCELL
  mstr_standard tap *
  page49_i19
#ISCELL
  mstr_standard offpage *
  page49_i2
#ISCELL
  mstr_standard tap *
  page49_i20
#ISCELL
  mstr_standard tap *
  page49_i21
#ISCELL
  mstr_standard tap *
  page49_i22
#ISCELL
  mstr_standard tap *
  page49_i23
#ISCELL
  mstr_standard tap *
  page49_i24
#ISCELL
  mstr_standard tap *
  page49_i25
#ISCELL
  mstr_standard tap *
  page49_i26
#ISCELL
  mstr_standard tap *
  page49_i27
#ISCELL
  mstr_standard tap *
  page49_i28
#ISCELL
  mstr_standard tap *
  page49_i29
#ISCELL
  mstr_standard tap *
  page49_i3
#ISCELL
  mstr_standard tap *
  page49_i30
#ISCELL
  mstr_standard tap *
  page49_i31
#ISCELL
  mstr_standard tap *
  page49_i32
#ISCELL
  mstr_standard tap *
  page49_i33
#ISCELL
  mstr_standard tap *
  page49_i34
#ISCELL
  mstr_standard tap *
  page49_i35
#ISCELL
  mstr_standard tap *
  page49_i36
#ISCELL
  mstr_standard tap *
  page49_i37
#ISCELL
  mstr_standard tap *
  page49_i38
#ISCELL
  mstr_standard tap *
  page49_i39
#ISCELL
  mstr_standard tap *
  page49_i4
#ISCELL
  mstr_standard tap *
  page49_i40
#ISCELL
  mstr_standard tap *
  page49_i41
#CELL
  mstr_sconn sconn288_h44441004 *
  page49_i43
#ISCELL
  mstr_symbols gnd *
  page49_i44
#ISCELL
  mstr_standard offpage *
  page49_i45
#ISCELL
  mstr_standard tap *
  page49_i46
#ISCELL
  mstr_standard tap *
  page49_i47
#ISCELL
  mstr_standard tap *
  page49_i48
#ISCELL
  mstr_standard tap *
  page49_i49
#ISCELL
  mstr_standard tap *
  page49_i5
#ISCELL
  mstr_standard tap *
  page49_i50
#ISCELL
  mstr_standard tap *
  page49_i51
#ISCELL
  mstr_standard tap *
  page49_i52
#ISCELL
  mstr_standard tap *
  page49_i53
#ISCELL
  mstr_standard tap *
  page49_i54
#ISCELL
  mstr_standard tap *
  page49_i55
#ISCELL
  mstr_standard tap *
  page49_i56
#ISCELL
  mstr_standard tap *
  page49_i57
#ISCELL
  mstr_standard tap *
  page49_i58
#ISCELL
  mstr_standard tap *
  page49_i59
#ISCELL
  mstr_standard tap *
  page49_i6
#ISCELL
  mstr_standard tap *
  page49_i60
#ISCELL
  mstr_standard tap *
  page49_i61
#ISCELL
  mstr_standard tap *
  page49_i62
#ISCELL
  mstr_standard tap *
  page49_i63
#ISCELL
  mstr_standard tap *
  page49_i64
#ISCELL
  mstr_standard tap *
  page49_i65
#CELL
  mstr_sconn sconn288_h44441004 *
  page49_i66
#ISCELL
  mstr_standard tap *
  page49_i67
#ISCELL
  mstr_standard tap *
  page49_i68
#ISCELL
  mstr_standard tap *
  page49_i69
#ISCELL
  mstr_standard tap *
  page49_i7
#ISCELL
  mstr_standard tap *
  page49_i70
#ISCELL
  mstr_standard tap *
  page49_i71
#ISCELL
  mstr_standard tap *
  page49_i72
#ISCELL
  mstr_standard tap *
  page49_i73
#ISCELL
  mstr_standard tap *
  page49_i74
#ISCELL
  mstr_standard tap *
  page49_i75
#ISCELL
  mstr_standard tap *
  page49_i76
#ISCELL
  mstr_standard tap *
  page49_i77
#ISCELL
  mstr_standard tap *
  page49_i78
#ISCELL
  mstr_standard tap *
  page49_i79
#ISCELL
  mstr_standard tap *
  page49_i8
#ISCELL
  mstr_standard tap *
  page49_i80
#ISCELL
  mstr_standard tap *
  page49_i81
#ISCELL
  mstr_standard tap *
  page49_i82
#ISCELL
  mstr_standard tap *
  page49_i83
#ISCELL
  mstr_standard tap *
  page49_i84
#ISCELL
  mstr_standard tap *
  page49_i85
#ISCELL
  mstr_standard tap *
  page49_i86
#ISCELL
  mstr_standard tap *
  page49_i87
#ISCELL
  mstr_standard tap *
  page49_i88
#ISCELL
  mstr_standard tap *
  page49_i89
#ISCELL
  mstr_standard tap *
  page49_i9
#ISCELL
  mstr_standard tap *
  page49_i90
#ISCELL
  mstr_standard tap *
  page49_i91
#ISCELL
  mstr_standard tap *
  page49_i92
#ISCELL
  mstr_standard tap *
  page49_i93
#ISCELL
  mstr_standard tap *
  page49_i94
#ISCELL
  mstr_standard tap *
  page49_i95
#ISCELL
  mstr_standard tap *
  page49_i96
#ISCELL
  mstr_standard tap *
  page49_i97
#ISCELL
  mstr_standard tap *
  page49_i98
#ISCELL
  mstr_standard tap *
  page49_i99
#ISCELL
  mstr_symbols bom_note *
  *
#ISCELL
  mstr_symbols intel_corp_bpage *
  *
#ISCELL
  mstr_symbols gnd *
  page50_i1
#ISCELL
  mstr_standard tap *
  page50_i10
#ISCELL
  mstr_standard tap *
  page50_i100
#ISCELL
  mstr_standard tap *
  page50_i101
#ISCELL
  mstr_standard tap *
  page50_i102
#ISCELL
  mstr_standard tap *
  page50_i103
#ISCELL
  mstr_standard tap *
  page50_i104
#ISCELL
  mstr_standard tap *
  page50_i105
#ISCELL
  mstr_standard tap *
  page50_i106
#ISCELL
  mstr_standard tap *
  page50_i107
#ISCELL
  mstr_standard tap *
  page50_i108
#ISCELL
  mstr_standard tap *
  page50_i109
#ISCELL
  mstr_standard tap *
  page50_i11
#ISCELL
  mstr_standard tap *
  page50_i110
#ISCELL
  mstr_standard tap *
  page50_i111
#ISCELL
  mstr_standard tap *
  page50_i112
#ISCELL
  mstr_standard tap *
  page50_i113
#ISCELL
  mstr_standard tap *
  page50_i114
#ISCELL
  mstr_standard tap *
  page50_i115
#ISCELL
  mstr_standard tap *
  page50_i116
#ISCELL
  mstr_standard tap *
  page50_i117
#ISCELL
  mstr_standard tap *
  page50_i118
#ISCELL
  mstr_standard tap *
  page50_i119
#ISCELL
  mstr_standard tap *
  page50_i12
#ISCELL
  mstr_standard tap *
  page50_i120
#ISCELL
  mstr_standard tap *
  page50_i121
#ISCELL
  mstr_standard tap *
  page50_i122
#ISCELL
  mstr_standard tap *
  page50_i123
#ISCELL
  mstr_standard tap *
  page50_i124
#ISCELL
  mstr_standard tap *
  page50_i125
#ISCELL
  mstr_standard tap *
  page50_i126
#ISCELL
  mstr_standard tap *
  page50_i127
#ISCELL
  mstr_standard tap *
  page50_i128
#ISCELL
  mstr_standard tap *
  page50_i129
#ISCELL
  mstr_standard tap *
  page50_i13
#ISCELL
  mstr_standard tap *
  page50_i130
#ISCELL
  mstr_standard tap *
  page50_i131
#ISCELL
  mstr_standard tap *
  page50_i132
#ISCELL
  mstr_standard tap *
  page50_i133
#ISCELL
  mstr_standard tap *
  page50_i134
#ISCELL
  mstr_standard tap *
  page50_i135
#ISCELL
  mstr_standard tap *
  page50_i136
#ISCELL
  mstr_standard tap *
  page50_i137
#ISCELL
  mstr_standard tap *
  page50_i138
#ISCELL
  mstr_standard tap *
  page50_i139
#ISCELL
  mstr_standard tap *
  page50_i14
#ISCELL
  mstr_standard tap *
  page50_i140
#ISCELL
  mstr_standard tap *
  page50_i141
#ISCELL
  mstr_standard tap *
  page50_i142
#ISCELL
  mstr_standard tap *
  page50_i143
#ISCELL
  mstr_standard tap *
  page50_i144
#ISCELL
  mstr_standard tap *
  page50_i145
#ISCELL
  mstr_standard tap *
  page50_i146
#ISCELL
  mstr_standard tap *
  page50_i147
#ISCELL
  mstr_standard tap *
  page50_i148
#ISCELL
  mstr_standard tap *
  page50_i149
#ISCELL
  mstr_standard tap *
  page50_i15
#ISCELL
  mstr_standard tap *
  page50_i150
#ISCELL
  mstr_standard tap *
  page50_i151
#ISCELL
  mstr_standard tap *
  page50_i152
#ISCELL
  mstr_standard tap *
  page50_i153
#ISCELL
  mstr_standard tap *
  page50_i154
#ISCELL
  mstr_standard tap *
  page50_i155
#ISCELL
  mstr_standard tap *
  page50_i156
#ISCELL
  mstr_standard tap *
  page50_i157
#CELL
  mstr_sconn sconn288_h44441003 *
  page50_i158
#ISCELL
  mstr_standard offpage *
  page50_i159
#ISCELL
  mstr_standard tap *
  page50_i16
#ISCELL
  mstr_standard offpage *
  page50_i160
#ISCELL
  mstr_standard offpage *
  page50_i161
#ISCELL
  mstr_standard offpage *
  page50_i162
#ISCELL
  mstr_standard offpage *
  page50_i163
#ISCELL
  mstr_standard offpage *
  page50_i164
#ISCELL
  mstr_standard offpage *
  page50_i165
#ISCELL
  mstr_standard offpage *
  page50_i166
#ISCELL
  mstr_standard offpage *
  page50_i167
#ISCELL
  mstr_standard offpage *
  page50_i168
#ISCELL
  mstr_standard offpage *
  page50_i169
#ISCELL
  mstr_standard tap *
  page50_i17
#ISCELL
  mstr_standard offpage *
  page50_i170
#ISCELL
  mstr_standard offpage *
  page50_i171
#ISCELL
  mstr_symbols pvpp_def *
  page50_i172
#ISCELL
  mstr_standard offpage *
  page50_i173
#ISCELL
  mstr_standard offpage *
  page50_i174
#ISCELL
  mstr_standard offpage *
  page50_i175
#ISCELL
  mstr_standard offpage *
  page50_i176
#CELL
  dev_discrete cap_a *
  page50_i177
#ISCELL
  mstr_symbols gnd *
  page50_i178
#ISCELL
  mstr_standard offpage *
  page50_i179
#ISCELL
  mstr_standard tap *
  page50_i18
#ISCELL
  mstr_symbols gnd *
  page50_i180
#ISCELL
  mstr_symbols p12v_nvdimm_def *
  page50_i181
#ISCELL
  mstr_standard offpage *
  page50_i19
#ISCELL
  mstr_standard offpage *
  page50_i2
#ISCELL
  mstr_standard tap *
  page50_i20
#ISCELL
  mstr_standard tap *
  page50_i21
#ISCELL
  mstr_standard tap *
  page50_i22
#ISCELL
  mstr_standard tap *
  page50_i23
#ISCELL
  mstr_standard tap *
  page50_i24
#ISCELL
  mstr_standard tap *
  page50_i25
#ISCELL
  mstr_standard tap *
  page50_i26
#ISCELL
  mstr_standard tap *
  page50_i27
#ISCELL
  mstr_standard tap *
  page50_i28
#ISCELL
  mstr_standard tap *
  page50_i29
#ISCELL
  mstr_standard offpage *
  page50_i3
#ISCELL
  mstr_standard tap *
  page50_i30
#ISCELL
  mstr_standard tap *
  page50_i31
#ISCELL
  mstr_standard tap *
  page50_i32
#ISCELL
  mstr_standard tap *
  page50_i33
#ISCELL
  mstr_standard tap *
  page50_i34
#ISCELL
  mstr_standard tap *
  page50_i35
#ISCELL
  mstr_standard tap *
  page50_i36
#ISCELL
  mstr_standard tap *
  page50_i37
#ISCELL
  mstr_standard tap *
  page50_i38
#ISCELL
  mstr_standard tap *
  page50_i39
#ISCELL
  mstr_standard tap *
  page50_i4
#ISCELL
  mstr_standard tap *
  page50_i40
#CELL
  mstr_sconn sconn288_h44441003 *
  page50_i44
#ISCELL
  mstr_symbols gnd *
  page50_i45
#CELL
  mstr_sconn sconn288_h44441003 *
  page50_i46
#ISCELL
  mstr_symbols pvpp_def *
  page50_i47
#ISCELL
  mstr_symbols pvtt_def *
  page50_i48
#ISCELL
  mstr_symbols pvddq_def *
  page50_i49
#ISCELL
  mstr_standard tap *
  page50_i5
#CELL
  mstr_sconn sconn288_h44441003 *
  page50_i50
#ISCELL
  mstr_standard tap *
  page50_i51
#ISCELL
  mstr_standard tap *
  page50_i52
#ISCELL
  mstr_standard tap *
  page50_i53
#ISCELL
  mstr_standard tap *
  page50_i54
#ISCELL
  mstr_standard tap *
  page50_i55
#ISCELL
  mstr_standard tap *
  page50_i56
#ISCELL
  mstr_standard tap *
  page50_i57
#ISCELL
  mstr_standard tap *
  page50_i58
#ISCELL
  mstr_standard tap *
  page50_i59
#ISCELL
  mstr_standard tap *
  page50_i6
#ISCELL
  mstr_standard tap *
  page50_i60
#ISCELL
  mstr_standard tap *
  page50_i61
#ISCELL
  mstr_standard tap *
  page50_i62
#ISCELL
  mstr_standard tap *
  page50_i63
#ISCELL
  mstr_standard tap *
  page50_i64
#ISCELL
  mstr_standard tap *
  page50_i65
#ISCELL
  mstr_standard tap *
  page50_i66
#ISCELL
  mstr_standard tap *
  page50_i67
#ISCELL
  mstr_standard tap *
  page50_i68
#ISCELL
  mstr_standard tap *
  page50_i69
#ISCELL
  mstr_standard tap *
  page50_i7
#ISCELL
  mstr_standard tap *
  page50_i70
#ISCELL
  mstr_standard tap *
  page50_i71
#ISCELL
  mstr_standard tap *
  page50_i72
#ISCELL
  mstr_standard tap *
  page50_i73
#ISCELL
  mstr_standard tap *
  page50_i74
#ISCELL
  mstr_standard tap *
  page50_i75
#ISCELL
  mstr_standard tap *
  page50_i76
#ISCELL
  mstr_standard tap *
  page50_i77
#ISCELL
  mstr_standard tap *
  page50_i78
#ISCELL
  mstr_standard offpage *
  page50_i79
#ISCELL
  mstr_standard tap *
  page50_i8
#ISCELL
  mstr_standard tap *
  page50_i80
#ISCELL
  mstr_standard tap *
  page50_i81
#ISCELL
  mstr_standard tap *
  page50_i82
#ISCELL
  mstr_standard tap *
  page50_i83
#ISCELL
  mstr_standard tap *
  page50_i84
#ISCELL
  mstr_standard tap *
  page50_i85
#ISCELL
  mstr_standard tap *
  page50_i86
#ISCELL
  mstr_standard tap *
  page50_i87
#ISCELL
  mstr_standard tap *
  page50_i88
#ISCELL
  mstr_standard tap *
  page50_i89
#ISCELL
  mstr_standard tap *
  page50_i9
#ISCELL
  mstr_standard tap *
  page50_i90
#ISCELL
  mstr_standard tap *
  page50_i91
#ISCELL
  mstr_standard tap *
  page50_i92
#ISCELL
  mstr_standard tap *
  page50_i93
#ISCELL
  mstr_standard tap *
  page50_i94
#ISCELL
  mstr_standard tap *
  page50_i95
#ISCELL
  mstr_standard tap *
  page50_i96
#ISCELL
  mstr_standard tap *
  page50_i97
#ISCELL
  mstr_standard tap *
  page50_i98
#ISCELL
  mstr_standard tap *
  page50_i99
#ISCELL
  mstr_symbols bom_note *
  *
#ISCELL
  mstr_symbols intel_corp_bpage *
  *
#ISCELL
  mstr_standard offpage *
  page51_i1
#ISCELL
  mstr_standard tap *
  page51_i10
#ISCELL
  mstr_standard tap *
  page51_i100
#ISCELL
  mstr_standard tap *
  page51_i101
#ISCELL
  mstr_standard tap *
  page51_i102
#ISCELL
  mstr_standard tap *
  page51_i103
#ISCELL
  mstr_standard tap *
  page51_i104
#ISCELL
  mstr_standard tap *
  page51_i105
#ISCELL
  mstr_standard tap *
  page51_i106
#ISCELL
  mstr_standard tap *
  page51_i107
#ISCELL
  mstr_standard tap *
  page51_i108
#ISCELL
  mstr_standard tap *
  page51_i109
#ISCELL
  mstr_standard tap *
  page51_i11
#ISCELL
  mstr_standard tap *
  page51_i110
#CELL
  mstr_sconn sconn288_h44441004 *
  page51_i111
#ISCELL
  mstr_standard tap *
  page51_i112
#ISCELL
  mstr_standard tap *
  page51_i113
#ISCELL
  mstr_standard tap *
  page51_i114
#ISCELL
  mstr_standard tap *
  page51_i115
#ISCELL
  mstr_standard tap *
  page51_i116
#ISCELL
  mstr_standard tap *
  page51_i117
#ISCELL
  mstr_standard tap *
  page51_i118
#ISCELL
  mstr_standard tap *
  page51_i119
#ISCELL
  mstr_standard tap *
  page51_i12
#ISCELL
  mstr_standard tap *
  page51_i120
#ISCELL
  mstr_standard tap *
  page51_i121
#ISCELL
  mstr_standard tap *
  page51_i122
#ISCELL
  mstr_standard tap *
  page51_i123
#ISCELL
  mstr_standard tap *
  page51_i124
#ISCELL
  mstr_standard tap *
  page51_i125
#ISCELL
  mstr_standard tap *
  page51_i126
#ISCELL
  mstr_standard tap *
  page51_i127
#ISCELL
  mstr_standard tap *
  page51_i128
#ISCELL
  mstr_standard tap *
  page51_i129
#ISCELL
  mstr_standard tap *
  page51_i13
#ISCELL
  mstr_standard tap *
  page51_i130
#ISCELL
  mstr_standard offpage *
  page51_i131
#ISCELL
  mstr_standard offpage *
  page51_i132
#ISCELL
  mstr_standard tap *
  page51_i133
#ISCELL
  mstr_standard tap *
  page51_i134
#ISCELL
  mstr_standard tap *
  page51_i135
#ISCELL
  mstr_standard offpage *
  page51_i136
#ISCELL
  mstr_standard offpage *
  page51_i137
#ISCELL
  mstr_standard tap *
  page51_i138
#ISCELL
  mstr_standard tap *
  page51_i139
#ISCELL
  mstr_standard tap *
  page51_i14
#ISCELL
  mstr_standard tap *
  page51_i140
#ISCELL
  mstr_standard tap *
  page51_i141
#ISCELL
  mstr_standard tap *
  page51_i142
#ISCELL
  mstr_standard tap *
  page51_i143
#ISCELL
  mstr_standard tap *
  page51_i144
#ISCELL
  mstr_standard tap *
  page51_i145
#ISCELL
  mstr_standard offpage *
  page51_i146
#ISCELL
  mstr_standard offpage *
  page51_i147
#ISCELL
  mstr_standard offpage *
  page51_i148
#ISCELL
  mstr_standard offpage *
  page51_i149
#ISCELL
  mstr_standard tap *
  page51_i15
#ISCELL
  mstr_standard offpage *
  page51_i150
#ISCELL
  mstr_standard offpage *
  page51_i151
#ISCELL
  mstr_standard tap *
  page51_i152
#ISCELL
  mstr_standard tap *
  page51_i153
#ISCELL
  mstr_standard offpage *
  page51_i154
#ISCELL
  mstr_standard offpage *
  page51_i155
#ISCELL
  mstr_standard tap *
  page51_i156
#ISCELL
  mstr_standard tap *
  page51_i157
#ISCELL
  mstr_standard tap *
  page51_i158
#ISCELL
  mstr_standard tap *
  page51_i159
#ISCELL
  mstr_symbols pvddq_def *
  page51_i16
#ISCELL
  mstr_standard tap *
  page51_i160
#ISCELL
  mstr_standard offpage *
  page51_i161
#ISCELL
  mstr_standard offpage *
  page51_i162
#ISCELL
  mstr_standard tap *
  page51_i163
#ISCELL
  mstr_standard tap *
  page51_i164
#ISCELL
  mstr_standard offpage *
  page51_i165
#ISCELL
  mstr_standard tap *
  page51_i166
#CELL
  mstr_sconn sconn288_h44441004 *
  page51_i167
#ISCELL
  mstr_symbols gnd *
  page51_i168
#ISCELL
  mstr_standard offpage *
  page51_i169
#ISCELL
  mstr_symbols pvtt_def *
  page51_i17
#ISCELL
  mstr_standard offpage *
  page51_i171
#ISCELL
  mstr_standard offpage *
  page51_i172
#ISCELL
  mstr_symbols gnd *
  page51_i174
#CELL
  dev_discrete cap_a *
  page51_i175
#ISCELL
  mstr_symbols gnd *
  page51_i176
#ISCELL
  mstr_symbols pvpp_def *
  page51_i177
#ISCELL
  mstr_symbols pvpp_def *
  page51_i178
#ISCELL
  mstr_standard offpage *
  page51_i179
#ISCELL
  mstr_standard tap *
  page51_i183
#ISCELL
  mstr_standard tap *
  page51_i184
#ISCELL
  mstr_symbols p12v_nvdimm_def *
  page51_i185
#ISCELL
  mstr_standard tap *
  page51_i19
#ISCELL
  mstr_standard offpage *
  page51_i2
#ISCELL
  mstr_standard tap *
  page51_i20
#ISCELL
  mstr_standard tap *
  page51_i21
#ISCELL
  mstr_standard tap *
  page51_i22
#ISCELL
  mstr_standard tap *
  page51_i23
#ISCELL
  mstr_standard tap *
  page51_i24
#ISCELL
  mstr_standard tap *
  page51_i25
#ISCELL
  mstr_standard tap *
  page51_i26
#ISCELL
  mstr_standard tap *
  page51_i27
#ISCELL
  mstr_standard tap *
  page51_i28
#ISCELL
  mstr_standard tap *
  page51_i29
#ISCELL
  mstr_standard tap *
  page51_i3
#ISCELL
  mstr_standard tap *
  page51_i30
#ISCELL
  mstr_standard tap *
  page51_i31
#ISCELL
  mstr_standard tap *
  page51_i32
#ISCELL
  mstr_standard tap *
  page51_i33
#ISCELL
  mstr_standard tap *
  page51_i34
#ISCELL
  mstr_standard tap *
  page51_i35
#ISCELL
  mstr_standard tap *
  page51_i36
#ISCELL
  mstr_standard tap *
  page51_i37
#ISCELL
  mstr_standard tap *
  page51_i38
#ISCELL
  mstr_standard tap *
  page51_i39
#ISCELL
  mstr_standard tap *
  page51_i4
#ISCELL
  mstr_standard tap *
  page51_i40
#ISCELL
  mstr_standard tap *
  page51_i41
#CELL
  mstr_sconn sconn288_h44441004 *
  page51_i43
#ISCELL
  mstr_symbols gnd *
  page51_i44
#ISCELL
  mstr_standard offpage *
  page51_i45
#ISCELL
  mstr_standard tap *
  page51_i46
#ISCELL
  mstr_standard tap *
  page51_i47
#ISCELL
  mstr_standard tap *
  page51_i48
#ISCELL
  mstr_standard tap *
  page51_i49
#ISCELL
  mstr_standard tap *
  page51_i5
#ISCELL
  mstr_standard tap *
  page51_i50
#ISCELL
  mstr_standard tap *
  page51_i51
#ISCELL
  mstr_standard tap *
  page51_i52
#ISCELL
  mstr_standard tap *
  page51_i53
#ISCELL
  mstr_standard tap *
  page51_i54
#ISCELL
  mstr_standard tap *
  page51_i55
#ISCELL
  mstr_standard tap *
  page51_i56
#ISCELL
  mstr_standard tap *
  page51_i57
#ISCELL
  mstr_standard tap *
  page51_i58
#ISCELL
  mstr_standard tap *
  page51_i59
#ISCELL
  mstr_standard tap *
  page51_i6
#ISCELL
  mstr_standard tap *
  page51_i60
#ISCELL
  mstr_standard tap *
  page51_i61
#ISCELL
  mstr_standard tap *
  page51_i62
#ISCELL
  mstr_standard tap *
  page51_i63
#ISCELL
  mstr_standard tap *
  page51_i64
#ISCELL
  mstr_standard tap *
  page51_i65
#CELL
  mstr_sconn sconn288_h44441004 *
  page51_i66
#ISCELL
  mstr_standard tap *
  page51_i67
#ISCELL
  mstr_standard tap *
  page51_i68
#ISCELL
  mstr_standard tap *
  page51_i69
#ISCELL
  mstr_standard tap *
  page51_i7
#ISCELL
  mstr_standard tap *
  page51_i70
#ISCELL
  mstr_standard tap *
  page51_i71
#ISCELL
  mstr_standard tap *
  page51_i72
#ISCELL
  mstr_standard tap *
  page51_i73
#ISCELL
  mstr_standard tap *
  page51_i74
#ISCELL
  mstr_standard tap *
  page51_i75
#ISCELL
  mstr_standard tap *
  page51_i76
#ISCELL
  mstr_standard tap *
  page51_i77
#ISCELL
  mstr_standard tap *
  page51_i78
#ISCELL
  mstr_standard tap *
  page51_i79
#ISCELL
  mstr_standard tap *
  page51_i8
#ISCELL
  mstr_standard tap *
  page51_i80
#ISCELL
  mstr_standard tap *
  page51_i81
#ISCELL
  mstr_standard tap *
  page51_i82
#ISCELL
  mstr_standard tap *
  page51_i83
#ISCELL
  mstr_standard tap *
  page51_i84
#ISCELL
  mstr_standard tap *
  page51_i85
#ISCELL
  mstr_standard tap *
  page51_i86
#ISCELL
  mstr_standard tap *
  page51_i87
#ISCELL
  mstr_standard tap *
  page51_i88
#ISCELL
  mstr_standard tap *
  page51_i89
#ISCELL
  mstr_standard tap *
  page51_i9
#ISCELL
  mstr_standard tap *
  page51_i90
#ISCELL
  mstr_standard tap *
  page51_i91
#ISCELL
  mstr_standard tap *
  page51_i92
#ISCELL
  mstr_standard tap *
  page51_i93
#ISCELL
  mstr_standard tap *
  page51_i94
#ISCELL
  mstr_standard tap *
  page51_i95
#ISCELL
  mstr_standard tap *
  page51_i96
#ISCELL
  mstr_standard tap *
  page51_i97
#ISCELL
  mstr_standard tap *
  page51_i98
#ISCELL
  mstr_standard tap *
  page51_i99
#ISCELL
  mstr_symbols bom_note *
  *
#ISCELL
  mstr_symbols intel_corp_bpage *
  *
#ISCELL
  mstr_symbols gnd *
  page52_i1
#ISCELL
  mstr_standard offpage *
  page52_i10
#CELL
  mstr_sconn sconn288_h44441003 *
  page52_i100
#ISCELL
  mstr_standard offpage *
  page52_i101
#ISCELL
  mstr_standard tap *
  page52_i102
#ISCELL
  mstr_standard tap *
  page52_i103
#ISCELL
  mstr_standard tap *
  page52_i104
#ISCELL
  mstr_standard tap *
  page52_i105
#ISCELL
  mstr_standard tap *
  page52_i106
#ISCELL
  mstr_standard tap *
  page52_i107
#ISCELL
  mstr_standard tap *
  page52_i108
#ISCELL
  mstr_standard tap *
  page52_i109
#ISCELL
  mstr_standard offpage *
  page52_i11
#ISCELL
  mstr_standard tap *
  page52_i110
#ISCELL
  mstr_standard tap *
  page52_i111
#ISCELL
  mstr_standard tap *
  page52_i112
#ISCELL
  mstr_standard tap *
  page52_i113
#ISCELL
  mstr_standard tap *
  page52_i114
#ISCELL
  mstr_standard tap *
  page52_i115
#ISCELL
  mstr_standard tap *
  page52_i116
#ISCELL
  mstr_standard tap *
  page52_i117
#ISCELL
  mstr_standard tap *
  page52_i118
#ISCELL
  mstr_standard tap *
  page52_i119
#CELL
  mstr_sconn sconn288_h44441003 *
  page52_i12
#ISCELL
  mstr_standard tap *
  page52_i120
#ISCELL
  mstr_standard tap *
  page52_i121
#ISCELL
  mstr_standard tap *
  page52_i122
#ISCELL
  mstr_standard tap *
  page52_i123
#ISCELL
  mstr_standard tap *
  page52_i124
#ISCELL
  mstr_standard tap *
  page52_i125
#ISCELL
  mstr_standard tap *
  page52_i126
#ISCELL
  mstr_standard tap *
  page52_i127
#ISCELL
  mstr_standard tap *
  page52_i128
#ISCELL
  mstr_standard tap *
  page52_i129
#ISCELL
  mstr_standard offpage *
  page52_i13
#ISCELL
  mstr_standard tap *
  page52_i130
#ISCELL
  mstr_standard tap *
  page52_i131
#ISCELL
  mstr_standard tap *
  page52_i132
#ISCELL
  mstr_standard tap *
  page52_i133
#ISCELL
  mstr_standard tap *
  page52_i134
#ISCELL
  mstr_standard tap *
  page52_i135
#ISCELL
  mstr_standard offpage *
  page52_i136
#ISCELL
  mstr_symbols gnd *
  page52_i137
#CELL
  mstr_sconn sconn288_h44441003 *
  page52_i138
#ISCELL
  mstr_standard offpage *
  page52_i14
#ISCELL
  mstr_standard tap *
  page52_i142
#ISCELL
  mstr_standard tap *
  page52_i143
#ISCELL
  mstr_standard tap *
  page52_i144
#ISCELL
  mstr_standard tap *
  page52_i145
#ISCELL
  mstr_standard tap *
  page52_i146
#ISCELL
  mstr_standard tap *
  page52_i147
#ISCELL
  mstr_standard tap *
  page52_i148
#ISCELL
  mstr_standard tap *
  page52_i149
#ISCELL
  mstr_standard offpage *
  page52_i15
#ISCELL
  mstr_standard tap *
  page52_i150
#ISCELL
  mstr_standard tap *
  page52_i151
#ISCELL
  mstr_standard tap *
  page52_i152
#ISCELL
  mstr_standard tap *
  page52_i153
#ISCELL
  mstr_standard tap *
  page52_i154
#ISCELL
  mstr_standard tap *
  page52_i155
#ISCELL
  mstr_symbols gnd *
  page52_i156
#ISCELL
  mstr_standard tap *
  page52_i157
#ISCELL
  mstr_standard tap *
  page52_i158
#ISCELL
  mstr_standard tap *
  page52_i159
#ISCELL
  mstr_standard offpage *
  page52_i16
#ISCELL
  mstr_standard tap *
  page52_i160
#ISCELL
  mstr_standard tap *
  page52_i161
#ISCELL
  mstr_standard tap *
  page52_i162
#ISCELL
  mstr_standard tap *
  page52_i163
#ISCELL
  mstr_standard tap *
  page52_i164
#ISCELL
  mstr_standard tap *
  page52_i165
#ISCELL
  mstr_standard tap *
  page52_i166
#ISCELL
  mstr_standard tap *
  page52_i167
#ISCELL
  mstr_standard tap *
  page52_i168
#ISCELL
  mstr_standard tap *
  page52_i169
#ISCELL
  mstr_standard offpage *
  page52_i17
#ISCELL
  mstr_standard tap *
  page52_i170
#ISCELL
  mstr_standard tap *
  page52_i171
#ISCELL
  mstr_standard tap *
  page52_i172
#ISCELL
  mstr_standard tap *
  page52_i173
#ISCELL
  mstr_standard tap *
  page52_i174
#ISCELL
  mstr_standard tap *
  page52_i175
#ISCELL
  mstr_standard tap *
  page52_i176
#ISCELL
  mstr_standard tap *
  page52_i177
#ISCELL
  mstr_standard tap *
  page52_i178
#ISCELL
  mstr_standard offpage *
  page52_i179
#ISCELL
  mstr_standard offpage *
  page52_i18
#ISCELL
  mstr_standard offpage *
  page52_i180
#ISCELL
  mstr_symbols p12v_nvdimm_def *
  page52_i181
#ISCELL
  mstr_standard tap *
  page52_i19
#ISCELL
  mstr_symbols gnd *
  page52_i2
#ISCELL
  mstr_standard tap *
  page52_i20
#ISCELL
  mstr_standard tap *
  page52_i21
#ISCELL
  mstr_standard tap *
  page52_i22
#ISCELL
  mstr_standard tap *
  page52_i23
#ISCELL
  mstr_standard tap *
  page52_i24
#ISCELL
  mstr_standard tap *
  page52_i25
#ISCELL
  mstr_standard tap *
  page52_i26
#ISCELL
  mstr_standard tap *
  page52_i27
#ISCELL
  mstr_standard tap *
  page52_i28
#ISCELL
  mstr_standard offpage *
  page52_i29
#CELL
  dev_discrete cap_a *
  page52_i3
#ISCELL
  mstr_standard offpage *
  page52_i30
#ISCELL
  mstr_standard offpage *
  page52_i31
#ISCELL
  mstr_standard tap *
  page52_i32
#ISCELL
  mstr_standard offpage *
  page52_i33
#ISCELL
  mstr_standard offpage *
  page52_i34
#ISCELL
  mstr_standard tap *
  page52_i35
#ISCELL
  mstr_standard tap *
  page52_i36
#ISCELL
  mstr_standard tap *
  page52_i37
#ISCELL
  mstr_standard tap *
  page52_i38
#ISCELL
  mstr_standard tap *
  page52_i39
#ISCELL
  mstr_standard offpage *
  page52_i4
#ISCELL
  mstr_standard tap *
  page52_i40
#ISCELL
  mstr_standard tap *
  page52_i41
#ISCELL
  mstr_standard tap *
  page52_i42
#ISCELL
  mstr_standard tap *
  page52_i43
#ISCELL
  mstr_standard tap *
  page52_i44
#ISCELL
  mstr_standard tap *
  page52_i45
#ISCELL
  mstr_standard tap *
  page52_i46
#ISCELL
  mstr_standard tap *
  page52_i47
#ISCELL
  mstr_standard tap *
  page52_i48
#ISCELL
  mstr_standard tap *
  page52_i49
#ISCELL
  mstr_symbols pvpp_def *
  page52_i5
#ISCELL
  mstr_standard tap *
  page52_i50
#ISCELL
  mstr_standard tap *
  page52_i51
#ISCELL
  mstr_standard tap *
  page52_i52
#ISCELL
  mstr_standard tap *
  page52_i53
#ISCELL
  mstr_standard tap *
  page52_i54
#CELL
  mstr_sconn sconn288_h44441003 *
  page52_i55
#ISCELL
  mstr_standard tap *
  page52_i56
#ISCELL
  mstr_standard tap *
  page52_i57
#ISCELL
  mstr_standard tap *
  page52_i58
#ISCELL
  mstr_standard tap *
  page52_i59
#ISCELL
  mstr_standard offpage *
  page52_i6
#ISCELL
  mstr_standard tap *
  page52_i60
#ISCELL
  mstr_standard tap *
  page52_i61
#ISCELL
  mstr_standard tap *
  page52_i62
#ISCELL
  mstr_standard tap *
  page52_i63
#ISCELL
  mstr_standard tap *
  page52_i64
#ISCELL
  mstr_standard tap *
  page52_i65
#ISCELL
  mstr_standard tap *
  page52_i66
#ISCELL
  mstr_standard tap *
  page52_i67
#ISCELL
  mstr_standard tap *
  page52_i68
#ISCELL
  mstr_standard tap *
  page52_i69
#ISCELL
  mstr_standard offpage *
  page52_i7
#ISCELL
  mstr_standard tap *
  page52_i70
#ISCELL
  mstr_standard tap *
  page52_i71
#ISCELL
  mstr_standard tap *
  page52_i72
#ISCELL
  mstr_standard tap *
  page52_i73
#ISCELL
  mstr_standard tap *
  page52_i74
#ISCELL
  mstr_standard tap *
  page52_i75
#ISCELL
  mstr_standard tap *
  page52_i76
#ISCELL
  mstr_symbols pvddq_def *
  page52_i77
#ISCELL
  mstr_standard tap *
  page52_i78
#ISCELL
  mstr_standard tap *
  page52_i79
#ISCELL
  mstr_standard offpage *
  page52_i8
#ISCELL
  mstr_standard tap *
  page52_i80
#ISCELL
  mstr_standard tap *
  page52_i81
#ISCELL
  mstr_standard tap *
  page52_i82
#ISCELL
  mstr_standard tap *
  page52_i83
#ISCELL
  mstr_standard tap *
  page52_i84
#ISCELL
  mstr_standard tap *
  page52_i85
#ISCELL
  mstr_standard tap *
  page52_i86
#ISCELL
  mstr_standard tap *
  page52_i87
#ISCELL
  mstr_standard tap *
  page52_i88
#ISCELL
  mstr_standard tap *
  page52_i89
#ISCELL
  mstr_standard offpage *
  page52_i9
#ISCELL
  mstr_standard tap *
  page52_i90
#ISCELL
  mstr_standard tap *
  page52_i91
#ISCELL
  mstr_standard tap *
  page52_i92
#ISCELL
  mstr_standard tap *
  page52_i93
#ISCELL
  mstr_standard tap *
  page52_i94
#ISCELL
  mstr_standard tap *
  page52_i95
#ISCELL
  mstr_standard tap *
  page52_i96
#ISCELL
  mstr_standard tap *
  page52_i97
#ISCELL
  mstr_symbols pvtt_def *
  page52_i98
#ISCELL
  mstr_symbols pvpp_def *
  page52_i99
#ISCELL
  mstr_symbols bom_note *
  *
#ISCELL
  mstr_symbols intel_corp_bpage *
  *
#ISCELL
  mstr_standard offpage *
  page53_i1
#ISCELL
  mstr_standard tap *
  page53_i10
#ISCELL
  mstr_standard tap *
  page53_i100
#ISCELL
  mstr_standard tap *
  page53_i101
#ISCELL
  mstr_standard tap *
  page53_i102
#ISCELL
  mstr_standard tap *
  page53_i103
#ISCELL
  mstr_standard tap *
  page53_i104
#ISCELL
  mstr_standard tap *
  page53_i105
#ISCELL
  mstr_standard tap *
  page53_i106
#ISCELL
  mstr_standard tap *
  page53_i107
#ISCELL
  mstr_standard tap *
  page53_i108
#ISCELL
  mstr_standard tap *
  page53_i109
#ISCELL
  mstr_standard tap *
  page53_i11
#ISCELL
  mstr_standard tap *
  page53_i110
#CELL
  mstr_sconn sconn288_h44441004 *
  page53_i111
#ISCELL
  mstr_standard tap *
  page53_i112
#ISCELL
  mstr_standard tap *
  page53_i113
#ISCELL
  mstr_standard tap *
  page53_i114
#ISCELL
  mstr_standard tap *
  page53_i115
#ISCELL
  mstr_standard tap *
  page53_i116
#ISCELL
  mstr_standard tap *
  page53_i117
#ISCELL
  mstr_standard tap *
  page53_i118
#ISCELL
  mstr_standard tap *
  page53_i119
#ISCELL
  mstr_standard tap *
  page53_i12
#ISCELL
  mstr_standard tap *
  page53_i120
#ISCELL
  mstr_standard tap *
  page53_i121
#ISCELL
  mstr_standard tap *
  page53_i122
#ISCELL
  mstr_standard tap *
  page53_i123
#ISCELL
  mstr_standard tap *
  page53_i124
#ISCELL
  mstr_standard tap *
  page53_i125
#ISCELL
  mstr_standard tap *
  page53_i126
#ISCELL
  mstr_standard tap *
  page53_i127
#ISCELL
  mstr_standard tap *
  page53_i128
#ISCELL
  mstr_standard tap *
  page53_i129
#ISCELL
  mstr_standard tap *
  page53_i13
#ISCELL
  mstr_standard tap *
  page53_i130
#ISCELL
  mstr_standard offpage *
  page53_i131
#ISCELL
  mstr_standard offpage *
  page53_i132
#ISCELL
  mstr_standard tap *
  page53_i133
#ISCELL
  mstr_standard tap *
  page53_i134
#ISCELL
  mstr_standard tap *
  page53_i135
#ISCELL
  mstr_standard offpage *
  page53_i136
#ISCELL
  mstr_standard offpage *
  page53_i137
#ISCELL
  mstr_standard tap *
  page53_i138
#ISCELL
  mstr_standard tap *
  page53_i139
#ISCELL
  mstr_standard tap *
  page53_i14
#ISCELL
  mstr_standard tap *
  page53_i140
#ISCELL
  mstr_standard tap *
  page53_i141
#ISCELL
  mstr_standard tap *
  page53_i142
#ISCELL
  mstr_standard tap *
  page53_i143
#ISCELL
  mstr_standard tap *
  page53_i144
#ISCELL
  mstr_standard tap *
  page53_i145
#ISCELL
  mstr_standard offpage *
  page53_i146
#ISCELL
  mstr_standard offpage *
  page53_i147
#ISCELL
  mstr_standard offpage *
  page53_i148
#ISCELL
  mstr_standard offpage *
  page53_i149
#ISCELL
  mstr_standard tap *
  page53_i15
#ISCELL
  mstr_standard offpage *
  page53_i150
#ISCELL
  mstr_standard tap *
  page53_i152
#ISCELL
  mstr_standard tap *
  page53_i153
#ISCELL
  mstr_standard tap *
  page53_i154
#ISCELL
  mstr_standard tap *
  page53_i155
#ISCELL
  mstr_standard offpage *
  page53_i156
#ISCELL
  mstr_standard offpage *
  page53_i157
#ISCELL
  mstr_standard tap *
  page53_i158
#ISCELL
  mstr_standard tap *
  page53_i159
#ISCELL
  mstr_standard tap *
  page53_i160
#ISCELL
  mstr_standard tap *
  page53_i161
#ISCELL
  mstr_standard tap *
  page53_i162
#ISCELL
  mstr_standard tap *
  page53_i163
#ISCELL
  mstr_standard tap *
  page53_i164
#ISCELL
  mstr_standard tap *
  page53_i165
#ISCELL
  mstr_standard offpage *
  page53_i166
#ISCELL
  mstr_standard offpage *
  page53_i167
#ISCELL
  mstr_standard offpage *
  page53_i168
#ISCELL
  mstr_standard offpage *
  page53_i169
#ISCELL
  mstr_symbols pvtt_def *
  page53_i17
#ISCELL
  mstr_standard offpage *
  page53_i170
#CELL
  mstr_sconn sconn288_h44441004 *
  page53_i171
#ISCELL
  mstr_symbols pvddq_def *
  page53_i172
#ISCELL
  mstr_symbols gnd *
  page53_i173
#ISCELL
  mstr_symbols gnd *
  page53_i175
#ISCELL
  mstr_standard offpage *
  page53_i176
#ISCELL
  mstr_standard offpage *
  page53_i177
#CELL
  dev_discrete cap_a *
  page53_i178
#ISCELL
  mstr_symbols gnd *
  page53_i179
#ISCELL
  mstr_symbols pvpp_def *
  page53_i180
#ISCELL
  mstr_symbols pvpp_def *
  page53_i181
#ISCELL
  mstr_standard offpage *
  page53_i182
#ISCELL
  mstr_standard tap *
  page53_i19
#ISCELL
  mstr_symbols p12v_nvdimm_def *
  page53_i195
#ISCELL
  mstr_standard offpage *
  page53_i2
#ISCELL
  mstr_standard tap *
  page53_i20
#ISCELL
  mstr_standard tap *
  page53_i21
#ISCELL
  mstr_standard tap *
  page53_i22
#ISCELL
  mstr_standard tap *
  page53_i23
#ISCELL
  mstr_standard tap *
  page53_i24
#ISCELL
  mstr_standard tap *
  page53_i25
#ISCELL
  mstr_standard tap *
  page53_i26
#ISCELL
  mstr_standard tap *
  page53_i27
#ISCELL
  mstr_standard tap *
  page53_i28
#ISCELL
  mstr_standard tap *
  page53_i29
#ISCELL
  mstr_standard tap *
  page53_i3
#ISCELL
  mstr_standard tap *
  page53_i30
#ISCELL
  mstr_standard tap *
  page53_i31
#ISCELL
  mstr_standard tap *
  page53_i32
#ISCELL
  mstr_standard tap *
  page53_i33
#ISCELL
  mstr_standard tap *
  page53_i34
#ISCELL
  mstr_standard tap *
  page53_i35
#ISCELL
  mstr_standard tap *
  page53_i36
#ISCELL
  mstr_standard tap *
  page53_i37
#ISCELL
  mstr_standard tap *
  page53_i38
#ISCELL
  mstr_standard tap *
  page53_i39
#ISCELL
  mstr_standard tap *
  page53_i4
#ISCELL
  mstr_standard tap *
  page53_i40
#ISCELL
  mstr_standard tap *
  page53_i41
#CELL
  mstr_sconn sconn288_h44441004 *
  page53_i43
#ISCELL
  mstr_symbols gnd *
  page53_i44
#ISCELL
  mstr_standard offpage *
  page53_i45
#ISCELL
  mstr_standard tap *
  page53_i46
#ISCELL
  mstr_standard tap *
  page53_i47
#ISCELL
  mstr_standard tap *
  page53_i48
#ISCELL
  mstr_standard tap *
  page53_i49
#ISCELL
  mstr_standard tap *
  page53_i5
#ISCELL
  mstr_standard tap *
  page53_i50
#ISCELL
  mstr_standard tap *
  page53_i51
#ISCELL
  mstr_standard tap *
  page53_i52
#ISCELL
  mstr_standard tap *
  page53_i53
#ISCELL
  mstr_standard tap *
  page53_i54
#ISCELL
  mstr_standard tap *
  page53_i55
#ISCELL
  mstr_standard tap *
  page53_i56
#ISCELL
  mstr_standard tap *
  page53_i57
#ISCELL
  mstr_standard tap *
  page53_i58
#ISCELL
  mstr_standard tap *
  page53_i59
#ISCELL
  mstr_standard tap *
  page53_i6
#ISCELL
  mstr_standard tap *
  page53_i60
#ISCELL
  mstr_standard tap *
  page53_i61
#ISCELL
  mstr_standard tap *
  page53_i62
#ISCELL
  mstr_standard tap *
  page53_i63
#ISCELL
  mstr_standard tap *
  page53_i64
#ISCELL
  mstr_standard tap *
  page53_i65
#CELL
  mstr_sconn sconn288_h44441004 *
  page53_i66
#ISCELL
  mstr_standard tap *
  page53_i67
#ISCELL
  mstr_standard tap *
  page53_i68
#ISCELL
  mstr_standard tap *
  page53_i69
#ISCELL
  mstr_standard tap *
  page53_i7
#ISCELL
  mstr_standard tap *
  page53_i70
#ISCELL
  mstr_standard tap *
  page53_i71
#ISCELL
  mstr_standard tap *
  page53_i72
#ISCELL
  mstr_standard tap *
  page53_i73
#ISCELL
  mstr_standard tap *
  page53_i74
#ISCELL
  mstr_standard tap *
  page53_i75
#ISCELL
  mstr_standard tap *
  page53_i76
#ISCELL
  mstr_standard tap *
  page53_i77
#ISCELL
  mstr_standard tap *
  page53_i78
#ISCELL
  mstr_standard tap *
  page53_i79
#ISCELL
  mstr_standard tap *
  page53_i8
#ISCELL
  mstr_standard tap *
  page53_i80
#ISCELL
  mstr_standard tap *
  page53_i81
#ISCELL
  mstr_standard tap *
  page53_i82
#ISCELL
  mstr_standard tap *
  page53_i83
#ISCELL
  mstr_standard tap *
  page53_i84
#ISCELL
  mstr_standard tap *
  page53_i85
#ISCELL
  mstr_standard tap *
  page53_i86
#ISCELL
  mstr_standard tap *
  page53_i87
#ISCELL
  mstr_standard tap *
  page53_i88
#ISCELL
  mstr_standard tap *
  page53_i89
#ISCELL
  mstr_standard tap *
  page53_i9
#ISCELL
  mstr_standard tap *
  page53_i90
#ISCELL
  mstr_standard tap *
  page53_i91
#ISCELL
  mstr_standard tap *
  page53_i92
#ISCELL
  mstr_standard tap *
  page53_i93
#ISCELL
  mstr_standard tap *
  page53_i94
#ISCELL
  mstr_standard tap *
  page53_i95
#ISCELL
  mstr_standard tap *
  page53_i96
#ISCELL
  mstr_standard tap *
  page53_i97
#ISCELL
  mstr_standard tap *
  page53_i98
#ISCELL
  mstr_standard tap *
  page53_i99
#ISCELL
  mstr_symbols bom_note *
  *
#ISCELL
  mstr_symbols intel_corp_bpage *
  *
#ISCELL
  mstr_standard offpage *
  page54_i1
#ISCELL
  mstr_standard tap *
  page54_i10
#ISCELL
  mstr_standard tap *
  page54_i100
#ISCELL
  mstr_standard tap *
  page54_i101
#ISCELL
  mstr_standard tap *
  page54_i102
#ISCELL
  mstr_standard tap *
  page54_i103
#ISCELL
  mstr_standard tap *
  page54_i104
#ISCELL
  mstr_standard tap *
  page54_i105
#ISCELL
  mstr_standard tap *
  page54_i106
#ISCELL
  mstr_standard tap *
  page54_i107
#ISCELL
  mstr_standard tap *
  page54_i108
#ISCELL
  mstr_standard tap *
  page54_i109
#ISCELL
  mstr_standard tap *
  page54_i11
#ISCELL
  mstr_standard tap *
  page54_i110
#CELL
  mstr_sconn sconn288_h44441003 *
  page54_i111
#ISCELL
  mstr_standard tap *
  page54_i112
#ISCELL
  mstr_standard tap *
  page54_i113
#ISCELL
  mstr_standard tap *
  page54_i114
#ISCELL
  mstr_standard tap *
  page54_i115
#ISCELL
  mstr_standard tap *
  page54_i116
#ISCELL
  mstr_standard tap *
  page54_i117
#ISCELL
  mstr_standard tap *
  page54_i118
#ISCELL
  mstr_standard tap *
  page54_i119
#ISCELL
  mstr_standard tap *
  page54_i12
#ISCELL
  mstr_standard tap *
  page54_i120
#ISCELL
  mstr_standard tap *
  page54_i121
#ISCELL
  mstr_standard tap *
  page54_i122
#ISCELL
  mstr_standard tap *
  page54_i123
#ISCELL
  mstr_standard tap *
  page54_i124
#ISCELL
  mstr_standard tap *
  page54_i125
#ISCELL
  mstr_standard tap *
  page54_i126
#ISCELL
  mstr_standard tap *
  page54_i127
#ISCELL
  mstr_standard tap *
  page54_i128
#ISCELL
  mstr_standard tap *
  page54_i129
#ISCELL
  mstr_standard tap *
  page54_i13
#ISCELL
  mstr_standard tap *
  page54_i130
#ISCELL
  mstr_standard offpage *
  page54_i131
#ISCELL
  mstr_standard offpage *
  page54_i132
#ISCELL
  mstr_standard tap *
  page54_i133
#ISCELL
  mstr_standard tap *
  page54_i134
#ISCELL
  mstr_standard tap *
  page54_i135
#ISCELL
  mstr_standard offpage *
  page54_i136
#ISCELL
  mstr_standard offpage *
  page54_i137
#ISCELL
  mstr_standard tap *
  page54_i138
#ISCELL
  mstr_standard tap *
  page54_i139
#ISCELL
  mstr_standard tap *
  page54_i14
#ISCELL
  mstr_standard tap *
  page54_i140
#ISCELL
  mstr_standard tap *
  page54_i141
#ISCELL
  mstr_standard tap *
  page54_i142
#ISCELL
  mstr_standard tap *
  page54_i143
#ISCELL
  mstr_standard tap *
  page54_i144
#ISCELL
  mstr_standard tap *
  page54_i145
#ISCELL
  mstr_standard offpage *
  page54_i146
#ISCELL
  mstr_standard offpage *
  page54_i147
#ISCELL
  mstr_standard offpage *
  page54_i148
#ISCELL
  mstr_standard offpage *
  page54_i149
#ISCELL
  mstr_standard tap *
  page54_i15
#ISCELL
  mstr_standard offpage *
  page54_i150
#ISCELL
  mstr_standard tap *
  page54_i152
#ISCELL
  mstr_standard tap *
  page54_i153
#ISCELL
  mstr_standard tap *
  page54_i154
#ISCELL
  mstr_standard tap *
  page54_i155
#ISCELL
  mstr_standard offpage *
  page54_i156
#ISCELL
  mstr_standard offpage *
  page54_i157
#ISCELL
  mstr_standard tap *
  page54_i158
#ISCELL
  mstr_standard tap *
  page54_i159
#ISCELL
  mstr_symbols pvddq_def *
  page54_i16
#ISCELL
  mstr_standard tap *
  page54_i160
#ISCELL
  mstr_standard tap *
  page54_i161
#ISCELL
  mstr_standard offpage *
  page54_i163
#ISCELL
  mstr_standard offpage *
  page54_i164
#ISCELL
  mstr_standard tap *
  page54_i165
#ISCELL
  mstr_standard tap *
  page54_i166
#ISCELL
  mstr_standard tap *
  page54_i167
#ISCELL
  mstr_standard tap *
  page54_i168
#ISCELL
  mstr_standard offpage *
  page54_i169
#ISCELL
  mstr_symbols pvtt_def *
  page54_i17
#CELL
  mstr_sconn sconn288_h44441003 *
  page54_i170
#ISCELL
  mstr_symbols gnd *
  page54_i171
#ISCELL
  mstr_standard offpage *
  page54_i172
#ISCELL
  mstr_standard offpage *
  page54_i173
#ISCELL
  mstr_standard offpage *
  page54_i174
#ISCELL
  mstr_standard offpage *
  page54_i175
#ISCELL
  mstr_symbols gnd *
  page54_i178
#CELL
  dev_discrete cap_a *
  page54_i179
#ISCELL
  mstr_symbols pvpp_def *
  page54_i180
#ISCELL
  mstr_symbols pvpp_def *
  page54_i181
#ISCELL
  mstr_standard offpage *
  page54_i182
#ISCELL
  mstr_symbols gnd *
  page54_i186
#ISCELL
  mstr_symbols p12v_nvdimm_def *
  page54_i187
#ISCELL
  mstr_standard tap *
  page54_i19
#ISCELL
  mstr_standard offpage *
  page54_i2
#ISCELL
  mstr_standard tap *
  page54_i20
#ISCELL
  mstr_standard tap *
  page54_i21
#ISCELL
  mstr_standard tap *
  page54_i22
#ISCELL
  mstr_standard tap *
  page54_i23
#ISCELL
  mstr_standard tap *
  page54_i24
#ISCELL
  mstr_standard tap *
  page54_i25
#ISCELL
  mstr_standard tap *
  page54_i26
#ISCELL
  mstr_standard tap *
  page54_i27
#ISCELL
  mstr_standard tap *
  page54_i28
#ISCELL
  mstr_standard tap *
  page54_i29
#ISCELL
  mstr_standard tap *
  page54_i3
#ISCELL
  mstr_standard tap *
  page54_i30
#ISCELL
  mstr_standard tap *
  page54_i31
#ISCELL
  mstr_standard tap *
  page54_i32
#ISCELL
  mstr_standard tap *
  page54_i33
#ISCELL
  mstr_standard tap *
  page54_i34
#ISCELL
  mstr_standard tap *
  page54_i35
#ISCELL
  mstr_standard tap *
  page54_i36
#ISCELL
  mstr_standard tap *
  page54_i37
#ISCELL
  mstr_standard tap *
  page54_i38
#ISCELL
  mstr_standard tap *
  page54_i39
#ISCELL
  mstr_standard tap *
  page54_i4
#ISCELL
  mstr_standard tap *
  page54_i40
#ISCELL
  mstr_standard tap *
  page54_i41
#CELL
  mstr_sconn sconn288_h44441003 *
  page54_i43
#ISCELL
  mstr_symbols gnd *
  page54_i44
#ISCELL
  mstr_standard offpage *
  page54_i45
#ISCELL
  mstr_standard tap *
  page54_i46
#ISCELL
  mstr_standard tap *
  page54_i47
#ISCELL
  mstr_standard tap *
  page54_i48
#ISCELL
  mstr_standard tap *
  page54_i49
#ISCELL
  mstr_standard tap *
  page54_i5
#ISCELL
  mstr_standard tap *
  page54_i50
#ISCELL
  mstr_standard tap *
  page54_i51
#ISCELL
  mstr_standard tap *
  page54_i52
#ISCELL
  mstr_standard tap *
  page54_i53
#ISCELL
  mstr_standard tap *
  page54_i54
#ISCELL
  mstr_standard tap *
  page54_i55
#ISCELL
  mstr_standard tap *
  page54_i56
#ISCELL
  mstr_standard tap *
  page54_i57
#ISCELL
  mstr_standard tap *
  page54_i58
#ISCELL
  mstr_standard tap *
  page54_i59
#ISCELL
  mstr_standard tap *
  page54_i6
#ISCELL
  mstr_standard tap *
  page54_i60
#ISCELL
  mstr_standard tap *
  page54_i61
#ISCELL
  mstr_standard tap *
  page54_i62
#ISCELL
  mstr_standard tap *
  page54_i63
#ISCELL
  mstr_standard tap *
  page54_i64
#ISCELL
  mstr_standard tap *
  page54_i65
#CELL
  mstr_sconn sconn288_h44441003 *
  page54_i66
#ISCELL
  mstr_standard tap *
  page54_i67
#ISCELL
  mstr_standard tap *
  page54_i68
#ISCELL
  mstr_standard tap *
  page54_i69
#ISCELL
  mstr_standard tap *
  page54_i7
#ISCELL
  mstr_standard tap *
  page54_i70
#ISCELL
  mstr_standard tap *
  page54_i71
#ISCELL
  mstr_standard tap *
  page54_i72
#ISCELL
  mstr_standard tap *
  page54_i73
#ISCELL
  mstr_standard tap *
  page54_i74
#ISCELL
  mstr_standard tap *
  page54_i75
#ISCELL
  mstr_standard tap *
  page54_i76
#ISCELL
  mstr_standard tap *
  page54_i77
#ISCELL
  mstr_standard tap *
  page54_i78
#ISCELL
  mstr_standard tap *
  page54_i79
#ISCELL
  mstr_standard tap *
  page54_i8
#ISCELL
  mstr_standard tap *
  page54_i80
#ISCELL
  mstr_standard tap *
  page54_i81
#ISCELL
  mstr_standard tap *
  page54_i82
#ISCELL
  mstr_standard tap *
  page54_i83
#ISCELL
  mstr_standard tap *
  page54_i84
#ISCELL
  mstr_standard tap *
  page54_i85
#ISCELL
  mstr_standard tap *
  page54_i86
#ISCELL
  mstr_standard tap *
  page54_i87
#ISCELL
  mstr_standard tap *
  page54_i88
#ISCELL
  mstr_standard tap *
  page54_i89
#ISCELL
  mstr_standard tap *
  page54_i9
#ISCELL
  mstr_standard tap *
  page54_i90
#ISCELL
  mstr_standard tap *
  page54_i91
#ISCELL
  mstr_standard tap *
  page54_i92
#ISCELL
  mstr_standard tap *
  page54_i93
#ISCELL
  mstr_standard tap *
  page54_i94
#ISCELL
  mstr_standard tap *
  page54_i95
#ISCELL
  mstr_standard tap *
  page54_i96
#ISCELL
  mstr_standard tap *
  page54_i97
#ISCELL
  mstr_standard tap *
  page54_i98
#ISCELL
  mstr_standard tap *
  page54_i99
#ISCELL
  mstr_misc prelim *
  *
#ISCELL
  mstr_symbols bom_note *
  *
#ISCELL
  mstr_symbols cad_note *
  *
#ISCELL
  mstr_symbols design_note *
  *
#ISCELL
  mstr_symbols intel_corp_bpage *
  *
#ISCELL
  mstr_standard offpage *
  page55_i10
#ISCELL
  mstr_standard offpage *
  page55_i100
#ISCELL
  mstr_standard offpage *
  page55_i101
#ISCELL
  mstr_standard offpage *
  page55_i102
#ISCELL
  mstr_standard offpage *
  page55_i103
#ISCELL
  mstr_standard offpage *
  page55_i108
#ISCELL
  mstr_standard offpage *
  page55_i109
#CELL
  mstr_discrete res *
  page55_i115
#CELL
  mstr_discrete res *
  page55_i116
#CELL
  mstr_discrete res *
  page55_i117
#CELL
  mstr_discrete res *
  page55_i118
#CELL
  mstr_discrete res *
  page55_i119
#ISCELL
  mstr_symbols gnd *
  page55_i121
#ISCELL
  mstr_symbols gnd *
  page55_i122
#CELL
  mstr_discrete res *
  page55_i123
#CELL
  mstr_discrete res *
  page55_i124
#CELL
  mstr_discrete res *
  page55_i125
#CELL
  mstr_discrete res *
  page55_i126
#ISCELL
  mstr_standard offpage *
  page55_i13
#ISCELL
  mstr_standard offpage *
  page55_i132
#ISCELL
  mstr_standard offpage *
  page55_i133
#ISCELL
  mstr_standard offpage *
  page55_i134
#ISCELL
  mstr_standard offpage *
  page55_i135
#ISCELL
  mstr_standard offpage *
  page55_i138
#ISCELL
  mstr_standard offpage *
  page55_i139
#ISCELL
  mstr_standard offpage *
  page55_i14
#CELL
  mstr_discrete res *
  page55_i140
#ISCELL
  mstr_standard offpage *
  page55_i145
#ISCELL
  mstr_standard offpage *
  page55_i146
#ISCELL
  mstr_standard offpage *
  page55_i148
#ISCELL
  mstr_standard offpage *
  page55_i149
#ISCELL
  mstr_standard offpage *
  page55_i15
#ISCELL
  mstr_standard offpage *
  page55_i150
#ISCELL
  mstr_standard offpage *
  page55_i151
#CELL
  chpset_lib socket_p_mech_a *
  page55_i152
#CELL
  chpset_lib socket_p_mech_a *
  page55_i153
#CELL
  mstr_discrete res *
  page55_i155
#CELL
  mstr_discrete res *
  page55_i156
#CELL
  mstr_discrete res *
  page55_i157
#CELL
  mstr_discrete res *
  page55_i158
#CELL
  mstr_discrete res *
  page55_i159
#ISCELL
  mstr_standard offpage *
  page55_i16
#CELL
  mstr_discrete res *
  page55_i160
#CELL
  mstr_discrete res *
  page55_i161
#ISCELL
  mstr_symbols p3v3_stby *
  page55_i162
#ISCELL
  mstr_standard offpage *
  page55_i163
#ISCELL
  mstr_standard offpage *
  page55_i164
#ISCELL
  mstr_standard offpage *
  page55_i165
#ISCELL
  mstr_standard offpage *
  page55_i166
#ISCELL
  mstr_standard offpage *
  page55_i167
#ISCELL
  mstr_symbols p3v3_stby *
  page55_i169
#ISCELL
  mstr_standard offpage *
  page55_i17
#CELL
  mstr_discrete res *
  page55_i170
#CELL
  chpset_lib skx_ext_b *
  page55_i172
#ISCELL
  mstr_standard offpage *
  page55_i173
#ISCELL
  mstr_standard offpage *
  page55_i174
#ISCELL
  mstr_standard offpage *
  page55_i175
#ISCELL
  mstr_standard offpage *
  page55_i178
#ISCELL
  mstr_standard offpage *
  page55_i179
#ISCELL
  mstr_standard offpage *
  page55_i18
#ISCELL
  mstr_standard offpage *
  page55_i180
#CELL
  mstr_discrete res *
  page55_i181
#ISCELL
  mstr_standard offpage *
  page55_i182
#ISCELL
  mstr_standard offpage *
  page55_i183
#ISCELL
  mstr_standard offpage *
  page55_i184
#ISCELL
  mstr_standard offpage *
  page55_i185
#ISCELL
  mstr_standard offpage *
  page55_i186
#ISCELL
  mstr_standard offpage *
  page55_i187
#ISCELL
  mstr_standard offpage *
  page55_i188
#ISCELL
  mstr_standard offpage *
  page55_i189
#CELL
  mstr_discrete res *
  page55_i19
#ISCELL
  mstr_standard offpage *
  page55_i190
#ISCELL
  mstr_standard offpage *
  page55_i191
#ISCELL
  mstr_standard offpage *
  page55_i2
#CELL
  mstr_discrete res *
  page55_i21
#ISCELL
  mstr_symbols pvccio_cpu1 *
  page55_i22
#ISCELL
  mstr_standard offpage *
  page55_i23
#CELL
  mstr_discrete res *
  page55_i24
#CELL
  mstr_discrete res *
  page55_i25
#CELL
  mstr_discrete res *
  page55_i26
#CELL
  mstr_discrete res *
  page55_i27
#CELL
  mstr_discrete res *
  page55_i28
#CELL
  mstr_discrete res *
  page55_i29
#ISCELL
  mstr_standard offpage *
  page55_i3
#ISCELL
  mstr_standard offpage *
  page55_i30
#ISCELL
  mstr_standard offpage *
  page55_i31
#ISCELL
  mstr_standard offpage *
  page55_i32
#ISCELL
  mstr_standard offpage *
  page55_i33
#ISCELL
  mstr_standard offpage *
  page55_i34
#ISCELL
  mstr_standard offpage *
  page55_i36
#ISCELL
  mstr_standard offpage *
  page55_i37
#ISCELL
  mstr_standard offpage *
  page55_i38
#ISCELL
  mstr_standard offpage *
  page55_i39
#CELL
  mstr_discrete res *
  page55_i4
#ISCELL
  mstr_standard offpage *
  page55_i40
#ISCELL
  mstr_standard offpage *
  page55_i41
#ISCELL
  mstr_standard offpage *
  page55_i42
#ISCELL
  mstr_standard offpage *
  page55_i43
#ISCELL
  mstr_standard offpage *
  page55_i44
#ISCELL
  mstr_standard offpage *
  page55_i57
#ISCELL
  mstr_standard offpage *
  page55_i58
#ISCELL
  mstr_standard offpage *
  page55_i59
#ISCELL
  mstr_symbols pvccio_cpu1 *
  page55_i6
#ISCELL
  mstr_standard offpage *
  page55_i60
#ISCELL
  mstr_standard offpage *
  page55_i61
#ISCELL
  mstr_standard offpage *
  page55_i62
#ISCELL
  mstr_standard offpage *
  page55_i63
#ISCELL
  mstr_standard offpage *
  page55_i64
#ISCELL
  mstr_standard offpage *
  page55_i65
#ISCELL
  mstr_standard offpage *
  page55_i67
#ISCELL
  mstr_standard offpage *
  page55_i68
#CELL
  mstr_discrete res *
  page55_i7
#ISCELL
  mstr_standard offpage *
  page55_i70
#ISCELL
  mstr_standard offpage *
  page55_i73
#ISCELL
  mstr_standard offpage *
  page55_i8
#ISCELL
  mstr_standard offpage *
  page55_i80
#ISCELL
  mstr_standard offpage *
  page55_i81
#ISCELL
  mstr_standard offpage *
  page55_i82
#ISCELL
  mstr_standard offpage *
  page55_i83
#ISCELL
  mstr_misc prelim *
  *
#ISCELL
  mstr_symbols design_note *
  *
#ISCELL
  mstr_symbols intel_corp_bpage *
  *
#ISCELL
  mstr_standard offpage *
  page56_i161
#ISCELL
  mstr_standard offpage *
  page56_i164
#CELL
  chpset_lib skx_ext_b *
  page56_i169
#ISCELL
  mstr_symbols gnd *
  page56_i171
#CELL
  mstr_discrete res *
  page56_i173
#CELL
  mstr_discrete res *
  page56_i174
#ISCELL
  mstr_standard offpage *
  page56_i178
#ISCELL
  mstr_standard offpage *
  page56_i179
#ISCELL
  mstr_standard offpage *
  page56_i180
#ISCELL
  mstr_standard offpage *
  page56_i181
#ISCELL
  mstr_standard offpage *
  page56_i182
#ISCELL
  mstr_standard offpage *
  page56_i183
#ISCELL
  mstr_symbols vcc_core *
  page56_i185
#ISCELL
  mstr_standard offpage *
  page56_i187
#ISCELL
  mstr_symbols vcc_core *
  page56_i188
#ISCELL
  mstr_standard offpage *
  page56_i189
#ISCELL
  mstr_standard offpage *
  page56_i190
#ISCELL
  mstr_misc prelim *
  *
#ISCELL
  mstr_symbols design_note *
  *
#ISCELL
  mstr_symbols intel_corp_bpage *
  *
#ISCELL
  mstr_standard offpage *
  page57_i1
#ISCELL
  mstr_standard tap *
  page57_i10
#ISCELL
  mstr_standard tap *
  page57_i100
#ISCELL
  mstr_standard tap *
  page57_i101
#ISCELL
  mstr_standard tap *
  page57_i102
#ISCELL
  mstr_standard tap *
  page57_i103
#ISCELL
  mstr_standard tap *
  page57_i104
#ISCELL
  mstr_standard tap *
  page57_i105
#ISCELL
  mstr_standard tap *
  page57_i106
#ISCELL
  mstr_standard tap *
  page57_i107
#ISCELL
  mstr_standard tap *
  page57_i108
#ISCELL
  mstr_standard tap *
  page57_i109
#ISCELL
  mstr_standard tap *
  page57_i11
#ISCELL
  mstr_standard tap *
  page57_i110
#ISCELL
  mstr_standard tap *
  page57_i111
#ISCELL
  mstr_standard tap *
  page57_i112
#ISCELL
  mstr_standard tap *
  page57_i113
#ISCELL
  mstr_standard tap *
  page57_i114
#ISCELL
  mstr_standard tap *
  page57_i115
#ISCELL
  mstr_standard tap *
  page57_i116
#ISCELL
  mstr_standard tap *
  page57_i117
#ISCELL
  mstr_standard tap *
  page57_i118
#ISCELL
  mstr_standard tap *
  page57_i119
#ISCELL
  mstr_standard tap *
  page57_i12
#ISCELL
  mstr_standard tap *
  page57_i120
#ISCELL
  mstr_standard tap *
  page57_i121
#ISCELL
  mstr_standard tap *
  page57_i122
#ISCELL
  mstr_standard tap *
  page57_i123
#ISCELL
  mstr_standard tap *
  page57_i124
#ISCELL
  mstr_standard tap *
  page57_i125
#ISCELL
  mstr_standard tap *
  page57_i126
#ISCELL
  mstr_standard tap *
  page57_i127
#ISCELL
  mstr_standard tap *
  page57_i128
#ISCELL
  mstr_standard tap *
  page57_i129
#ISCELL
  mstr_standard tap *
  page57_i13
#ISCELL
  mstr_standard tap *
  page57_i130
#ISCELL
  mstr_standard tap *
  page57_i131
#ISCELL
  mstr_standard tap *
  page57_i132
#ISCELL
  mstr_standard tap *
  page57_i133
#ISCELL
  mstr_standard tap *
  page57_i134
#ISCELL
  mstr_standard tap *
  page57_i135
#ISCELL
  mstr_standard tap *
  page57_i136
#ISCELL
  mstr_standard tap *
  page57_i137
#ISCELL
  mstr_standard tap *
  page57_i138
#ISCELL
  mstr_standard tap *
  page57_i139
#ISCELL
  mstr_standard tap *
  page57_i14
#ISCELL
  mstr_standard tap *
  page57_i140
#ISCELL
  mstr_standard tap *
  page57_i141
#ISCELL
  mstr_standard tap *
  page57_i142
#ISCELL
  mstr_standard tap *
  page57_i143
#ISCELL
  mstr_standard tap *
  page57_i144
#ISCELL
  mstr_standard tap *
  page57_i145
#ISCELL
  mstr_standard tap *
  page57_i146
#ISCELL
  mstr_standard offpage *
  page57_i147
#ISCELL
  mstr_standard offpage *
  page57_i148
#ISCELL
  mstr_standard offpage *
  page57_i149
#ISCELL
  mstr_standard tap *
  page57_i15
#ISCELL
  mstr_standard offpage *
  page57_i150
#ISCELL
  mstr_standard offpage *
  page57_i151
#ISCELL
  mstr_standard offpage *
  page57_i152
#ISCELL
  mstr_standard offpage *
  page57_i153
#ISCELL
  mstr_standard offpage *
  page57_i154
#ISCELL
  mstr_standard offpage *
  page57_i155
#ISCELL
  mstr_standard offpage *
  page57_i156
#ISCELL
  mstr_standard tap *
  page57_i157
#ISCELL
  mstr_standard tap *
  page57_i158
#ISCELL
  mstr_standard tap *
  page57_i159
#ISCELL
  mstr_standard tap *
  page57_i16
#ISCELL
  mstr_standard tap *
  page57_i160
#ISCELL
  mstr_standard tap *
  page57_i161
#ISCELL
  mstr_standard tap *
  page57_i162
#ISCELL
  mstr_standard tap *
  page57_i163
#ISCELL
  mstr_standard tap *
  page57_i164
#ISCELL
  mstr_standard tap *
  page57_i165
#ISCELL
  mstr_standard tap *
  page57_i166
#ISCELL
  mstr_standard tap *
  page57_i167
#ISCELL
  mstr_standard tap *
  page57_i168
#ISCELL
  mstr_standard tap *
  page57_i169
#ISCELL
  mstr_standard tap *
  page57_i17
#ISCELL
  mstr_standard tap *
  page57_i170
#ISCELL
  mstr_standard offpage *
  page57_i171
#CELL
  chpset_lib skx_ext_b *
  page57_i172
#ISCELL
  mstr_standard tap *
  page57_i18
#ISCELL
  mstr_standard tap *
  page57_i19
#ISCELL
  mstr_standard offpage *
  page57_i2
#ISCELL
  mstr_standard tap *
  page57_i20
#ISCELL
  mstr_standard tap *
  page57_i21
#ISCELL
  mstr_standard tap *
  page57_i22
#ISCELL
  mstr_standard tap *
  page57_i23
#ISCELL
  mstr_standard tap *
  page57_i24
#ISCELL
  mstr_standard tap *
  page57_i25
#ISCELL
  mstr_standard tap *
  page57_i26
#ISCELL
  mstr_standard tap *
  page57_i27
#ISCELL
  mstr_standard tap *
  page57_i28
#ISCELL
  mstr_standard tap *
  page57_i29
#ISCELL
  mstr_standard offpage *
  page57_i3
#ISCELL
  mstr_standard tap *
  page57_i31
#ISCELL
  mstr_standard tap *
  page57_i32
#ISCELL
  mstr_standard tap *
  page57_i33
#ISCELL
  mstr_standard tap *
  page57_i34
#ISCELL
  mstr_standard tap *
  page57_i35
#ISCELL
  mstr_standard tap *
  page57_i36
#ISCELL
  mstr_standard tap *
  page57_i37
#ISCELL
  mstr_standard tap *
  page57_i38
#ISCELL
  mstr_standard tap *
  page57_i39
#ISCELL
  mstr_standard offpage *
  page57_i4
#ISCELL
  mstr_standard tap *
  page57_i40
#ISCELL
  mstr_standard tap *
  page57_i41
#ISCELL
  mstr_standard tap *
  page57_i42
#ISCELL
  mstr_standard tap *
  page57_i43
#ISCELL
  mstr_standard tap *
  page57_i44
#ISCELL
  mstr_standard tap *
  page57_i45
#ISCELL
  mstr_standard tap *
  page57_i46
#ISCELL
  mstr_standard tap *
  page57_i47
#ISCELL
  mstr_standard tap *
  page57_i48
#ISCELL
  mstr_standard tap *
  page57_i49
#ISCELL
  mstr_standard tap *
  page57_i5
#ISCELL
  mstr_standard tap *
  page57_i50
#ISCELL
  mstr_standard tap *
  page57_i51
#ISCELL
  mstr_standard tap *
  page57_i52
#ISCELL
  mstr_standard tap *
  page57_i53
#ISCELL
  mstr_standard tap *
  page57_i54
#ISCELL
  mstr_standard tap *
  page57_i55
#ISCELL
  mstr_standard tap *
  page57_i56
#ISCELL
  mstr_standard tap *
  page57_i57
#ISCELL
  mstr_standard tap *
  page57_i58
#ISCELL
  mstr_standard tap *
  page57_i59
#ISCELL
  mstr_standard tap *
  page57_i6
#ISCELL
  mstr_standard tap *
  page57_i60
#ISCELL
  mstr_standard tap *
  page57_i61
#ISCELL
  mstr_standard tap *
  page57_i62
#ISCELL
  mstr_standard tap *
  page57_i63
#ISCELL
  mstr_standard tap *
  page57_i64
#ISCELL
  mstr_standard tap *
  page57_i65
#ISCELL
  mstr_standard tap *
  page57_i66
#ISCELL
  mstr_standard tap *
  page57_i67
#ISCELL
  mstr_standard tap *
  page57_i68
#ISCELL
  mstr_standard tap *
  page57_i69
#ISCELL
  mstr_standard tap *
  page57_i7
#ISCELL
  mstr_standard tap *
  page57_i70
#ISCELL
  mstr_standard tap *
  page57_i71
#ISCELL
  mstr_standard offpage *
  page57_i72
#ISCELL
  mstr_standard tap *
  page57_i73
#ISCELL
  mstr_standard tap *
  page57_i74
#ISCELL
  mstr_standard tap *
  page57_i75
#ISCELL
  mstr_standard tap *
  page57_i76
#ISCELL
  mstr_standard tap *
  page57_i77
#ISCELL
  mstr_standard tap *
  page57_i78
#ISCELL
  mstr_standard tap *
  page57_i79
#ISCELL
  mstr_standard tap *
  page57_i8
#ISCELL
  mstr_standard tap *
  page57_i80
#ISCELL
  mstr_standard tap *
  page57_i81
#ISCELL
  mstr_standard tap *
  page57_i82
#ISCELL
  mstr_standard tap *
  page57_i83
#ISCELL
  mstr_standard tap *
  page57_i84
#ISCELL
  mstr_standard tap *
  page57_i85
#ISCELL
  mstr_standard tap *
  page57_i86
#ISCELL
  mstr_standard tap *
  page57_i87
#ISCELL
  mstr_standard tap *
  page57_i88
#ISCELL
  mstr_standard tap *
  page57_i89
#ISCELL
  mstr_standard tap *
  page57_i9
#ISCELL
  mstr_standard tap *
  page57_i90
#ISCELL
  mstr_standard tap *
  page57_i91
#ISCELL
  mstr_standard tap *
  page57_i92
#ISCELL
  mstr_standard tap *
  page57_i93
#ISCELL
  mstr_standard tap *
  page57_i94
#ISCELL
  mstr_standard tap *
  page57_i95
#ISCELL
  mstr_standard tap *
  page57_i96
#ISCELL
  mstr_standard tap *
  page57_i97
#ISCELL
  mstr_standard tap *
  page57_i98
#ISCELL
  mstr_standard tap *
  page57_i99
#ISCELL
  mstr_misc prelim *
  *
#ISCELL
  mstr_symbols design_note *
  *
#ISCELL
  mstr_symbols intel_corp_bpage *
  *
#ISCELL
  mstr_standard offpage *
  page58_i1
#ISCELL
  mstr_standard tap *
  page58_i10
#ISCELL
  mstr_standard tap *
  page58_i100
#ISCELL
  mstr_standard tap *
  page58_i101
#ISCELL
  mstr_standard tap *
  page58_i102
#ISCELL
  mstr_standard tap *
  page58_i103
#ISCELL
  mstr_standard tap *
  page58_i104
#ISCELL
  mstr_standard tap *
  page58_i105
#ISCELL
  mstr_standard tap *
  page58_i106
#ISCELL
  mstr_standard tap *
  page58_i107
#ISCELL
  mstr_standard tap *
  page58_i108
#ISCELL
  mstr_standard tap *
  page58_i109
#ISCELL
  mstr_standard tap *
  page58_i11
#ISCELL
  mstr_standard tap *
  page58_i110
#ISCELL
  mstr_standard tap *
  page58_i111
#ISCELL
  mstr_standard tap *
  page58_i112
#ISCELL
  mstr_standard tap *
  page58_i113
#ISCELL
  mstr_standard tap *
  page58_i114
#ISCELL
  mstr_standard tap *
  page58_i115
#ISCELL
  mstr_standard tap *
  page58_i116
#ISCELL
  mstr_standard tap *
  page58_i117
#ISCELL
  mstr_standard tap *
  page58_i118
#ISCELL
  mstr_standard tap *
  page58_i119
#ISCELL
  mstr_standard tap *
  page58_i12
#ISCELL
  mstr_standard tap *
  page58_i120
#ISCELL
  mstr_standard tap *
  page58_i121
#ISCELL
  mstr_standard tap *
  page58_i122
#ISCELL
  mstr_standard tap *
  page58_i123
#ISCELL
  mstr_standard tap *
  page58_i124
#ISCELL
  mstr_standard tap *
  page58_i125
#ISCELL
  mstr_standard tap *
  page58_i126
#ISCELL
  mstr_standard tap *
  page58_i127
#ISCELL
  mstr_standard tap *
  page58_i128
#ISCELL
  mstr_standard tap *
  page58_i129
#ISCELL
  mstr_standard tap *
  page58_i13
#ISCELL
  mstr_standard tap *
  page58_i130
#ISCELL
  mstr_standard tap *
  page58_i131
#ISCELL
  mstr_standard tap *
  page58_i132
#ISCELL
  mstr_standard tap *
  page58_i133
#ISCELL
  mstr_standard tap *
  page58_i134
#ISCELL
  mstr_standard tap *
  page58_i135
#ISCELL
  mstr_standard tap *
  page58_i136
#ISCELL
  mstr_standard tap *
  page58_i137
#ISCELL
  mstr_standard tap *
  page58_i138
#ISCELL
  mstr_standard tap *
  page58_i139
#ISCELL
  mstr_standard tap *
  page58_i14
#ISCELL
  mstr_standard tap *
  page58_i140
#ISCELL
  mstr_standard tap *
  page58_i141
#ISCELL
  mstr_standard tap *
  page58_i142
#ISCELL
  mstr_standard tap *
  page58_i143
#ISCELL
  mstr_standard tap *
  page58_i144
#ISCELL
  mstr_standard tap *
  page58_i145
#ISCELL
  mstr_standard tap *
  page58_i146
#ISCELL
  mstr_standard offpage *
  page58_i147
#ISCELL
  mstr_standard offpage *
  page58_i148
#ISCELL
  mstr_standard offpage *
  page58_i149
#ISCELL
  mstr_standard tap *
  page58_i15
#ISCELL
  mstr_standard offpage *
  page58_i150
#ISCELL
  mstr_standard offpage *
  page58_i151
#ISCELL
  mstr_standard offpage *
  page58_i152
#ISCELL
  mstr_standard offpage *
  page58_i153
#ISCELL
  mstr_standard offpage *
  page58_i154
#ISCELL
  mstr_standard offpage *
  page58_i155
#ISCELL
  mstr_standard offpage *
  page58_i156
#ISCELL
  mstr_standard tap *
  page58_i157
#ISCELL
  mstr_standard tap *
  page58_i158
#ISCELL
  mstr_standard tap *
  page58_i159
#ISCELL
  mstr_standard tap *
  page58_i16
#ISCELL
  mstr_standard tap *
  page58_i160
#ISCELL
  mstr_standard tap *
  page58_i161
#ISCELL
  mstr_standard tap *
  page58_i162
#ISCELL
  mstr_standard tap *
  page58_i163
#ISCELL
  mstr_standard tap *
  page58_i164
#ISCELL
  mstr_standard tap *
  page58_i165
#ISCELL
  mstr_standard tap *
  page58_i166
#ISCELL
  mstr_standard tap *
  page58_i167
#ISCELL
  mstr_standard tap *
  page58_i168
#ISCELL
  mstr_standard tap *
  page58_i169
#ISCELL
  mstr_standard tap *
  page58_i17
#ISCELL
  mstr_standard tap *
  page58_i170
#ISCELL
  mstr_standard offpage *
  page58_i171
#CELL
  chpset_lib skx_ext_b *
  page58_i172
#ISCELL
  mstr_standard tap *
  page58_i18
#ISCELL
  mstr_standard tap *
  page58_i19
#ISCELL
  mstr_standard offpage *
  page58_i2
#ISCELL
  mstr_standard tap *
  page58_i20
#ISCELL
  mstr_standard tap *
  page58_i21
#ISCELL
  mstr_standard tap *
  page58_i22
#ISCELL
  mstr_standard tap *
  page58_i23
#ISCELL
  mstr_standard tap *
  page58_i24
#ISCELL
  mstr_standard tap *
  page58_i25
#ISCELL
  mstr_standard tap *
  page58_i26
#ISCELL
  mstr_standard tap *
  page58_i27
#ISCELL
  mstr_standard tap *
  page58_i28
#ISCELL
  mstr_standard tap *
  page58_i29
#ISCELL
  mstr_standard offpage *
  page58_i3
#ISCELL
  mstr_standard tap *
  page58_i31
#ISCELL
  mstr_standard tap *
  page58_i32
#ISCELL
  mstr_standard tap *
  page58_i33
#ISCELL
  mstr_standard tap *
  page58_i34
#ISCELL
  mstr_standard tap *
  page58_i35
#ISCELL
  mstr_standard tap *
  page58_i36
#ISCELL
  mstr_standard tap *
  page58_i37
#ISCELL
  mstr_standard tap *
  page58_i38
#ISCELL
  mstr_standard tap *
  page58_i39
#ISCELL
  mstr_standard offpage *
  page58_i4
#ISCELL
  mstr_standard tap *
  page58_i40
#ISCELL
  mstr_standard tap *
  page58_i41
#ISCELL
  mstr_standard tap *
  page58_i42
#ISCELL
  mstr_standard tap *
  page58_i43
#ISCELL
  mstr_standard tap *
  page58_i44
#ISCELL
  mstr_standard tap *
  page58_i45
#ISCELL
  mstr_standard tap *
  page58_i46
#ISCELL
  mstr_standard tap *
  page58_i47
#ISCELL
  mstr_standard tap *
  page58_i48
#ISCELL
  mstr_standard tap *
  page58_i49
#ISCELL
  mstr_standard tap *
  page58_i5
#ISCELL
  mstr_standard tap *
  page58_i50
#ISCELL
  mstr_standard tap *
  page58_i51
#ISCELL
  mstr_standard tap *
  page58_i52
#ISCELL
  mstr_standard tap *
  page58_i53
#ISCELL
  mstr_standard tap *
  page58_i54
#ISCELL
  mstr_standard tap *
  page58_i55
#ISCELL
  mstr_standard tap *
  page58_i56
#ISCELL
  mstr_standard tap *
  page58_i57
#ISCELL
  mstr_standard tap *
  page58_i58
#ISCELL
  mstr_standard tap *
  page58_i59
#ISCELL
  mstr_standard tap *
  page58_i6
#ISCELL
  mstr_standard tap *
  page58_i60
#ISCELL
  mstr_standard tap *
  page58_i61
#ISCELL
  mstr_standard tap *
  page58_i62
#ISCELL
  mstr_standard tap *
  page58_i63
#ISCELL
  mstr_standard tap *
  page58_i64
#ISCELL
  mstr_standard tap *
  page58_i65
#ISCELL
  mstr_standard tap *
  page58_i66
#ISCELL
  mstr_standard tap *
  page58_i67
#ISCELL
  mstr_standard tap *
  page58_i68
#ISCELL
  mstr_standard tap *
  page58_i69
#ISCELL
  mstr_standard tap *
  page58_i7
#ISCELL
  mstr_standard tap *
  page58_i70
#ISCELL
  mstr_standard tap *
  page58_i71
#ISCELL
  mstr_standard offpage *
  page58_i72
#ISCELL
  mstr_standard tap *
  page58_i73
#ISCELL
  mstr_standard tap *
  page58_i74
#ISCELL
  mstr_standard tap *
  page58_i75
#ISCELL
  mstr_standard tap *
  page58_i76
#ISCELL
  mstr_standard tap *
  page58_i77
#ISCELL
  mstr_standard tap *
  page58_i78
#ISCELL
  mstr_standard tap *
  page58_i79
#ISCELL
  mstr_standard tap *
  page58_i8
#ISCELL
  mstr_standard tap *
  page58_i80
#ISCELL
  mstr_standard tap *
  page58_i81
#ISCELL
  mstr_standard tap *
  page58_i82
#ISCELL
  mstr_standard tap *
  page58_i83
#ISCELL
  mstr_standard tap *
  page58_i84
#ISCELL
  mstr_standard tap *
  page58_i85
#ISCELL
  mstr_standard tap *
  page58_i86
#ISCELL
  mstr_standard tap *
  page58_i87
#ISCELL
  mstr_standard tap *
  page58_i88
#ISCELL
  mstr_standard tap *
  page58_i89
#ISCELL
  mstr_standard tap *
  page58_i9
#ISCELL
  mstr_standard tap *
  page58_i90
#ISCELL
  mstr_standard tap *
  page58_i91
#ISCELL
  mstr_standard tap *
  page58_i92
#ISCELL
  mstr_standard tap *
  page58_i93
#ISCELL
  mstr_standard tap *
  page58_i94
#ISCELL
  mstr_standard tap *
  page58_i95
#ISCELL
  mstr_standard tap *
  page58_i96
#ISCELL
  mstr_standard tap *
  page58_i97
#ISCELL
  mstr_standard tap *
  page58_i98
#ISCELL
  mstr_standard tap *
  page58_i99
#ISCELL
  mstr_misc prelim *
  *
#ISCELL
  mstr_symbols design_note *
  *
#ISCELL
  mstr_symbols intel_corp_bpage *
  *
#ISCELL
  mstr_standard offpage *
  page59_i1
#ISCELL
  mstr_standard tap *
  page59_i10
#ISCELL
  mstr_standard tap *
  page59_i100
#ISCELL
  mstr_standard tap *
  page59_i101
#ISCELL
  mstr_standard tap *
  page59_i102
#ISCELL
  mstr_standard tap *
  page59_i103
#ISCELL
  mstr_standard tap *
  page59_i104
#ISCELL
  mstr_standard tap *
  page59_i105
#ISCELL
  mstr_standard tap *
  page59_i106
#ISCELL
  mstr_standard tap *
  page59_i107
#ISCELL
  mstr_standard tap *
  page59_i108
#ISCELL
  mstr_standard tap *
  page59_i109
#ISCELL
  mstr_standard tap *
  page59_i11
#ISCELL
  mstr_standard tap *
  page59_i110
#ISCELL
  mstr_standard tap *
  page59_i111
#ISCELL
  mstr_standard tap *
  page59_i112
#ISCELL
  mstr_standard tap *
  page59_i113
#ISCELL
  mstr_standard tap *
  page59_i114
#ISCELL
  mstr_standard tap *
  page59_i115
#ISCELL
  mstr_standard tap *
  page59_i116
#ISCELL
  mstr_standard tap *
  page59_i117
#ISCELL
  mstr_standard tap *
  page59_i118
#ISCELL
  mstr_standard tap *
  page59_i119
#ISCELL
  mstr_standard tap *
  page59_i12
#ISCELL
  mstr_standard tap *
  page59_i120
#ISCELL
  mstr_standard tap *
  page59_i121
#ISCELL
  mstr_standard tap *
  page59_i122
#ISCELL
  mstr_standard tap *
  page59_i123
#ISCELL
  mstr_standard tap *
  page59_i124
#ISCELL
  mstr_standard tap *
  page59_i125
#ISCELL
  mstr_standard tap *
  page59_i126
#ISCELL
  mstr_standard tap *
  page59_i127
#ISCELL
  mstr_standard tap *
  page59_i128
#ISCELL
  mstr_standard tap *
  page59_i129
#ISCELL
  mstr_standard tap *
  page59_i13
#ISCELL
  mstr_standard tap *
  page59_i130
#ISCELL
  mstr_standard tap *
  page59_i131
#ISCELL
  mstr_standard tap *
  page59_i132
#ISCELL
  mstr_standard tap *
  page59_i133
#ISCELL
  mstr_standard tap *
  page59_i134
#ISCELL
  mstr_standard tap *
  page59_i135
#ISCELL
  mstr_standard tap *
  page59_i136
#ISCELL
  mstr_standard tap *
  page59_i137
#ISCELL
  mstr_standard tap *
  page59_i138
#ISCELL
  mstr_standard tap *
  page59_i139
#ISCELL
  mstr_standard tap *
  page59_i14
#ISCELL
  mstr_standard tap *
  page59_i140
#ISCELL
  mstr_standard tap *
  page59_i141
#ISCELL
  mstr_standard tap *
  page59_i142
#ISCELL
  mstr_standard tap *
  page59_i143
#ISCELL
  mstr_standard tap *
  page59_i144
#ISCELL
  mstr_standard tap *
  page59_i145
#ISCELL
  mstr_standard tap *
  page59_i146
#ISCELL
  mstr_standard offpage *
  page59_i147
#ISCELL
  mstr_standard offpage *
  page59_i148
#ISCELL
  mstr_standard offpage *
  page59_i149
#ISCELL
  mstr_standard tap *
  page59_i15
#ISCELL
  mstr_standard offpage *
  page59_i150
#ISCELL
  mstr_standard offpage *
  page59_i151
#ISCELL
  mstr_standard offpage *
  page59_i152
#ISCELL
  mstr_standard offpage *
  page59_i153
#ISCELL
  mstr_standard offpage *
  page59_i154
#ISCELL
  mstr_standard offpage *
  page59_i155
#ISCELL
  mstr_standard offpage *
  page59_i156
#ISCELL
  mstr_standard tap *
  page59_i157
#ISCELL
  mstr_standard tap *
  page59_i158
#ISCELL
  mstr_standard tap *
  page59_i159
#ISCELL
  mstr_standard tap *
  page59_i16
#ISCELL
  mstr_standard tap *
  page59_i160
#ISCELL
  mstr_standard tap *
  page59_i161
#ISCELL
  mstr_standard tap *
  page59_i162
#ISCELL
  mstr_standard tap *
  page59_i163
#ISCELL
  mstr_standard tap *
  page59_i164
#ISCELL
  mstr_standard tap *
  page59_i165
#ISCELL
  mstr_standard tap *
  page59_i166
#ISCELL
  mstr_standard tap *
  page59_i167
#ISCELL
  mstr_standard tap *
  page59_i168
#ISCELL
  mstr_standard tap *
  page59_i169
#ISCELL
  mstr_standard tap *
  page59_i17
#ISCELL
  mstr_standard tap *
  page59_i170
#ISCELL
  mstr_standard offpage *
  page59_i171
#CELL
  chpset_lib skx_ext_b *
  page59_i172
#ISCELL
  mstr_standard tap *
  page59_i18
#ISCELL
  mstr_standard tap *
  page59_i19
#ISCELL
  mstr_standard offpage *
  page59_i2
#ISCELL
  mstr_standard tap *
  page59_i20
#ISCELL
  mstr_standard tap *
  page59_i21
#ISCELL
  mstr_standard tap *
  page59_i22
#ISCELL
  mstr_standard tap *
  page59_i23
#ISCELL
  mstr_standard tap *
  page59_i24
#ISCELL
  mstr_standard tap *
  page59_i25
#ISCELL
  mstr_standard tap *
  page59_i26
#ISCELL
  mstr_standard tap *
  page59_i27
#ISCELL
  mstr_standard tap *
  page59_i28
#ISCELL
  mstr_standard tap *
  page59_i29
#ISCELL
  mstr_standard offpage *
  page59_i3
#ISCELL
  mstr_standard tap *
  page59_i31
#ISCELL
  mstr_standard tap *
  page59_i32
#ISCELL
  mstr_standard tap *
  page59_i33
#ISCELL
  mstr_standard tap *
  page59_i34
#ISCELL
  mstr_standard tap *
  page59_i35
#ISCELL
  mstr_standard tap *
  page59_i36
#ISCELL
  mstr_standard tap *
  page59_i37
#ISCELL
  mstr_standard tap *
  page59_i38
#ISCELL
  mstr_standard tap *
  page59_i39
#ISCELL
  mstr_standard offpage *
  page59_i4
#ISCELL
  mstr_standard tap *
  page59_i40
#ISCELL
  mstr_standard tap *
  page59_i41
#ISCELL
  mstr_standard tap *
  page59_i42
#ISCELL
  mstr_standard tap *
  page59_i43
#ISCELL
  mstr_standard tap *
  page59_i44
#ISCELL
  mstr_standard tap *
  page59_i45
#ISCELL
  mstr_standard tap *
  page59_i46
#ISCELL
  mstr_standard tap *
  page59_i47
#ISCELL
  mstr_standard tap *
  page59_i48
#ISCELL
  mstr_standard tap *
  page59_i49
#ISCELL
  mstr_standard tap *
  page59_i5
#ISCELL
  mstr_standard tap *
  page59_i50
#ISCELL
  mstr_standard tap *
  page59_i51
#ISCELL
  mstr_standard tap *
  page59_i52
#ISCELL
  mstr_standard tap *
  page59_i53
#ISCELL
  mstr_standard tap *
  page59_i54
#ISCELL
  mstr_standard tap *
  page59_i55
#ISCELL
  mstr_standard tap *
  page59_i56
#ISCELL
  mstr_standard tap *
  page59_i57
#ISCELL
  mstr_standard tap *
  page59_i58
#ISCELL
  mstr_standard tap *
  page59_i59
#ISCELL
  mstr_standard tap *
  page59_i6
#ISCELL
  mstr_standard tap *
  page59_i60
#ISCELL
  mstr_standard tap *
  page59_i61
#ISCELL
  mstr_standard tap *
  page59_i62
#ISCELL
  mstr_standard tap *
  page59_i63
#ISCELL
  mstr_standard tap *
  page59_i64
#ISCELL
  mstr_standard tap *
  page59_i65
#ISCELL
  mstr_standard tap *
  page59_i66
#ISCELL
  mstr_standard tap *
  page59_i67
#ISCELL
  mstr_standard tap *
  page59_i68
#ISCELL
  mstr_standard tap *
  page59_i69
#ISCELL
  mstr_standard tap *
  page59_i7
#ISCELL
  mstr_standard tap *
  page59_i70
#ISCELL
  mstr_standard tap *
  page59_i71
#ISCELL
  mstr_standard offpage *
  page59_i72
#ISCELL
  mstr_standard tap *
  page59_i73
#ISCELL
  mstr_standard tap *
  page59_i74
#ISCELL
  mstr_standard tap *
  page59_i75
#ISCELL
  mstr_standard tap *
  page59_i76
#ISCELL
  mstr_standard tap *
  page59_i77
#ISCELL
  mstr_standard tap *
  page59_i78
#ISCELL
  mstr_standard tap *
  page59_i79
#ISCELL
  mstr_standard tap *
  page59_i8
#ISCELL
  mstr_standard tap *
  page59_i80
#ISCELL
  mstr_standard tap *
  page59_i81
#ISCELL
  mstr_standard tap *
  page59_i82
#ISCELL
  mstr_standard tap *
  page59_i83
#ISCELL
  mstr_standard tap *
  page59_i84
#ISCELL
  mstr_standard tap *
  page59_i85
#ISCELL
  mstr_standard tap *
  page59_i86
#ISCELL
  mstr_standard tap *
  page59_i87
#ISCELL
  mstr_standard tap *
  page59_i88
#ISCELL
  mstr_standard tap *
  page59_i89
#ISCELL
  mstr_standard tap *
  page59_i9
#ISCELL
  mstr_standard tap *
  page59_i90
#ISCELL
  mstr_standard tap *
  page59_i91
#ISCELL
  mstr_standard tap *
  page59_i92
#ISCELL
  mstr_standard tap *
  page59_i93
#ISCELL
  mstr_standard tap *
  page59_i94
#ISCELL
  mstr_standard tap *
  page59_i95
#ISCELL
  mstr_standard tap *
  page59_i96
#ISCELL
  mstr_standard tap *
  page59_i97
#ISCELL
  mstr_standard tap *
  page59_i98
#ISCELL
  mstr_standard tap *
  page59_i99
#ISCELL
  mstr_misc prelim *
  *
#ISCELL
  mstr_symbols design_note *
  *
#ISCELL
  mstr_symbols intel_corp_bpage *
  *
#ISCELL
  mstr_standard offpage *
  page60_i1
#ISCELL
  mstr_standard tap *
  page60_i10
#ISCELL
  mstr_standard tap *
  page60_i100
#ISCELL
  mstr_standard tap *
  page60_i101
#ISCELL
  mstr_standard tap *
  page60_i102
#ISCELL
  mstr_standard tap *
  page60_i103
#ISCELL
  mstr_standard tap *
  page60_i104
#ISCELL
  mstr_standard tap *
  page60_i105
#ISCELL
  mstr_standard tap *
  page60_i106
#ISCELL
  mstr_standard tap *
  page60_i107
#ISCELL
  mstr_standard tap *
  page60_i108
#ISCELL
  mstr_standard tap *
  page60_i109
#ISCELL
  mstr_standard tap *
  page60_i11
#ISCELL
  mstr_standard tap *
  page60_i110
#ISCELL
  mstr_standard tap *
  page60_i111
#ISCELL
  mstr_standard tap *
  page60_i112
#ISCELL
  mstr_standard tap *
  page60_i113
#ISCELL
  mstr_standard tap *
  page60_i114
#ISCELL
  mstr_standard tap *
  page60_i115
#ISCELL
  mstr_standard tap *
  page60_i116
#ISCELL
  mstr_standard tap *
  page60_i117
#ISCELL
  mstr_standard tap *
  page60_i118
#ISCELL
  mstr_standard tap *
  page60_i119
#ISCELL
  mstr_standard tap *
  page60_i12
#ISCELL
  mstr_standard tap *
  page60_i120
#ISCELL
  mstr_standard tap *
  page60_i121
#ISCELL
  mstr_standard tap *
  page60_i122
#ISCELL
  mstr_standard tap *
  page60_i123
#ISCELL
  mstr_standard tap *
  page60_i124
#ISCELL
  mstr_standard tap *
  page60_i125
#ISCELL
  mstr_standard tap *
  page60_i126
#ISCELL
  mstr_standard tap *
  page60_i127
#ISCELL
  mstr_standard tap *
  page60_i128
#ISCELL
  mstr_standard tap *
  page60_i129
#ISCELL
  mstr_standard tap *
  page60_i13
#ISCELL
  mstr_standard tap *
  page60_i130
#ISCELL
  mstr_standard tap *
  page60_i131
#ISCELL
  mstr_standard tap *
  page60_i132
#ISCELL
  mstr_standard tap *
  page60_i133
#ISCELL
  mstr_standard tap *
  page60_i134
#ISCELL
  mstr_standard tap *
  page60_i135
#ISCELL
  mstr_standard tap *
  page60_i136
#ISCELL
  mstr_standard tap *
  page60_i137
#ISCELL
  mstr_standard tap *
  page60_i138
#ISCELL
  mstr_standard tap *
  page60_i139
#ISCELL
  mstr_standard tap *
  page60_i14
#ISCELL
  mstr_standard tap *
  page60_i140
#ISCELL
  mstr_standard tap *
  page60_i141
#ISCELL
  mstr_standard tap *
  page60_i142
#ISCELL
  mstr_standard tap *
  page60_i143
#ISCELL
  mstr_standard tap *
  page60_i144
#ISCELL
  mstr_standard tap *
  page60_i145
#ISCELL
  mstr_standard tap *
  page60_i146
#ISCELL
  mstr_standard offpage *
  page60_i147
#ISCELL
  mstr_standard offpage *
  page60_i148
#ISCELL
  mstr_standard offpage *
  page60_i149
#ISCELL
  mstr_standard tap *
  page60_i15
#ISCELL
  mstr_standard offpage *
  page60_i150
#ISCELL
  mstr_standard offpage *
  page60_i151
#ISCELL
  mstr_standard offpage *
  page60_i152
#ISCELL
  mstr_standard offpage *
  page60_i153
#ISCELL
  mstr_standard offpage *
  page60_i154
#ISCELL
  mstr_standard offpage *
  page60_i155
#ISCELL
  mstr_standard offpage *
  page60_i156
#ISCELL
  mstr_standard tap *
  page60_i157
#ISCELL
  mstr_standard tap *
  page60_i158
#ISCELL
  mstr_standard tap *
  page60_i159
#ISCELL
  mstr_standard tap *
  page60_i16
#ISCELL
  mstr_standard tap *
  page60_i160
#ISCELL
  mstr_standard tap *
  page60_i161
#ISCELL
  mstr_standard tap *
  page60_i162
#ISCELL
  mstr_standard tap *
  page60_i163
#ISCELL
  mstr_standard tap *
  page60_i164
#ISCELL
  mstr_standard tap *
  page60_i165
#ISCELL
  mstr_standard tap *
  page60_i166
#ISCELL
  mstr_standard tap *
  page60_i167
#ISCELL
  mstr_standard tap *
  page60_i168
#ISCELL
  mstr_standard tap *
  page60_i169
#ISCELL
  mstr_standard tap *
  page60_i17
#ISCELL
  mstr_standard tap *
  page60_i170
#ISCELL
  mstr_standard offpage *
  page60_i171
#CELL
  chpset_lib skx_ext_b *
  page60_i172
#ISCELL
  mstr_standard tap *
  page60_i18
#ISCELL
  mstr_standard tap *
  page60_i19
#ISCELL
  mstr_standard offpage *
  page60_i2
#ISCELL
  mstr_standard tap *
  page60_i20
#ISCELL
  mstr_standard tap *
  page60_i21
#ISCELL
  mstr_standard tap *
  page60_i22
#ISCELL
  mstr_standard tap *
  page60_i23
#ISCELL
  mstr_standard tap *
  page60_i24
#ISCELL
  mstr_standard tap *
  page60_i25
#ISCELL
  mstr_standard tap *
  page60_i26
#ISCELL
  mstr_standard tap *
  page60_i27
#ISCELL
  mstr_standard tap *
  page60_i28
#ISCELL
  mstr_standard tap *
  page60_i29
#ISCELL
  mstr_standard offpage *
  page60_i3
#ISCELL
  mstr_standard tap *
  page60_i31
#ISCELL
  mstr_standard tap *
  page60_i32
#ISCELL
  mstr_standard tap *
  page60_i33
#ISCELL
  mstr_standard tap *
  page60_i34
#ISCELL
  mstr_standard tap *
  page60_i35
#ISCELL
  mstr_standard tap *
  page60_i36
#ISCELL
  mstr_standard tap *
  page60_i37
#ISCELL
  mstr_standard tap *
  page60_i38
#ISCELL
  mstr_standard tap *
  page60_i39
#ISCELL
  mstr_standard offpage *
  page60_i4
#ISCELL
  mstr_standard tap *
  page60_i40
#ISCELL
  mstr_standard tap *
  page60_i41
#ISCELL
  mstr_standard tap *
  page60_i42
#ISCELL
  mstr_standard tap *
  page60_i43
#ISCELL
  mstr_standard tap *
  page60_i44
#ISCELL
  mstr_standard tap *
  page60_i45
#ISCELL
  mstr_standard tap *
  page60_i46
#ISCELL
  mstr_standard tap *
  page60_i47
#ISCELL
  mstr_standard tap *
  page60_i48
#ISCELL
  mstr_standard tap *
  page60_i49
#ISCELL
  mstr_standard tap *
  page60_i5
#ISCELL
  mstr_standard tap *
  page60_i50
#ISCELL
  mstr_standard tap *
  page60_i51
#ISCELL
  mstr_standard tap *
  page60_i52
#ISCELL
  mstr_standard tap *
  page60_i53
#ISCELL
  mstr_standard tap *
  page60_i54
#ISCELL
  mstr_standard tap *
  page60_i55
#ISCELL
  mstr_standard tap *
  page60_i56
#ISCELL
  mstr_standard tap *
  page60_i57
#ISCELL
  mstr_standard tap *
  page60_i58
#ISCELL
  mstr_standard tap *
  page60_i59
#ISCELL
  mstr_standard tap *
  page60_i6
#ISCELL
  mstr_standard tap *
  page60_i60
#ISCELL
  mstr_standard tap *
  page60_i61
#ISCELL
  mstr_standard tap *
  page60_i62
#ISCELL
  mstr_standard tap *
  page60_i63
#ISCELL
  mstr_standard tap *
  page60_i64
#ISCELL
  mstr_standard tap *
  page60_i65
#ISCELL
  mstr_standard tap *
  page60_i66
#ISCELL
  mstr_standard tap *
  page60_i67
#ISCELL
  mstr_standard tap *
  page60_i68
#ISCELL
  mstr_standard tap *
  page60_i69
#ISCELL
  mstr_standard tap *
  page60_i7
#ISCELL
  mstr_standard tap *
  page60_i70
#ISCELL
  mstr_standard tap *
  page60_i71
#ISCELL
  mstr_standard offpage *
  page60_i72
#ISCELL
  mstr_standard tap *
  page60_i73
#ISCELL
  mstr_standard tap *
  page60_i74
#ISCELL
  mstr_standard tap *
  page60_i75
#ISCELL
  mstr_standard tap *
  page60_i76
#ISCELL
  mstr_standard tap *
  page60_i77
#ISCELL
  mstr_standard tap *
  page60_i78
#ISCELL
  mstr_standard tap *
  page60_i79
#ISCELL
  mstr_standard tap *
  page60_i8
#ISCELL
  mstr_standard tap *
  page60_i80
#ISCELL
  mstr_standard tap *
  page60_i81
#ISCELL
  mstr_standard tap *
  page60_i82
#ISCELL
  mstr_standard tap *
  page60_i83
#ISCELL
  mstr_standard tap *
  page60_i84
#ISCELL
  mstr_standard tap *
  page60_i85
#ISCELL
  mstr_standard tap *
  page60_i86
#ISCELL
  mstr_standard tap *
  page60_i87
#ISCELL
  mstr_standard tap *
  page60_i88
#ISCELL
  mstr_standard tap *
  page60_i89
#ISCELL
  mstr_standard tap *
  page60_i9
#ISCELL
  mstr_standard tap *
  page60_i90
#ISCELL
  mstr_standard tap *
  page60_i91
#ISCELL
  mstr_standard tap *
  page60_i92
#ISCELL
  mstr_standard tap *
  page60_i93
#ISCELL
  mstr_standard tap *
  page60_i94
#ISCELL
  mstr_standard tap *
  page60_i95
#ISCELL
  mstr_standard tap *
  page60_i96
#ISCELL
  mstr_standard tap *
  page60_i97
#ISCELL
  mstr_standard tap *
  page60_i98
#ISCELL
  mstr_standard tap *
  page60_i99
#ISCELL
  mstr_misc prelim *
  *
#ISCELL
  mstr_symbols design_note *
  *
#ISCELL
  mstr_symbols intel_corp_bpage *
  *
#ISCELL
  mstr_standard offpage *
  page61_i1
#ISCELL
  mstr_standard tap *
  page61_i10
#ISCELL
  mstr_standard tap *
  page61_i100
#ISCELL
  mstr_standard tap *
  page61_i101
#ISCELL
  mstr_standard tap *
  page61_i102
#ISCELL
  mstr_standard tap *
  page61_i103
#ISCELL
  mstr_standard tap *
  page61_i104
#ISCELL
  mstr_standard tap *
  page61_i105
#ISCELL
  mstr_standard tap *
  page61_i106
#ISCELL
  mstr_standard tap *
  page61_i107
#ISCELL
  mstr_standard tap *
  page61_i108
#ISCELL
  mstr_standard tap *
  page61_i109
#ISCELL
  mstr_standard tap *
  page61_i11
#ISCELL
  mstr_standard tap *
  page61_i110
#ISCELL
  mstr_standard tap *
  page61_i111
#ISCELL
  mstr_standard tap *
  page61_i112
#ISCELL
  mstr_standard tap *
  page61_i113
#ISCELL
  mstr_standard tap *
  page61_i114
#ISCELL
  mstr_standard tap *
  page61_i115
#ISCELL
  mstr_standard tap *
  page61_i116
#ISCELL
  mstr_standard tap *
  page61_i117
#ISCELL
  mstr_standard tap *
  page61_i118
#ISCELL
  mstr_standard tap *
  page61_i119
#ISCELL
  mstr_standard tap *
  page61_i12
#ISCELL
  mstr_standard tap *
  page61_i120
#ISCELL
  mstr_standard tap *
  page61_i121
#ISCELL
  mstr_standard tap *
  page61_i122
#ISCELL
  mstr_standard tap *
  page61_i123
#ISCELL
  mstr_standard tap *
  page61_i124
#ISCELL
  mstr_standard tap *
  page61_i125
#ISCELL
  mstr_standard tap *
  page61_i126
#ISCELL
  mstr_standard tap *
  page61_i127
#ISCELL
  mstr_standard tap *
  page61_i128
#ISCELL
  mstr_standard tap *
  page61_i129
#ISCELL
  mstr_standard tap *
  page61_i13
#ISCELL
  mstr_standard tap *
  page61_i130
#ISCELL
  mstr_standard tap *
  page61_i131
#ISCELL
  mstr_standard tap *
  page61_i132
#ISCELL
  mstr_standard tap *
  page61_i133
#ISCELL
  mstr_standard tap *
  page61_i134
#ISCELL
  mstr_standard tap *
  page61_i135
#ISCELL
  mstr_standard tap *
  page61_i136
#ISCELL
  mstr_standard tap *
  page61_i137
#ISCELL
  mstr_standard tap *
  page61_i138
#ISCELL
  mstr_standard tap *
  page61_i139
#ISCELL
  mstr_standard tap *
  page61_i14
#ISCELL
  mstr_standard tap *
  page61_i140
#ISCELL
  mstr_standard tap *
  page61_i141
#ISCELL
  mstr_standard tap *
  page61_i142
#ISCELL
  mstr_standard tap *
  page61_i143
#ISCELL
  mstr_standard tap *
  page61_i144
#ISCELL
  mstr_standard tap *
  page61_i145
#ISCELL
  mstr_standard tap *
  page61_i146
#ISCELL
  mstr_standard offpage *
  page61_i147
#ISCELL
  mstr_standard offpage *
  page61_i148
#ISCELL
  mstr_standard offpage *
  page61_i149
#ISCELL
  mstr_standard tap *
  page61_i15
#ISCELL
  mstr_standard offpage *
  page61_i150
#ISCELL
  mstr_standard offpage *
  page61_i151
#ISCELL
  mstr_standard offpage *
  page61_i152
#ISCELL
  mstr_standard offpage *
  page61_i153
#ISCELL
  mstr_standard offpage *
  page61_i154
#ISCELL
  mstr_standard offpage *
  page61_i155
#ISCELL
  mstr_standard offpage *
  page61_i156
#ISCELL
  mstr_standard tap *
  page61_i157
#ISCELL
  mstr_standard tap *
  page61_i158
#ISCELL
  mstr_standard tap *
  page61_i159
#ISCELL
  mstr_standard tap *
  page61_i16
#ISCELL
  mstr_standard tap *
  page61_i160
#ISCELL
  mstr_standard tap *
  page61_i161
#ISCELL
  mstr_standard tap *
  page61_i162
#ISCELL
  mstr_standard tap *
  page61_i163
#ISCELL
  mstr_standard tap *
  page61_i164
#ISCELL
  mstr_standard tap *
  page61_i165
#ISCELL
  mstr_standard tap *
  page61_i166
#ISCELL
  mstr_standard tap *
  page61_i167
#ISCELL
  mstr_standard tap *
  page61_i168
#ISCELL
  mstr_standard tap *
  page61_i169
#ISCELL
  mstr_standard tap *
  page61_i17
#ISCELL
  mstr_standard tap *
  page61_i170
#ISCELL
  mstr_standard offpage *
  page61_i171
#CELL
  chpset_lib skx_ext_b *
  page61_i172
#ISCELL
  mstr_standard tap *
  page61_i18
#ISCELL
  mstr_standard tap *
  page61_i19
#ISCELL
  mstr_standard offpage *
  page61_i2
#ISCELL
  mstr_standard tap *
  page61_i20
#ISCELL
  mstr_standard tap *
  page61_i21
#ISCELL
  mstr_standard tap *
  page61_i22
#ISCELL
  mstr_standard tap *
  page61_i23
#ISCELL
  mstr_standard tap *
  page61_i24
#ISCELL
  mstr_standard tap *
  page61_i25
#ISCELL
  mstr_standard tap *
  page61_i26
#ISCELL
  mstr_standard tap *
  page61_i27
#ISCELL
  mstr_standard tap *
  page61_i28
#ISCELL
  mstr_standard tap *
  page61_i29
#ISCELL
  mstr_standard offpage *
  page61_i3
#ISCELL
  mstr_standard tap *
  page61_i31
#ISCELL
  mstr_standard tap *
  page61_i32
#ISCELL
  mstr_standard tap *
  page61_i33
#ISCELL
  mstr_standard tap *
  page61_i34
#ISCELL
  mstr_standard tap *
  page61_i35
#ISCELL
  mstr_standard tap *
  page61_i36
#ISCELL
  mstr_standard tap *
  page61_i37
#ISCELL
  mstr_standard tap *
  page61_i38
#ISCELL
  mstr_standard tap *
  page61_i39
#ISCELL
  mstr_standard offpage *
  page61_i4
#ISCELL
  mstr_standard tap *
  page61_i40
#ISCELL
  mstr_standard tap *
  page61_i41
#ISCELL
  mstr_standard tap *
  page61_i42
#ISCELL
  mstr_standard tap *
  page61_i43
#ISCELL
  mstr_standard tap *
  page61_i44
#ISCELL
  mstr_standard tap *
  page61_i45
#ISCELL
  mstr_standard tap *
  page61_i46
#ISCELL
  mstr_standard tap *
  page61_i47
#ISCELL
  mstr_standard tap *
  page61_i48
#ISCELL
  mstr_standard tap *
  page61_i49
#ISCELL
  mstr_standard tap *
  page61_i5
#ISCELL
  mstr_standard tap *
  page61_i50
#ISCELL
  mstr_standard tap *
  page61_i51
#ISCELL
  mstr_standard tap *
  page61_i52
#ISCELL
  mstr_standard tap *
  page61_i53
#ISCELL
  mstr_standard tap *
  page61_i54
#ISCELL
  mstr_standard tap *
  page61_i55
#ISCELL
  mstr_standard tap *
  page61_i56
#ISCELL
  mstr_standard tap *
  page61_i57
#ISCELL
  mstr_standard tap *
  page61_i58
#ISCELL
  mstr_standard tap *
  page61_i59
#ISCELL
  mstr_standard tap *
  page61_i6
#ISCELL
  mstr_standard tap *
  page61_i60
#ISCELL
  mstr_standard tap *
  page61_i61
#ISCELL
  mstr_standard tap *
  page61_i62
#ISCELL
  mstr_standard tap *
  page61_i63
#ISCELL
  mstr_standard tap *
  page61_i64
#ISCELL
  mstr_standard tap *
  page61_i65
#ISCELL
  mstr_standard tap *
  page61_i66
#ISCELL
  mstr_standard tap *
  page61_i67
#ISCELL
  mstr_standard tap *
  page61_i68
#ISCELL
  mstr_standard tap *
  page61_i69
#ISCELL
  mstr_standard tap *
  page61_i7
#ISCELL
  mstr_standard tap *
  page61_i70
#ISCELL
  mstr_standard tap *
  page61_i71
#ISCELL
  mstr_standard offpage *
  page61_i72
#ISCELL
  mstr_standard tap *
  page61_i73
#ISCELL
  mstr_standard tap *
  page61_i74
#ISCELL
  mstr_standard tap *
  page61_i75
#ISCELL
  mstr_standard tap *
  page61_i76
#ISCELL
  mstr_standard tap *
  page61_i77
#ISCELL
  mstr_standard tap *
  page61_i78
#ISCELL
  mstr_standard tap *
  page61_i79
#ISCELL
  mstr_standard tap *
  page61_i8
#ISCELL
  mstr_standard tap *
  page61_i80
#ISCELL
  mstr_standard tap *
  page61_i81
#ISCELL
  mstr_standard tap *
  page61_i82
#ISCELL
  mstr_standard tap *
  page61_i83
#ISCELL
  mstr_standard tap *
  page61_i84
#ISCELL
  mstr_standard tap *
  page61_i85
#ISCELL
  mstr_standard tap *
  page61_i86
#ISCELL
  mstr_standard tap *
  page61_i87
#ISCELL
  mstr_standard tap *
  page61_i88
#ISCELL
  mstr_standard tap *
  page61_i89
#ISCELL
  mstr_standard tap *
  page61_i9
#ISCELL
  mstr_standard tap *
  page61_i90
#ISCELL
  mstr_standard tap *
  page61_i91
#ISCELL
  mstr_standard tap *
  page61_i92
#ISCELL
  mstr_standard tap *
  page61_i93
#ISCELL
  mstr_standard tap *
  page61_i94
#ISCELL
  mstr_standard tap *
  page61_i95
#ISCELL
  mstr_standard tap *
  page61_i96
#ISCELL
  mstr_standard tap *
  page61_i97
#ISCELL
  mstr_standard tap *
  page61_i98
#ISCELL
  mstr_standard tap *
  page61_i99
#ISCELL
  mstr_misc prelim *
  *
#ISCELL
  mstr_symbols design_note *
  *
#ISCELL
  mstr_symbols intel_corp_bpage *
  *
#ISCELL
  mstr_standard offpage *
  page62_i1
#ISCELL
  mstr_standard tap *
  page62_i10
#ISCELL
  mstr_standard tap *
  page62_i100
#ISCELL
  mstr_standard tap *
  page62_i101
#ISCELL
  mstr_standard tap *
  page62_i102
#ISCELL
  mstr_standard tap *
  page62_i103
#ISCELL
  mstr_standard tap *
  page62_i104
#ISCELL
  mstr_standard tap *
  page62_i105
#ISCELL
  mstr_standard tap *
  page62_i106
#ISCELL
  mstr_standard tap *
  page62_i107
#ISCELL
  mstr_standard tap *
  page62_i108
#ISCELL
  mstr_standard tap *
  page62_i109
#ISCELL
  mstr_standard tap *
  page62_i11
#ISCELL
  mstr_standard tap *
  page62_i110
#ISCELL
  mstr_standard tap *
  page62_i111
#ISCELL
  mstr_standard tap *
  page62_i112
#ISCELL
  mstr_standard tap *
  page62_i113
#ISCELL
  mstr_standard tap *
  page62_i114
#ISCELL
  mstr_standard tap *
  page62_i115
#ISCELL
  mstr_standard tap *
  page62_i116
#ISCELL
  mstr_standard tap *
  page62_i117
#ISCELL
  mstr_standard tap *
  page62_i118
#ISCELL
  mstr_standard tap *
  page62_i119
#ISCELL
  mstr_standard tap *
  page62_i12
#ISCELL
  mstr_standard tap *
  page62_i120
#ISCELL
  mstr_standard tap *
  page62_i121
#ISCELL
  mstr_standard tap *
  page62_i122
#ISCELL
  mstr_standard tap *
  page62_i123
#ISCELL
  mstr_standard tap *
  page62_i124
#ISCELL
  mstr_standard tap *
  page62_i125
#ISCELL
  mstr_standard tap *
  page62_i126
#ISCELL
  mstr_standard tap *
  page62_i127
#ISCELL
  mstr_standard tap *
  page62_i128
#ISCELL
  mstr_standard tap *
  page62_i129
#ISCELL
  mstr_standard tap *
  page62_i13
#ISCELL
  mstr_standard tap *
  page62_i130
#ISCELL
  mstr_standard tap *
  page62_i131
#ISCELL
  mstr_standard tap *
  page62_i132
#ISCELL
  mstr_standard tap *
  page62_i133
#ISCELL
  mstr_standard tap *
  page62_i134
#ISCELL
  mstr_standard tap *
  page62_i135
#ISCELL
  mstr_standard tap *
  page62_i136
#ISCELL
  mstr_standard tap *
  page62_i137
#ISCELL
  mstr_standard tap *
  page62_i138
#ISCELL
  mstr_standard tap *
  page62_i139
#ISCELL
  mstr_standard tap *
  page62_i14
#ISCELL
  mstr_standard tap *
  page62_i140
#ISCELL
  mstr_standard tap *
  page62_i141
#ISCELL
  mstr_standard tap *
  page62_i142
#ISCELL
  mstr_standard tap *
  page62_i143
#ISCELL
  mstr_standard tap *
  page62_i144
#ISCELL
  mstr_standard tap *
  page62_i145
#ISCELL
  mstr_standard tap *
  page62_i146
#ISCELL
  mstr_standard offpage *
  page62_i147
#ISCELL
  mstr_standard offpage *
  page62_i148
#ISCELL
  mstr_standard offpage *
  page62_i149
#ISCELL
  mstr_standard tap *
  page62_i15
#ISCELL
  mstr_standard offpage *
  page62_i150
#ISCELL
  mstr_standard offpage *
  page62_i151
#ISCELL
  mstr_standard offpage *
  page62_i152
#ISCELL
  mstr_standard offpage *
  page62_i153
#ISCELL
  mstr_standard offpage *
  page62_i154
#ISCELL
  mstr_standard offpage *
  page62_i155
#ISCELL
  mstr_standard offpage *
  page62_i156
#ISCELL
  mstr_standard tap *
  page62_i157
#ISCELL
  mstr_standard tap *
  page62_i158
#ISCELL
  mstr_standard tap *
  page62_i159
#ISCELL
  mstr_standard tap *
  page62_i16
#ISCELL
  mstr_standard tap *
  page62_i160
#ISCELL
  mstr_standard tap *
  page62_i161
#ISCELL
  mstr_standard tap *
  page62_i162
#ISCELL
  mstr_standard tap *
  page62_i163
#ISCELL
  mstr_standard tap *
  page62_i164
#ISCELL
  mstr_standard tap *
  page62_i165
#ISCELL
  mstr_standard tap *
  page62_i166
#ISCELL
  mstr_standard tap *
  page62_i167
#ISCELL
  mstr_standard tap *
  page62_i168
#ISCELL
  mstr_standard tap *
  page62_i169
#ISCELL
  mstr_standard tap *
  page62_i17
#ISCELL
  mstr_standard tap *
  page62_i170
#ISCELL
  mstr_standard offpage *
  page62_i171
#CELL
  chpset_lib skx_ext_b *
  page62_i172
#ISCELL
  mstr_standard tap *
  page62_i18
#ISCELL
  mstr_standard tap *
  page62_i19
#ISCELL
  mstr_standard offpage *
  page62_i2
#ISCELL
  mstr_standard tap *
  page62_i20
#ISCELL
  mstr_standard tap *
  page62_i21
#ISCELL
  mstr_standard tap *
  page62_i22
#ISCELL
  mstr_standard tap *
  page62_i23
#ISCELL
  mstr_standard tap *
  page62_i24
#ISCELL
  mstr_standard tap *
  page62_i25
#ISCELL
  mstr_standard tap *
  page62_i26
#ISCELL
  mstr_standard tap *
  page62_i27
#ISCELL
  mstr_standard tap *
  page62_i28
#ISCELL
  mstr_standard tap *
  page62_i29
#ISCELL
  mstr_standard offpage *
  page62_i3
#ISCELL
  mstr_standard tap *
  page62_i31
#ISCELL
  mstr_standard tap *
  page62_i32
#ISCELL
  mstr_standard tap *
  page62_i33
#ISCELL
  mstr_standard tap *
  page62_i34
#ISCELL
  mstr_standard tap *
  page62_i35
#ISCELL
  mstr_standard tap *
  page62_i36
#ISCELL
  mstr_standard tap *
  page62_i37
#ISCELL
  mstr_standard tap *
  page62_i38
#ISCELL
  mstr_standard tap *
  page62_i39
#ISCELL
  mstr_standard offpage *
  page62_i4
#ISCELL
  mstr_standard tap *
  page62_i40
#ISCELL
  mstr_standard tap *
  page62_i41
#ISCELL
  mstr_standard tap *
  page62_i42
#ISCELL
  mstr_standard tap *
  page62_i43
#ISCELL
  mstr_standard tap *
  page62_i44
#ISCELL
  mstr_standard tap *
  page62_i45
#ISCELL
  mstr_standard tap *
  page62_i46
#ISCELL
  mstr_standard tap *
  page62_i47
#ISCELL
  mstr_standard tap *
  page62_i48
#ISCELL
  mstr_standard tap *
  page62_i49
#ISCELL
  mstr_standard tap *
  page62_i5
#ISCELL
  mstr_standard tap *
  page62_i50
#ISCELL
  mstr_standard tap *
  page62_i51
#ISCELL
  mstr_standard tap *
  page62_i52
#ISCELL
  mstr_standard tap *
  page62_i53
#ISCELL
  mstr_standard tap *
  page62_i54
#ISCELL
  mstr_standard tap *
  page62_i55
#ISCELL
  mstr_standard tap *
  page62_i56
#ISCELL
  mstr_standard tap *
  page62_i57
#ISCELL
  mstr_standard tap *
  page62_i58
#ISCELL
  mstr_standard tap *
  page62_i59
#ISCELL
  mstr_standard tap *
  page62_i6
#ISCELL
  mstr_standard tap *
  page62_i60
#ISCELL
  mstr_standard tap *
  page62_i61
#ISCELL
  mstr_standard tap *
  page62_i62
#ISCELL
  mstr_standard tap *
  page62_i63
#ISCELL
  mstr_standard tap *
  page62_i64
#ISCELL
  mstr_standard tap *
  page62_i65
#ISCELL
  mstr_standard tap *
  page62_i66
#ISCELL
  mstr_standard tap *
  page62_i67
#ISCELL
  mstr_standard tap *
  page62_i68
#ISCELL
  mstr_standard tap *
  page62_i69
#ISCELL
  mstr_standard tap *
  page62_i7
#ISCELL
  mstr_standard tap *
  page62_i70
#ISCELL
  mstr_standard tap *
  page62_i71
#ISCELL
  mstr_standard offpage *
  page62_i72
#ISCELL
  mstr_standard tap *
  page62_i73
#ISCELL
  mstr_standard tap *
  page62_i74
#ISCELL
  mstr_standard tap *
  page62_i75
#ISCELL
  mstr_standard tap *
  page62_i76
#ISCELL
  mstr_standard tap *
  page62_i77
#ISCELL
  mstr_standard tap *
  page62_i78
#ISCELL
  mstr_standard tap *
  page62_i79
#ISCELL
  mstr_standard tap *
  page62_i8
#ISCELL
  mstr_standard tap *
  page62_i80
#ISCELL
  mstr_standard tap *
  page62_i81
#ISCELL
  mstr_standard tap *
  page62_i82
#ISCELL
  mstr_standard tap *
  page62_i83
#ISCELL
  mstr_standard tap *
  page62_i84
#ISCELL
  mstr_standard tap *
  page62_i85
#ISCELL
  mstr_standard tap *
  page62_i86
#ISCELL
  mstr_standard tap *
  page62_i87
#ISCELL
  mstr_standard tap *
  page62_i88
#ISCELL
  mstr_standard tap *
  page62_i89
#ISCELL
  mstr_standard tap *
  page62_i9
#ISCELL
  mstr_standard tap *
  page62_i90
#ISCELL
  mstr_standard tap *
  page62_i91
#ISCELL
  mstr_standard tap *
  page62_i92
#ISCELL
  mstr_standard tap *
  page62_i93
#ISCELL
  mstr_standard tap *
  page62_i94
#ISCELL
  mstr_standard tap *
  page62_i95
#ISCELL
  mstr_standard tap *
  page62_i96
#ISCELL
  mstr_standard tap *
  page62_i97
#ISCELL
  mstr_standard tap *
  page62_i98
#ISCELL
  mstr_standard tap *
  page62_i99
#ISCELL
  mstr_misc prelim *
  *
#ISCELL
  mstr_symbols design_note *
  *
#ISCELL
  mstr_symbols intel_corp_bpage *
  *
#ISCELL
  mstr_standard offpage *
  page63_i10
#ISCELL
  mstr_standard offpage *
  page63_i12
#ISCELL
  mstr_standard offpage *
  page63_i15
#ISCELL
  mstr_standard offpage *
  page63_i16
#ISCELL
  mstr_standard offpage *
  page63_i20
#ISCELL
  mstr_standard offpage *
  page63_i21
#ISCELL
  mstr_standard offpage *
  page63_i22
#CELL
  chpset_lib skx_ext_b *
  page63_i23
#ISCELL
  mstr_standard offpage *
  page63_i26
#ISCELL
  mstr_symbols vcc_core *
  page63_i27
#ISCELL
  mstr_standard offpage *
  page63_i7
#ISCELL
  mstr_standard offpage *
  page63_i9
#ISCELL
  mstr_misc prelim *
  *
#ISCELL
  mstr_symbols design_note *
  *
#ISCELL
  mstr_symbols intel_corp_bpage *
  *
#ISCELL
  mstr_standard tap *
  page64_i10
#ISCELL
  mstr_standard tap *
  page64_i11
#ISCELL
  mstr_standard tap *
  page64_i12
#ISCELL
  mstr_standard tap *
  page64_i13
#ISCELL
  mstr_standard tap *
  page64_i14
#ISCELL
  mstr_standard tap *
  page64_i15
#ISCELL
  mstr_standard tap *
  page64_i16
#ISCELL
  mstr_standard tap *
  page64_i17
#ISCELL
  mstr_standard tap *
  page64_i18
#ISCELL
  mstr_standard tap *
  page64_i19
#ISCELL
  mstr_standard tap *
  page64_i20
#ISCELL
  mstr_standard tap *
  page64_i21
#ISCELL
  mstr_standard tap *
  page64_i22
#ISCELL
  mstr_standard tap *
  page64_i23
#ISCELL
  mstr_standard tap *
  page64_i24
#ISCELL
  mstr_standard tap *
  page64_i25
#ISCELL
  mstr_standard tap *
  page64_i26
#ISCELL
  mstr_standard tap *
  page64_i27
#ISCELL
  mstr_standard tap *
  page64_i28
#ISCELL
  mstr_standard tap *
  page64_i29
#ISCELL
  mstr_standard tap *
  page64_i3
#ISCELL
  mstr_standard tap *
  page64_i30
#ISCELL
  mstr_standard tap *
  page64_i31
#ISCELL
  mstr_standard tap *
  page64_i32
#ISCELL
  mstr_standard tap *
  page64_i33
#ISCELL
  mstr_standard tap *
  page64_i34
#ISCELL
  mstr_standard tap *
  page64_i35
#ISCELL
  mstr_standard tap *
  page64_i36
#ISCELL
  mstr_standard tap *
  page64_i37
#ISCELL
  mstr_standard tap *
  page64_i38
#ISCELL
  mstr_standard tap *
  page64_i39
#ISCELL
  mstr_standard tap *
  page64_i4
#ISCELL
  mstr_standard tap *
  page64_i40
#ISCELL
  mstr_standard tap *
  page64_i41
#ISCELL
  mstr_standard tap *
  page64_i42
#ISCELL
  mstr_standard tap *
  page64_i43
#ISCELL
  mstr_standard tap *
  page64_i44
#ISCELL
  mstr_standard tap *
  page64_i45
#ISCELL
  mstr_standard tap *
  page64_i46
#ISCELL
  mstr_standard tap *
  page64_i47
#ISCELL
  mstr_standard tap *
  page64_i48
#ISCELL
  mstr_standard tap *
  page64_i49
#ISCELL
  mstr_standard tap *
  page64_i5
#ISCELL
  mstr_standard tap *
  page64_i50
#ISCELL
  mstr_standard tap *
  page64_i51
#ISCELL
  mstr_standard tap *
  page64_i52
#ISCELL
  mstr_standard tap *
  page64_i53
#ISCELL
  mstr_standard tap *
  page64_i54
#ISCELL
  mstr_standard tap *
  page64_i55
#ISCELL
  mstr_standard tap *
  page64_i56
#ISCELL
  mstr_standard tap *
  page64_i57
#ISCELL
  mstr_standard tap *
  page64_i58
#ISCELL
  mstr_standard tap *
  page64_i59
#ISCELL
  mstr_standard tap *
  page64_i6
#ISCELL
  mstr_standard tap *
  page64_i60
#ISCELL
  mstr_standard tap *
  page64_i61
#ISCELL
  mstr_standard tap *
  page64_i62
#ISCELL
  mstr_standard tap *
  page64_i63
#ISCELL
  mstr_standard tap *
  page64_i64
#ISCELL
  mstr_standard tap *
  page64_i65
#ISCELL
  mstr_standard tap *
  page64_i66
#ISCELL
  mstr_standard tap *
  page64_i67
#CELL
  chpset_lib skx_ext_b *
  page64_i68
#ISCELL
  mstr_standard tap *
  page64_i7
#ISCELL
  mstr_standard tap *
  page64_i8
#ISCELL
  mstr_misc prelim *
  *
#ISCELL
  mstr_symbols design_note *
  *
#ISCELL
  mstr_symbols intel_corp_bpage *
  *
#ISCELL
  mstr_standard tap *
  page65_i11
#ISCELL
  mstr_standard tap *
  page65_i12
#ISCELL
  mstr_standard tap *
  page65_i13
#ISCELL
  mstr_standard tap *
  page65_i14
#ISCELL
  mstr_standard tap *
  page65_i15
#ISCELL
  mstr_standard tap *
  page65_i16
#ISCELL
  mstr_standard tap *
  page65_i17
#ISCELL
  mstr_standard tap *
  page65_i18
#ISCELL
  mstr_standard tap *
  page65_i19
#ISCELL
  mstr_standard tap *
  page65_i20
#ISCELL
  mstr_standard tap *
  page65_i21
#ISCELL
  mstr_standard tap *
  page65_i22
#ISCELL
  mstr_standard tap *
  page65_i23
#ISCELL
  mstr_standard tap *
  page65_i24
#ISCELL
  mstr_standard tap *
  page65_i25
#ISCELL
  mstr_standard tap *
  page65_i26
#ISCELL
  mstr_standard tap *
  page65_i27
#ISCELL
  mstr_standard tap *
  page65_i28
#ISCELL
  mstr_standard tap *
  page65_i29
#ISCELL
  mstr_standard tap *
  page65_i3
#ISCELL
  mstr_standard tap *
  page65_i30
#ISCELL
  mstr_standard tap *
  page65_i31
#ISCELL
  mstr_standard tap *
  page65_i32
#ISCELL
  mstr_standard tap *
  page65_i33
#ISCELL
  mstr_standard tap *
  page65_i34
#ISCELL
  mstr_standard tap *
  page65_i35
#ISCELL
  mstr_standard tap *
  page65_i36
#ISCELL
  mstr_standard tap *
  page65_i37
#ISCELL
  mstr_standard tap *
  page65_i38
#ISCELL
  mstr_standard tap *
  page65_i39
#ISCELL
  mstr_standard tap *
  page65_i4
#ISCELL
  mstr_standard tap *
  page65_i40
#ISCELL
  mstr_standard tap *
  page65_i41
#ISCELL
  mstr_standard tap *
  page65_i42
#ISCELL
  mstr_standard tap *
  page65_i43
#ISCELL
  mstr_standard tap *
  page65_i44
#ISCELL
  mstr_standard tap *
  page65_i45
#ISCELL
  mstr_standard tap *
  page65_i46
#ISCELL
  mstr_standard tap *
  page65_i47
#ISCELL
  mstr_standard tap *
  page65_i48
#ISCELL
  mstr_standard tap *
  page65_i49
#ISCELL
  mstr_standard tap *
  page65_i5
#ISCELL
  mstr_standard tap *
  page65_i50
#ISCELL
  mstr_standard tap *
  page65_i51
#ISCELL
  mstr_standard tap *
  page65_i52
#ISCELL
  mstr_standard tap *
  page65_i53
#ISCELL
  mstr_standard tap *
  page65_i54
#ISCELL
  mstr_standard tap *
  page65_i55
#ISCELL
  mstr_standard tap *
  page65_i56
#ISCELL
  mstr_standard tap *
  page65_i57
#ISCELL
  mstr_standard tap *
  page65_i58
#ISCELL
  mstr_standard tap *
  page65_i59
#ISCELL
  mstr_standard tap *
  page65_i6
#ISCELL
  mstr_standard tap *
  page65_i60
#ISCELL
  mstr_standard tap *
  page65_i61
#ISCELL
  mstr_standard tap *
  page65_i62
#ISCELL
  mstr_standard tap *
  page65_i63
#ISCELL
  mstr_standard tap *
  page65_i64
#ISCELL
  mstr_standard tap *
  page65_i65
#ISCELL
  mstr_standard tap *
  page65_i66
#ISCELL
  mstr_standard tap *
  page65_i67
#CELL
  chpset_lib skx_ext_b *
  page65_i68
#ISCELL
  mstr_standard tap *
  page65_i7
#ISCELL
  mstr_standard tap *
  page65_i8
#ISCELL
  mstr_standard tap *
  page65_i9
#ISCELL
  mstr_misc prelim *
  *
#ISCELL
  mstr_symbols design_note *
  *
#ISCELL
  mstr_symbols intel_corp_bpage *
  *
#ISCELL
  mstr_standard tap *
  page66_i10
#ISCELL
  mstr_standard tap *
  page66_i11
#ISCELL
  mstr_standard tap *
  page66_i12
#ISCELL
  mstr_standard tap *
  page66_i13
#ISCELL
  mstr_standard tap *
  page66_i14
#ISCELL
  mstr_standard tap *
  page66_i15
#ISCELL
  mstr_standard tap *
  page66_i16
#ISCELL
  mstr_standard tap *
  page66_i17
#ISCELL
  mstr_standard tap *
  page66_i18
#ISCELL
  mstr_standard tap *
  page66_i19
#ISCELL
  mstr_standard tap *
  page66_i20
#ISCELL
  mstr_standard tap *
  page66_i21
#ISCELL
  mstr_standard tap *
  page66_i22
#ISCELL
  mstr_standard tap *
  page66_i23
#ISCELL
  mstr_standard tap *
  page66_i24
#ISCELL
  mstr_standard tap *
  page66_i25
#ISCELL
  mstr_standard tap *
  page66_i26
#ISCELL
  mstr_standard tap *
  page66_i27
#ISCELL
  mstr_standard tap *
  page66_i28
#ISCELL
  mstr_standard tap *
  page66_i29
#ISCELL
  mstr_standard tap *
  page66_i30
#ISCELL
  mstr_standard tap *
  page66_i31
#ISCELL
  mstr_standard tap *
  page66_i32
#ISCELL
  mstr_standard tap *
  page66_i33
#ISCELL
  mstr_standard tap *
  page66_i34
#ISCELL
  mstr_standard tap *
  page66_i35
#ISCELL
  mstr_standard tap *
  page66_i36
#ISCELL
  mstr_standard tap *
  page66_i37
#ISCELL
  mstr_standard tap *
  page66_i38
#ISCELL
  mstr_standard tap *
  page66_i39
#ISCELL
  mstr_standard tap *
  page66_i40
#ISCELL
  mstr_standard tap *
  page66_i41
#ISCELL
  mstr_standard tap *
  page66_i42
#ISCELL
  mstr_standard tap *
  page66_i43
#ISCELL
  mstr_standard tap *
  page66_i44
#ISCELL
  mstr_standard tap *
  page66_i45
#ISCELL
  mstr_standard tap *
  page66_i46
#ISCELL
  mstr_standard tap *
  page66_i47
#ISCELL
  mstr_standard tap *
  page66_i48
#ISCELL
  mstr_standard tap *
  page66_i49
#ISCELL
  mstr_standard tap *
  page66_i50
#ISCELL
  mstr_standard tap *
  page66_i51
#ISCELL
  mstr_standard tap *
  page66_i52
#ISCELL
  mstr_standard tap *
  page66_i53
#ISCELL
  mstr_standard tap *
  page66_i54
#ISCELL
  mstr_standard tap *
  page66_i55
#ISCELL
  mstr_standard tap *
  page66_i56
#ISCELL
  mstr_standard tap *
  page66_i57
#ISCELL
  mstr_standard tap *
  page66_i58
#ISCELL
  mstr_standard tap *
  page66_i59
#ISCELL
  mstr_standard tap *
  page66_i60
#ISCELL
  mstr_standard tap *
  page66_i61
#ISCELL
  mstr_standard tap *
  page66_i62
#ISCELL
  mstr_standard tap *
  page66_i63
#ISCELL
  mstr_standard tap *
  page66_i64
#ISCELL
  mstr_standard tap *
  page66_i65
#ISCELL
  mstr_standard tap *
  page66_i66
#ISCELL
  mstr_standard tap *
  page66_i67
#ISCELL
  mstr_standard tap *
  page66_i68
#ISCELL
  mstr_standard tap *
  page66_i69
#ISCELL
  mstr_standard tap *
  page66_i70
#ISCELL
  mstr_standard tap *
  page66_i71
#ISCELL
  mstr_standard tap *
  page66_i72
#ISCELL
  mstr_standard tap *
  page66_i73
#ISCELL
  mstr_standard offpage *
  page66_i75
#ISCELL
  mstr_standard offpage *
  page66_i76
#ISCELL
  mstr_standard offpage *
  page66_i77
#ISCELL
  mstr_standard offpage *
  page66_i78
#ISCELL
  mstr_standard offpage *
  page66_i80
#ISCELL
  mstr_standard offpage *
  page66_i81
#ISCELL
  mstr_standard offpage *
  page66_i82
#ISCELL
  mstr_standard offpage *
  page66_i83
#CELL
  chpset_lib skx_ext_b *
  page66_i84
#ISCELL
  mstr_misc prelim *
  *
#ISCELL
  mstr_symbols design_note *
  *
#ISCELL
  mstr_symbols intel_corp_bpage *
  *
#ISCELL
  mstr_standard offpage *
  page67_i1
#ISCELL
  mstr_standard tap *
  page67_i100
#ISCELL
  mstr_standard tap *
  page67_i101
#ISCELL
  mstr_standard tap *
  page67_i102
#ISCELL
  mstr_standard tap *
  page67_i103
#ISCELL
  mstr_standard tap *
  page67_i104
#ISCELL
  mstr_standard tap *
  page67_i105
#ISCELL
  mstr_standard tap *
  page67_i106
#ISCELL
  mstr_standard tap *
  page67_i107
#ISCELL
  mstr_standard tap *
  page67_i108
#ISCELL
  mstr_standard tap *
  page67_i109
#ISCELL
  mstr_standard tap *
  page67_i110
#ISCELL
  mstr_standard tap *
  page67_i111
#ISCELL
  mstr_standard tap *
  page67_i112
#ISCELL
  mstr_standard tap *
  page67_i113
#ISCELL
  mstr_standard tap *
  page67_i114
#ISCELL
  mstr_standard tap *
  page67_i115
#ISCELL
  mstr_standard tap *
  page67_i116
#ISCELL
  mstr_standard tap *
  page67_i117
#ISCELL
  mstr_standard tap *
  page67_i118
#ISCELL
  mstr_standard tap *
  page67_i119
#ISCELL
  mstr_standard tap *
  page67_i120
#ISCELL
  mstr_standard tap *
  page67_i121
#ISCELL
  mstr_standard tap *
  page67_i122
#ISCELL
  mstr_standard tap *
  page67_i123
#ISCELL
  mstr_standard tap *
  page67_i124
#ISCELL
  mstr_standard tap *
  page67_i125
#ISCELL
  mstr_standard tap *
  page67_i126
#ISCELL
  mstr_standard tap *
  page67_i127
#ISCELL
  mstr_standard tap *
  page67_i128
#ISCELL
  mstr_standard tap *
  page67_i129
#ISCELL
  mstr_standard tap *
  page67_i130
#ISCELL
  mstr_standard tap *
  page67_i131
#CELL
  chpset_lib skx_ext_b *
  page67_i132
#ISCELL
  mstr_standard tap *
  page67_i14
#ISCELL
  mstr_standard tap *
  page67_i16
#ISCELL
  mstr_standard offpage *
  page67_i2
#ISCELL
  mstr_standard tap *
  page67_i20
#ISCELL
  mstr_standard tap *
  page67_i21
#ISCELL
  mstr_standard tap *
  page67_i26
#ISCELL
  mstr_standard tap *
  page67_i27
#ISCELL
  mstr_standard tap *
  page67_i28
#ISCELL
  mstr_standard tap *
  page67_i34
#ISCELL
  mstr_standard tap *
  page67_i36
#ISCELL
  mstr_standard tap *
  page67_i40
#ISCELL
  mstr_standard tap *
  page67_i41
#ISCELL
  mstr_standard tap *
  page67_i42
#ISCELL
  mstr_standard tap *
  page67_i43
#ISCELL
  mstr_standard tap *
  page67_i46
#ISCELL
  mstr_standard tap *
  page67_i48
#ISCELL
  mstr_standard tap *
  page67_i49
#ISCELL
  mstr_standard tap *
  page67_i5
#ISCELL
  mstr_standard tap *
  page67_i51
#ISCELL
  mstr_standard tap *
  page67_i53
#ISCELL
  mstr_standard tap *
  page67_i54
#ISCELL
  mstr_standard tap *
  page67_i58
#ISCELL
  mstr_standard tap *
  page67_i6
#ISCELL
  mstr_standard tap *
  page67_i61
#ISCELL
  mstr_standard tap *
  page67_i62
#ISCELL
  mstr_standard tap *
  page67_i66
#ISCELL
  mstr_standard tap *
  page67_i67
#ISCELL
  mstr_standard tap *
  page67_i69
#ISCELL
  mstr_standard tap *
  page67_i7
#ISCELL
  mstr_standard tap *
  page67_i72
#ISCELL
  mstr_standard tap *
  page67_i73
#ISCELL
  mstr_standard tap *
  page67_i74
#ISCELL
  mstr_standard tap *
  page67_i78
#ISCELL
  mstr_standard tap *
  page67_i81
#ISCELL
  mstr_standard tap *
  page67_i83
#ISCELL
  mstr_standard offpage *
  page67_i84
#ISCELL
  mstr_standard offpage *
  page67_i85
#ISCELL
  mstr_standard tap *
  page67_i86
#ISCELL
  mstr_standard tap *
  page67_i87
#ISCELL
  mstr_standard tap *
  page67_i88
#ISCELL
  mstr_standard tap *
  page67_i89
#ISCELL
  mstr_standard tap *
  page67_i90
#ISCELL
  mstr_standard tap *
  page67_i91
#ISCELL
  mstr_standard tap *
  page67_i92
#ISCELL
  mstr_standard tap *
  page67_i93
#ISCELL
  mstr_standard tap *
  page67_i94
#ISCELL
  mstr_standard tap *
  page67_i95
#ISCELL
  mstr_standard tap *
  page67_i96
#ISCELL
  mstr_standard tap *
  page67_i97
#ISCELL
  mstr_standard tap *
  page67_i98
#ISCELL
  mstr_standard tap *
  page67_i99
#ISCELL
  mstr_misc prelim *
  *
#ISCELL
  mstr_symbols design_note *
  *
#ISCELL
  mstr_symbols intel_corp_bpage *
  *
#ISCELL
  mstr_standard offpage *
  page68_i1
#ISCELL
  mstr_standard tap *
  page68_i10
#ISCELL
  mstr_standard tap *
  page68_i100
#ISCELL
  mstr_standard tap *
  page68_i101
#ISCELL
  mstr_standard tap *
  page68_i102
#ISCELL
  mstr_standard tap *
  page68_i103
#ISCELL
  mstr_standard tap *
  page68_i104
#ISCELL
  mstr_standard tap *
  page68_i105
#ISCELL
  mstr_standard tap *
  page68_i106
#ISCELL
  mstr_standard tap *
  page68_i107
#ISCELL
  mstr_standard tap *
  page68_i108
#ISCELL
  mstr_standard tap *
  page68_i109
#ISCELL
  mstr_standard tap *
  page68_i11
#ISCELL
  mstr_standard tap *
  page68_i110
#ISCELL
  mstr_standard tap *
  page68_i111
#ISCELL
  mstr_standard tap *
  page68_i112
#ISCELL
  mstr_standard tap *
  page68_i113
#ISCELL
  mstr_standard tap *
  page68_i114
#ISCELL
  mstr_standard tap *
  page68_i115
#ISCELL
  mstr_standard tap *
  page68_i116
#ISCELL
  mstr_standard tap *
  page68_i117
#ISCELL
  mstr_standard tap *
  page68_i118
#ISCELL
  mstr_standard tap *
  page68_i119
#ISCELL
  mstr_standard tap *
  page68_i120
#ISCELL
  mstr_standard tap *
  page68_i121
#ISCELL
  mstr_standard tap *
  page68_i122
#ISCELL
  mstr_standard tap *
  page68_i123
#ISCELL
  mstr_standard tap *
  page68_i124
#CELL
  chpset_lib skx_ext_b *
  page68_i125
#ISCELL
  mstr_standard tap *
  page68_i13
#ISCELL
  mstr_standard tap *
  page68_i14
#ISCELL
  mstr_standard tap *
  page68_i18
#ISCELL
  mstr_standard offpage *
  page68_i2
#ISCELL
  mstr_standard tap *
  page68_i21
#ISCELL
  mstr_standard tap *
  page68_i22
#ISCELL
  mstr_standard tap *
  page68_i26
#ISCELL
  mstr_standard tap *
  page68_i27
#ISCELL
  mstr_standard tap *
  page68_i28
#ISCELL
  mstr_standard tap *
  page68_i29
#ISCELL
  mstr_standard tap *
  page68_i30
#ISCELL
  mstr_standard tap *
  page68_i31
#ISCELL
  mstr_standard tap *
  page68_i32
#ISCELL
  mstr_standard tap *
  page68_i33
#ISCELL
  mstr_standard tap *
  page68_i34
#ISCELL
  mstr_standard tap *
  page68_i35
#ISCELL
  mstr_standard tap *
  page68_i36
#ISCELL
  mstr_standard tap *
  page68_i37
#ISCELL
  mstr_standard tap *
  page68_i38
#ISCELL
  mstr_standard tap *
  page68_i39
#ISCELL
  mstr_standard tap *
  page68_i40
#ISCELL
  mstr_standard tap *
  page68_i41
#ISCELL
  mstr_standard tap *
  page68_i42
#ISCELL
  mstr_standard tap *
  page68_i43
#ISCELL
  mstr_standard tap *
  page68_i46
#ISCELL
  mstr_standard tap *
  page68_i47
#ISCELL
  mstr_standard tap *
  page68_i48
#ISCELL
  mstr_standard tap *
  page68_i5
#ISCELL
  mstr_standard tap *
  page68_i54
#ISCELL
  mstr_standard tap *
  page68_i56
#ISCELL
  mstr_standard tap *
  page68_i6
#ISCELL
  mstr_standard tap *
  page68_i60
#ISCELL
  mstr_standard tap *
  page68_i61
#ISCELL
  mstr_standard tap *
  page68_i66
#ISCELL
  mstr_standard tap *
  page68_i67
#ISCELL
  mstr_standard tap *
  page68_i69
#ISCELL
  mstr_standard tap *
  page68_i74
#ISCELL
  mstr_standard tap *
  page68_i76
#ISCELL
  mstr_standard tap *
  page68_i80
#ISCELL
  mstr_standard tap *
  page68_i82
#ISCELL
  mstr_standard offpage *
  page68_i84
#ISCELL
  mstr_standard offpage *
  page68_i85
#ISCELL
  mstr_standard tap *
  page68_i86
#ISCELL
  mstr_standard tap *
  page68_i87
#ISCELL
  mstr_standard tap *
  page68_i88
#ISCELL
  mstr_standard tap *
  page68_i89
#ISCELL
  mstr_standard tap *
  page68_i90
#ISCELL
  mstr_standard tap *
  page68_i91
#ISCELL
  mstr_standard tap *
  page68_i92
#ISCELL
  mstr_standard tap *
  page68_i93
#ISCELL
  mstr_standard tap *
  page68_i94
#ISCELL
  mstr_standard tap *
  page68_i95
#ISCELL
  mstr_standard tap *
  page68_i96
#ISCELL
  mstr_standard tap *
  page68_i97
#ISCELL
  mstr_standard tap *
  page68_i98
#ISCELL
  mstr_standard tap *
  page68_i99
#ISCELL
  mstr_misc prelim *
  *
#ISCELL
  mstr_symbols design_note *
  *
#ISCELL
  mstr_symbols intel_corp_bpage *
  *
#CELL
  chpset_lib skx_ext_b *
  page69_i1
#ISCELL
  mstr_symbols gnd *
  page69_i2
#ISCELL
  mstr_misc prelim *
  *
#ISCELL
  mstr_symbols design_note *
  *
#ISCELL
  mstr_symbols intel_corp_bpage *
  *
#CELL
  chpset_lib skx_ext_b *
  page70_i10
#ISCELL
  mstr_standard offpage *
  page70_i11
#ISCELL
  mstr_symbols vcc_core *
  page70_i12
#ISCELL
  mstr_symbols vcc_core *
  page70_i13
#ISCELL
  mstr_symbols vcc_core *
  page70_i15
#ISCELL
  mstr_symbols vcc_core *
  page70_i16
#ISCELL
  mstr_standard offpage *
  page70_i7
#CELL
  chpset_lib skx_ext_b *
  page70_i9
#ISCELL
  mstr_misc dns *
  *
#ISCELL
  mstr_misc prelim *
  *
#ISCELL
  mstr_symbols design_note *
  *
#ISCELL
  mstr_symbols intel_corp_bpage *
  *
#ISCELL
  mstr_symbols pvccin_cpu1 *
  page71_i35
#ISCELL
  mstr_symbols pvccin_cpu1 *
  page71_i36
#ISCELL
  mstr_standard offpage *
  page71_i38
#ISCELL
  mstr_standard offpage *
  page71_i39
#ISCELL
  mstr_symbols pvccin_cpu1 *
  page71_i40
#ISCELL
  mstr_symbols pvccin_cpu1 *
  page71_i41
#ISCELL
  mstr_symbols gnd *
  page71_i42
#CELL
  mstr_discrete res *
  page71_i43
#ISCELL
  mstr_symbols pvccin_cpu1 *
  page71_i45
#CELL
  mstr_discrete res *
  page71_i49
#CELL
  chpset_lib skx_ext_b *
  page71_i50
#CELL
  chpset_lib skx_ext_b *
  page71_i51
#ISCELL
  mstr_symbols pvccio_cpu1 *
  page71_i52
#CELL
  mstr_discrete res *
  page71_i53
#ISCELL
  mstr_misc prelim *
  *
#ISCELL
  mstr_symbols design_note *
  *
#ISCELL
  mstr_symbols intel_corp_bpage *
  *
#ISCELL
  mstr_symbols pvddq_ghj *
  page72_i14
#ISCELL
  mstr_symbols pvddq_klm *
  page72_i15
#ISCELL
  mstr_symbols pvccio_cpu1 *
  page72_i17
#ISCELL
  mstr_symbols pvccio_cpu1 *
  page72_i18
#ISCELL
  mstr_symbols pvsa_cpu1 *
  page72_i22
#ISCELL
  mstr_symbols gnd *
  page72_i23
#CELL
  mstr_discrete cap *
  page72_i25
#ISCELL
  mstr_symbols vcc_core *
  page72_i28
#ISCELL
  mstr_symbols vcc_core *
  page72_i29
#CELL
  chpset_lib skx_ext_b *
  page72_i32
#CELL
  chpset_lib skx_ext_b *
  page72_i33
#ISCELL
  mstr_symbols pvpp_ghj *
  page72_i38
#ISCELL
  mstr_symbols vcc_core *
  page72_i39
#ISCELL
  mstr_symbols p3v3_stby *
  page72_i40
#ISCELL
  mstr_misc prelim *
  *
#ISCELL
  mstr_symbols design_note *
  *
#ISCELL
  mstr_symbols intel_corp_bpage *
  *
#ISCELL
  mstr_symbols vcc_core *
  page73_i104
#ISCELL
  mstr_symbols vcc_core *
  page73_i105
#CELL
  chpset_lib skx_ext_b *
  page73_i107
#ISCELL
  mstr_symbols vcc_core *
  page73_i108
#ISCELL
  mstr_standard offpage *
  page73_i109
#ISCELL
  mstr_symbols pvccio_cpu1 *
  page73_i22
#ISCELL
  mstr_standard offpage *
  page73_i91
#ISCELL
  mstr_standard offpage *
  page73_i92
#ISCELL
  mstr_standard offpage *
  page73_i93
#ISCELL
  mstr_standard offpage *
  page73_i94
#ISCELL
  mstr_standard offpage *
  page73_i95
#ISCELL
  mstr_standard offpage *
  page73_i96
#ISCELL
  mstr_standard offpage *
  page73_i97
#ISCELL
  mstr_standard offpage *
  page73_i98
#ISCELL
  mstr_misc prelim *
  *
#ISCELL
  mstr_symbols design_note *
  *
#ISCELL
  mstr_symbols intel_corp_bpage *
  *
#ISCELL
  mstr_symbols gnd *
  page74_i1
#ISCELL
  mstr_symbols gnd *
  page74_i11
#ISCELL
  mstr_symbols gnd *
  page74_i12
#ISCELL
  mstr_symbols gnd *
  page74_i14
#CELL
  chpset_lib skx_ext_b *
  page74_i20
#CELL
  chpset_lib skx_ext_b *
  page74_i21
#CELL
  chpset_lib skx_ext_b *
  page74_i22
#CELL
  chpset_lib skx_ext_b *
  page74_i23
#ISCELL
  mstr_symbols gnd *
  page74_i3
#ISCELL
  mstr_symbols gnd *
  page74_i4
#ISCELL
  mstr_symbols gnd *
  page74_i6
#ISCELL
  mstr_symbols gnd *
  page74_i9
#ISCELL
  mstr_misc prelim *
  *
#ISCELL
  mstr_symbols design_note *
  *
#ISCELL
  mstr_symbols intel_corp_bpage *
  *
#ISCELL
  mstr_symbols gnd *
  page75_i10
#ISCELL
  mstr_symbols gnd *
  page75_i11
#ISCELL
  mstr_symbols gnd *
  page75_i12
#ISCELL
  mstr_symbols gnd *
  page75_i13
#ISCELL
  mstr_symbols gnd *
  page75_i14
#ISCELL
  mstr_symbols gnd *
  page75_i15
#ISCELL
  mstr_symbols gnd *
  page75_i16
#CELL
  chpset_lib skx_ext_b *
  page75_i17
#CELL
  chpset_lib skx_ext_b *
  page75_i18
#CELL
  chpset_lib skx_ext_b *
  page75_i19
#CELL
  chpset_lib skx_ext_b *
  page75_i20
#ISCELL
  mstr_symbols gnd *
  page75_i9
#ISCELL
  mstr_symbols design_note *
  *
#ISCELL
  mstr_symbols intel_corp_bpage *
  *
#CELL
  dev_discrete cap_a *
  page76_i1
#CELL
  dev_discrete cap_a *
  page76_i10
#CELL
  mstr_discrete cap *
  page76_i103
#CELL
  mstr_discrete cap *
  page76_i107
#CELL
  dev_discrete cap_a *
  page76_i108
#ISCELL
  mstr_symbols gnd *
  page76_i109
#CELL
  dev_discrete cap_a *
  page76_i112
#ISCELL
  mstr_symbols gnd *
  page76_i113
#CELL
  dev_discrete cap_a *
  page76_i114
#CELL
  mstr_discrete cap *
  page76_i118
#CELL
  dev_discrete cap_a *
  page76_i119
#CELL
  dev_discrete cap_a *
  page76_i122
#CELL
  dev_discrete cap_a *
  page76_i124
#CELL
  mstr_discrete cap *
  page76_i125
#CELL
  mstr_discrete cap *
  page76_i127
#CELL
  mstr_discrete cap *
  page76_i129
#ISCELL
  mstr_symbols gnd *
  page76_i130
#CELL
  mstr_discrete cap *
  page76_i132
#ISCELL
  mstr_symbols gnd *
  page76_i134
#CELL
  mstr_discrete cap *
  page76_i137
#CELL
  mstr_discrete cap *
  page76_i139
#ISCELL
  mstr_symbols pvccin_cpu1 *
  page76_i143
#ISCELL
  mstr_symbols pvccin_cpu1 *
  page76_i144
#ISCELL
  mstr_symbols pvccin_cpu1 *
  page76_i145
#ISCELL
  mstr_symbols pvccin_cpu1 *
  page76_i146
#ISCELL
  mstr_symbols pvccin_cpu1 *
  page76_i147
#CELL
  dev_discrete cap_a *
  page76_i15
#ISCELL
  mstr_symbols pvccin_cpu1 *
  page76_i153
#ISCELL
  mstr_symbols pvccin_cpu1 *
  page76_i154
#ISCELL
  mstr_symbols pvccin_cpu1 *
  page76_i155
#ISCELL
  mstr_symbols pvccin_cpu1 *
  page76_i156
#ISCELL
  mstr_symbols pvccin_cpu1 *
  page76_i157
#ISCELL
  mstr_symbols pvccin_cpu1 *
  page76_i158
#CELL
  dev_discrete cap_a *
  page76_i159
#ISCELL
  mstr_symbols gnd *
  page76_i16
#CELL
  dev_discrete cap_a *
  page76_i160
#CELL
  dev_discrete cap_a *
  page76_i161
#ISCELL
  mstr_symbols vcc_core *
  page76_i162
#ISCELL
  mstr_symbols vcc_core *
  page76_i163
#CELL
  dev_discrete cap_a *
  page76_i164
#CELL
  dev_discrete cap_a *
  page76_i165
#CELL
  dev_discrete cap_a *
  page76_i166
#ISCELL
  mstr_symbols pvccio_cpu1 *
  page76_i167
#CELL
  dev_discrete cap_a *
  page76_i169
#CELL
  dev_discrete cap_a *
  page76_i170
#CELL
  dev_discrete cap_a *
  page76_i171
#CELL
  dev_discrete cap_a *
  page76_i172
#CELL
  dev_discrete cap_a *
  page76_i174
#CELL
  dev_discrete cap_a *
  page76_i175
#CELL
  dev_discrete cap_a *
  page76_i176
#CELL
  dev_discrete cap_a *
  page76_i179
#CELL
  dev_discrete cap_a *
  page76_i18
#CELL
  dev_discrete cap_a *
  page76_i196
#CELL
  dev_discrete cap_a *
  page76_i197
#CELL
  dev_discrete cap_a *
  page76_i198
#CELL
  dev_discrete cap_a *
  page76_i199
#ISCELL
  mstr_symbols gnd *
  page76_i2
#CELL
  dev_discrete cap_a *
  page76_i206
#CELL
  dev_discrete cap_a *
  page76_i207
#CELL
  dev_discrete cap_a *
  page76_i208
#ISCELL
  mstr_symbols vcc_core *
  page76_i209
#ISCELL
  mstr_symbols gnd *
  page76_i210
#CELL
  mstr_discrete cap *
  page76_i215
#CELL
  mstr_discrete cap *
  page76_i217
#ISCELL
  mstr_symbols gnd *
  page76_i224
#ISCELL
  mstr_symbols gnd *
  page76_i228
#ISCELL
  mstr_symbols pvccin_cpu1 *
  page76_i229
#ISCELL
  mstr_symbols gnd *
  page76_i231
#ISCELL
  mstr_symbols gnd *
  page76_i233
#ISCELL
  mstr_symbols gnd *
  page76_i24
#ISCELL
  mstr_symbols gnd *
  page76_i240
#ISCELL
  mstr_symbols gnd *
  page76_i241
#ISCELL
  mstr_symbols pvccin_cpu1 *
  page76_i244
#CELL
  mstr_discrete cap *
  page76_i245
#CELL
  mstr_discrete cap *
  page76_i246
#CELL
  mstr_discrete cap *
  page76_i247
#CELL
  mstr_discrete cap *
  page76_i248
#CELL
  mstr_discrete cap *
  page76_i249
#CELL
  mstr_discrete cap *
  page76_i250
#CELL
  mstr_discrete cap *
  page76_i251
#CELL
  mstr_discrete cap *
  page76_i252
#ISCELL
  mstr_symbols gnd *
  page76_i253
#CELL
  dev_discrete cap_a *
  page76_i254
#CELL
  dev_discrete cap_a *
  page76_i256
#ISCELL
  mstr_symbols vcc_core *
  page76_i257
#CELL
  mstr_discrete cap *
  page76_i258
#CELL
  mstr_discrete cap *
  page76_i259
#CELL
  mstr_discrete cap *
  page76_i260
#CELL
  mstr_discrete cap *
  page76_i261
#CELL
  mstr_discrete cap *
  page76_i262
#CELL
  mstr_discrete cap *
  page76_i263
#CELL
  mstr_discrete cap *
  page76_i264
#CELL
  mstr_discrete cap *
  page76_i265
#CELL
  mstr_discrete cap *
  page76_i266
#CELL
  mstr_discrete cap *
  page76_i267
#CELL
  mstr_discrete cap *
  page76_i268
#CELL
  mstr_discrete cap *
  page76_i269
#CELL
  mstr_discrete cap *
  page76_i270
#CELL
  mstr_discrete cap *
  page76_i271
#CELL
  mstr_discrete cap *
  page76_i272
#CELL
  mstr_discrete cap *
  page76_i273
#CELL
  mstr_discrete cap *
  page76_i274
#CELL
  mstr_discrete cap *
  page76_i29
#CELL
  dev_discrete cap_a *
  page76_i3
#ISCELL
  mstr_symbols gnd *
  page76_i30
#CELL
  mstr_discrete cap *
  page76_i33
#ISCELL
  mstr_symbols gnd *
  page76_i36
#CELL
  mstr_discrete cap *
  page76_i37
#CELL
  dev_discrete cap_a *
  page76_i4
#ISCELL
  mstr_symbols pvsa_cpu1 *
  page76_i41
#CELL
  mstr_discrete cap *
  page76_i42
#CELL
  mstr_discrete cap *
  page76_i43
#ISCELL
  mstr_symbols pvccio_cpu1 *
  page76_i47
#CELL
  dev_discrete cap_a *
  page76_i5
#CELL
  mstr_discrete cap *
  page76_i51
#CELL
  mstr_discrete cap *
  page76_i52
#ISCELL
  mstr_symbols gnd *
  page76_i53
#ISCELL
  mstr_symbols pvsa_cpu1 *
  page76_i57
#CELL
  dev_discrete cap_a *
  page76_i59
#ISCELL
  mstr_symbols gnd *
  page76_i60
#CELL
  dev_discrete cap_a *
  page76_i61
#CELL
  dev_discrete cap_a *
  page76_i63
#CELL
  dev_discrete cap_a *
  page76_i65
#CELL
  dev_discrete cap_a *
  page76_i66
#ISCELL
  mstr_symbols gnd *
  page76_i67
#CELL
  dev_discrete cap_a *
  page76_i69
#CELL
  dev_discrete cap_a *
  page76_i7
#CELL
  dev_discrete cap_a *
  page76_i70
#ISCELL
  mstr_symbols pvccin_cpu1 *
  page76_i71
#CELL
  dev_discrete cap_a *
  page76_i73
#ISCELL
  mstr_symbols gnd *
  page76_i74
#CELL
  dev_discrete cap_a *
  page76_i75
#CELL
  dev_discrete cap_a *
  page76_i76
#ISCELL
  mstr_symbols gnd *
  page76_i77
#CELL
  dev_discrete cap_a *
  page76_i79
#CELL
  dev_discrete cap_a *
  page76_i8
#CELL
  dev_discrete cap_a *
  page76_i80
#CELL
  dev_discrete cap_a *
  page76_i82
#CELL
  dev_discrete cap_a *
  page76_i83
#CELL
  dev_discrete cap_a *
  page76_i85
#CELL
  mstr_discrete cap *
  page76_i89
#CELL
  dev_discrete cap_a *
  page76_i90
#CELL
  mstr_discrete cap *
  page76_i92
#ISCELL
  mstr_symbols bom_note *
  *
#ISCELL
  mstr_symbols intel_corp_bpage *
  *
#ISCELL
  mstr_standard offpage *
  page77_i1
#ISCELL
  mstr_standard tap *
  page77_i10
#ISCELL
  mstr_standard tap *
  page77_i100
#ISCELL
  mstr_standard tap *
  page77_i101
#ISCELL
  mstr_standard tap *
  page77_i102
#ISCELL
  mstr_standard tap *
  page77_i103
#ISCELL
  mstr_standard tap *
  page77_i104
#ISCELL
  mstr_standard tap *
  page77_i105
#ISCELL
  mstr_standard tap *
  page77_i106
#ISCELL
  mstr_standard tap *
  page77_i107
#ISCELL
  mstr_standard tap *
  page77_i108
#ISCELL
  mstr_standard tap *
  page77_i109
#ISCELL
  mstr_standard tap *
  page77_i11
#ISCELL
  mstr_standard tap *
  page77_i110
#CELL
  mstr_sconn sconn288_h44441004 *
  page77_i111
#ISCELL
  mstr_standard tap *
  page77_i112
#ISCELL
  mstr_standard tap *
  page77_i113
#ISCELL
  mstr_standard tap *
  page77_i114
#ISCELL
  mstr_standard tap *
  page77_i115
#ISCELL
  mstr_standard tap *
  page77_i116
#ISCELL
  mstr_standard tap *
  page77_i117
#ISCELL
  mstr_standard tap *
  page77_i118
#ISCELL
  mstr_standard tap *
  page77_i119
#ISCELL
  mstr_standard tap *
  page77_i12
#ISCELL
  mstr_standard tap *
  page77_i120
#ISCELL
  mstr_standard tap *
  page77_i121
#ISCELL
  mstr_standard tap *
  page77_i122
#ISCELL
  mstr_standard tap *
  page77_i123
#ISCELL
  mstr_standard tap *
  page77_i124
#ISCELL
  mstr_standard tap *
  page77_i125
#ISCELL
  mstr_standard tap *
  page77_i126
#ISCELL
  mstr_standard tap *
  page77_i127
#ISCELL
  mstr_standard tap *
  page77_i128
#ISCELL
  mstr_standard tap *
  page77_i129
#ISCELL
  mstr_standard tap *
  page77_i13
#ISCELL
  mstr_standard tap *
  page77_i130
#ISCELL
  mstr_standard offpage *
  page77_i131
#ISCELL
  mstr_standard offpage *
  page77_i132
#ISCELL
  mstr_standard tap *
  page77_i133
#ISCELL
  mstr_standard tap *
  page77_i134
#ISCELL
  mstr_standard tap *
  page77_i135
#ISCELL
  mstr_standard offpage *
  page77_i136
#ISCELL
  mstr_standard offpage *
  page77_i137
#ISCELL
  mstr_standard tap *
  page77_i138
#ISCELL
  mstr_standard tap *
  page77_i139
#ISCELL
  mstr_standard tap *
  page77_i14
#ISCELL
  mstr_standard tap *
  page77_i140
#ISCELL
  mstr_standard tap *
  page77_i141
#ISCELL
  mstr_standard tap *
  page77_i142
#ISCELL
  mstr_standard tap *
  page77_i143
#ISCELL
  mstr_standard tap *
  page77_i144
#ISCELL
  mstr_standard tap *
  page77_i145
#ISCELL
  mstr_standard offpage *
  page77_i147
#ISCELL
  mstr_standard offpage *
  page77_i148
#ISCELL
  mstr_standard offpage *
  page77_i149
#ISCELL
  mstr_standard tap *
  page77_i15
#ISCELL
  mstr_standard offpage *
  page77_i150
#ISCELL
  mstr_standard tap *
  page77_i152
#ISCELL
  mstr_standard tap *
  page77_i153
#ISCELL
  mstr_standard offpage *
  page77_i154
#ISCELL
  mstr_standard offpage *
  page77_i155
#ISCELL
  mstr_standard tap *
  page77_i156
#ISCELL
  mstr_standard tap *
  page77_i157
#ISCELL
  mstr_standard tap *
  page77_i158
#ISCELL
  mstr_standard tap *
  page77_i159
#ISCELL
  mstr_symbols pvddq_ghj *
  page77_i16
#ISCELL
  mstr_standard tap *
  page77_i160
#ISCELL
  mstr_standard tap *
  page77_i161
#ISCELL
  mstr_standard tap *
  page77_i162
#ISCELL
  mstr_standard offpage *
  page77_i163
#ISCELL
  mstr_standard offpage *
  page77_i164
#ISCELL
  mstr_standard tap *
  page77_i165
#ISCELL
  mstr_standard tap *
  page77_i166
#ISCELL
  mstr_standard offpage *
  page77_i167
#ISCELL
  mstr_standard tap *
  page77_i168
#ISCELL
  mstr_symbols pvtt_ghj *
  page77_i17
#CELL
  mstr_sconn sconn288_h44441004 *
  page77_i171
#ISCELL
  mstr_symbols gnd *
  page77_i172
#ISCELL
  mstr_standard offpage *
  page77_i173
#ISCELL
  mstr_standard offpage *
  page77_i174
#ISCELL
  mstr_standard offpage *
  page77_i175
#ISCELL
  mstr_symbols gnd *
  page77_i177
#ISCELL
  mstr_standard offpage *
  page77_i178
#ISCELL
  mstr_standard offpage *
  page77_i179
#ISCELL
  mstr_symbols gnd *
  page77_i180
#CELL
  dev_discrete cap_a *
  page77_i181
#ISCELL
  mstr_symbols pvpp_ghj *
  page77_i182
#ISCELL
  mstr_symbols pvpp_ghj *
  page77_i183
#ISCELL
  mstr_standard offpage *
  page77_i184
#ISCELL
  mstr_standard tap *
  page77_i19
#ISCELL
  mstr_symbols p12v_nvdimm_ghj *
  page77_i197
#ISCELL
  mstr_standard offpage *
  page77_i2
#ISCELL
  mstr_standard tap *
  page77_i20
#ISCELL
  mstr_standard tap *
  page77_i21
#ISCELL
  mstr_standard tap *
  page77_i22
#ISCELL
  mstr_standard tap *
  page77_i23
#ISCELL
  mstr_standard tap *
  page77_i24
#ISCELL
  mstr_standard tap *
  page77_i25
#ISCELL
  mstr_standard tap *
  page77_i26
#ISCELL
  mstr_standard tap *
  page77_i27
#ISCELL
  mstr_standard tap *
  page77_i28
#ISCELL
  mstr_standard tap *
  page77_i29
#ISCELL
  mstr_standard tap *
  page77_i3
#ISCELL
  mstr_standard tap *
  page77_i30
#ISCELL
  mstr_standard tap *
  page77_i31
#ISCELL
  mstr_standard tap *
  page77_i32
#ISCELL
  mstr_standard tap *
  page77_i33
#ISCELL
  mstr_standard tap *
  page77_i34
#ISCELL
  mstr_standard tap *
  page77_i35
#ISCELL
  mstr_standard tap *
  page77_i36
#ISCELL
  mstr_standard tap *
  page77_i37
#ISCELL
  mstr_standard tap *
  page77_i38
#ISCELL
  mstr_standard tap *
  page77_i39
#ISCELL
  mstr_standard tap *
  page77_i4
#ISCELL
  mstr_standard tap *
  page77_i40
#ISCELL
  mstr_standard tap *
  page77_i41
#CELL
  mstr_sconn sconn288_h44441004 *
  page77_i43
#ISCELL
  mstr_symbols gnd *
  page77_i44
#ISCELL
  mstr_standard offpage *
  page77_i45
#ISCELL
  mstr_standard tap *
  page77_i46
#ISCELL
  mstr_standard tap *
  page77_i47
#ISCELL
  mstr_standard tap *
  page77_i48
#ISCELL
  mstr_standard tap *
  page77_i49
#ISCELL
  mstr_standard tap *
  page77_i5
#ISCELL
  mstr_standard tap *
  page77_i50
#ISCELL
  mstr_standard tap *
  page77_i51
#ISCELL
  mstr_standard tap *
  page77_i52
#ISCELL
  mstr_standard tap *
  page77_i53
#ISCELL
  mstr_standard tap *
  page77_i54
#ISCELL
  mstr_standard tap *
  page77_i55
#ISCELL
  mstr_standard tap *
  page77_i56
#ISCELL
  mstr_standard tap *
  page77_i57
#ISCELL
  mstr_standard tap *
  page77_i58
#ISCELL
  mstr_standard tap *
  page77_i59
#ISCELL
  mstr_standard tap *
  page77_i6
#ISCELL
  mstr_standard tap *
  page77_i60
#ISCELL
  mstr_standard tap *
  page77_i61
#ISCELL
  mstr_standard tap *
  page77_i62
#ISCELL
  mstr_standard tap *
  page77_i63
#ISCELL
  mstr_standard tap *
  page77_i64
#ISCELL
  mstr_standard tap *
  page77_i65
#CELL
  mstr_sconn sconn288_h44441004 *
  page77_i66
#ISCELL
  mstr_standard tap *
  page77_i67
#ISCELL
  mstr_standard tap *
  page77_i68
#ISCELL
  mstr_standard tap *
  page77_i69
#ISCELL
  mstr_standard tap *
  page77_i7
#ISCELL
  mstr_standard tap *
  page77_i70
#ISCELL
  mstr_standard tap *
  page77_i71
#ISCELL
  mstr_standard tap *
  page77_i72
#ISCELL
  mstr_standard tap *
  page77_i73
#ISCELL
  mstr_standard tap *
  page77_i74
#ISCELL
  mstr_standard tap *
  page77_i75
#ISCELL
  mstr_standard tap *
  page77_i76
#ISCELL
  mstr_standard tap *
  page77_i77
#ISCELL
  mstr_standard tap *
  page77_i78
#ISCELL
  mstr_standard tap *
  page77_i79
#ISCELL
  mstr_standard tap *
  page77_i8
#ISCELL
  mstr_standard tap *
  page77_i80
#ISCELL
  mstr_standard tap *
  page77_i81
#ISCELL
  mstr_standard tap *
  page77_i82
#ISCELL
  mstr_standard tap *
  page77_i83
#ISCELL
  mstr_standard tap *
  page77_i84
#ISCELL
  mstr_standard tap *
  page77_i85
#ISCELL
  mstr_standard tap *
  page77_i86
#ISCELL
  mstr_standard tap *
  page77_i87
#ISCELL
  mstr_standard tap *
  page77_i88
#ISCELL
  mstr_standard tap *
  page77_i89
#ISCELL
  mstr_standard tap *
  page77_i9
#ISCELL
  mstr_standard tap *
  page77_i90
#ISCELL
  mstr_standard tap *
  page77_i91
#ISCELL
  mstr_standard tap *
  page77_i92
#ISCELL
  mstr_standard tap *
  page77_i93
#ISCELL
  mstr_standard tap *
  page77_i94
#ISCELL
  mstr_standard tap *
  page77_i95
#ISCELL
  mstr_standard tap *
  page77_i96
#ISCELL
  mstr_standard tap *
  page77_i97
#ISCELL
  mstr_standard tap *
  page77_i98
#ISCELL
  mstr_standard tap *
  page77_i99
#ISCELL
  mstr_symbols bom_note *
  *
#ISCELL
  mstr_symbols intel_corp_bpage *
  *
#ISCELL
  mstr_symbols gnd *
  page78_i1
#ISCELL
  mstr_standard offpage *
  page78_i10
#ISCELL
  mstr_standard tap *
  page78_i100
#ISCELL
  mstr_standard tap *
  page78_i101
#ISCELL
  mstr_standard tap *
  page78_i102
#ISCELL
  mstr_standard tap *
  page78_i103
#ISCELL
  mstr_standard tap *
  page78_i104
#ISCELL
  mstr_standard tap *
  page78_i105
#ISCELL
  mstr_standard tap *
  page78_i106
#ISCELL
  mstr_standard tap *
  page78_i107
#ISCELL
  mstr_standard tap *
  page78_i108
#ISCELL
  mstr_standard tap *
  page78_i109
#ISCELL
  mstr_standard offpage *
  page78_i11
#ISCELL
  mstr_standard tap *
  page78_i110
#ISCELL
  mstr_standard tap *
  page78_i111
#ISCELL
  mstr_standard tap *
  page78_i112
#ISCELL
  mstr_standard tap *
  page78_i113
#ISCELL
  mstr_standard tap *
  page78_i114
#ISCELL
  mstr_standard tap *
  page78_i115
#ISCELL
  mstr_standard tap *
  page78_i116
#ISCELL
  mstr_standard tap *
  page78_i117
#ISCELL
  mstr_standard tap *
  page78_i118
#ISCELL
  mstr_symbols pvpp_ghj *
  page78_i119
#ISCELL
  mstr_standard tap *
  page78_i12
#CELL
  mstr_sconn sconn288_h44441003 *
  page78_i120
#ISCELL
  mstr_standard offpage *
  page78_i121
#ISCELL
  mstr_standard tap *
  page78_i122
#ISCELL
  mstr_standard tap *
  page78_i123
#ISCELL
  mstr_standard tap *
  page78_i124
#ISCELL
  mstr_standard tap *
  page78_i125
#ISCELL
  mstr_standard tap *
  page78_i126
#ISCELL
  mstr_standard tap *
  page78_i127
#ISCELL
  mstr_standard tap *
  page78_i128
#CELL
  mstr_sconn sconn288_h44441003 *
  page78_i13
#ISCELL
  mstr_standard tap *
  page78_i135
#ISCELL
  mstr_standard tap *
  page78_i136
#ISCELL
  mstr_standard tap *
  page78_i137
#ISCELL
  mstr_standard tap *
  page78_i138
#ISCELL
  mstr_standard tap *
  page78_i139
#ISCELL
  mstr_standard offpage *
  page78_i14
#ISCELL
  mstr_standard tap *
  page78_i140
#ISCELL
  mstr_standard tap *
  page78_i141
#ISCELL
  mstr_standard offpage *
  page78_i142
#ISCELL
  mstr_symbols gnd *
  page78_i143
#CELL
  mstr_sconn sconn288_h44441003 *
  page78_i144
#ISCELL
  mstr_standard tap *
  page78_i148
#ISCELL
  mstr_standard tap *
  page78_i149
#ISCELL
  mstr_standard offpage *
  page78_i15
#ISCELL
  mstr_standard tap *
  page78_i150
#ISCELL
  mstr_standard tap *
  page78_i151
#ISCELL
  mstr_standard tap *
  page78_i152
#ISCELL
  mstr_standard tap *
  page78_i153
#ISCELL
  mstr_standard tap *
  page78_i154
#ISCELL
  mstr_standard tap *
  page78_i155
#ISCELL
  mstr_standard tap *
  page78_i156
#ISCELL
  mstr_standard tap *
  page78_i157
#ISCELL
  mstr_standard tap *
  page78_i158
#ISCELL
  mstr_standard tap *
  page78_i159
#ISCELL
  mstr_standard offpage *
  page78_i16
#ISCELL
  mstr_standard tap *
  page78_i160
#ISCELL
  mstr_standard tap *
  page78_i161
#ISCELL
  mstr_standard tap *
  page78_i162
#ISCELL
  mstr_standard tap *
  page78_i163
#ISCELL
  mstr_symbols gnd *
  page78_i164
#ISCELL
  mstr_standard tap *
  page78_i165
#ISCELL
  mstr_standard tap *
  page78_i166
#ISCELL
  mstr_standard tap *
  page78_i167
#ISCELL
  mstr_standard tap *
  page78_i168
#ISCELL
  mstr_standard tap *
  page78_i169
#ISCELL
  mstr_standard offpage *
  page78_i17
#ISCELL
  mstr_standard tap *
  page78_i170
#ISCELL
  mstr_standard tap *
  page78_i171
#ISCELL
  mstr_standard tap *
  page78_i172
#ISCELL
  mstr_standard tap *
  page78_i173
#ISCELL
  mstr_standard tap *
  page78_i174
#ISCELL
  mstr_standard tap *
  page78_i175
#ISCELL
  mstr_standard tap *
  page78_i176
#ISCELL
  mstr_standard tap *
  page78_i177
#ISCELL
  mstr_standard tap *
  page78_i178
#ISCELL
  mstr_standard tap *
  page78_i179
#ISCELL
  mstr_standard offpage *
  page78_i18
#ISCELL
  mstr_standard tap *
  page78_i180
#ISCELL
  mstr_standard tap *
  page78_i181
#ISCELL
  mstr_standard tap *
  page78_i182
#ISCELL
  mstr_standard tap *
  page78_i183
#ISCELL
  mstr_standard tap *
  page78_i184
#ISCELL
  mstr_standard offpage *
  page78_i185
#ISCELL
  mstr_standard offpage *
  page78_i186
#ISCELL
  mstr_symbols p12v_nvdimm_ghj *
  page78_i187
#ISCELL
  mstr_standard offpage *
  page78_i19
#CELL
  dev_discrete cap_a *
  page78_i2
#ISCELL
  mstr_standard offpage *
  page78_i20
#ISCELL
  mstr_standard tap *
  page78_i21
#ISCELL
  mstr_standard tap *
  page78_i22
#ISCELL
  mstr_standard tap *
  page78_i23
#ISCELL
  mstr_standard tap *
  page78_i24
#ISCELL
  mstr_standard tap *
  page78_i25
#ISCELL
  mstr_standard tap *
  page78_i26
#ISCELL
  mstr_standard tap *
  page78_i27
#ISCELL
  mstr_standard tap *
  page78_i28
#ISCELL
  mstr_standard tap *
  page78_i29
#ISCELL
  mstr_symbols gnd *
  page78_i3
#ISCELL
  mstr_standard tap *
  page78_i30
#ISCELL
  mstr_standard tap *
  page78_i31
#ISCELL
  mstr_standard tap *
  page78_i32
#ISCELL
  mstr_standard tap *
  page78_i33
#ISCELL
  mstr_standard tap *
  page78_i34
#ISCELL
  mstr_standard tap *
  page78_i35
#ISCELL
  mstr_standard offpage *
  page78_i36
#ISCELL
  mstr_standard offpage *
  page78_i37
#ISCELL
  mstr_standard offpage *
  page78_i38
#ISCELL
  mstr_standard offpage *
  page78_i39
#ISCELL
  mstr_standard offpage *
  page78_i4
#ISCELL
  mstr_standard tap *
  page78_i40
#ISCELL
  mstr_standard tap *
  page78_i41
#ISCELL
  mstr_standard tap *
  page78_i42
#ISCELL
  mstr_standard tap *
  page78_i43
#ISCELL
  mstr_standard tap *
  page78_i44
#ISCELL
  mstr_standard tap *
  page78_i45
#ISCELL
  mstr_standard tap *
  page78_i46
#ISCELL
  mstr_standard tap *
  page78_i47
#ISCELL
  mstr_standard tap *
  page78_i48
#ISCELL
  mstr_standard tap *
  page78_i49
#ISCELL
  mstr_symbols pvpp_ghj *
  page78_i5
#ISCELL
  mstr_standard tap *
  page78_i50
#ISCELL
  mstr_standard tap *
  page78_i51
#ISCELL
  mstr_standard tap *
  page78_i52
#ISCELL
  mstr_standard tap *
  page78_i53
#ISCELL
  mstr_standard tap *
  page78_i54
#ISCELL
  mstr_standard tap *
  page78_i55
#ISCELL
  mstr_standard tap *
  page78_i56
#ISCELL
  mstr_standard tap *
  page78_i57
#ISCELL
  mstr_standard tap *
  page78_i58
#ISCELL
  mstr_standard tap *
  page78_i59
#ISCELL
  mstr_standard offpage *
  page78_i6
#ISCELL
  mstr_standard tap *
  page78_i60
#ISCELL
  mstr_standard tap *
  page78_i61
#ISCELL
  mstr_standard tap *
  page78_i62
#ISCELL
  mstr_standard tap *
  page78_i63
#ISCELL
  mstr_standard tap *
  page78_i64
#ISCELL
  mstr_standard tap *
  page78_i65
#ISCELL
  mstr_standard tap *
  page78_i66
#ISCELL
  mstr_standard tap *
  page78_i67
#ISCELL
  mstr_standard tap *
  page78_i68
#ISCELL
  mstr_standard tap *
  page78_i69
#ISCELL
  mstr_standard offpage *
  page78_i7
#ISCELL
  mstr_standard tap *
  page78_i70
#ISCELL
  mstr_standard tap *
  page78_i71
#ISCELL
  mstr_standard tap *
  page78_i72
#ISCELL
  mstr_standard tap *
  page78_i73
#ISCELL
  mstr_standard tap *
  page78_i74
#CELL
  mstr_sconn sconn288_h44441003 *
  page78_i75
#ISCELL
  mstr_standard tap *
  page78_i76
#ISCELL
  mstr_standard tap *
  page78_i77
#ISCELL
  mstr_standard tap *
  page78_i78
#ISCELL
  mstr_standard tap *
  page78_i79
#ISCELL
  mstr_standard offpage *
  page78_i8
#ISCELL
  mstr_standard tap *
  page78_i80
#ISCELL
  mstr_standard tap *
  page78_i81
#ISCELL
  mstr_standard tap *
  page78_i82
#ISCELL
  mstr_standard tap *
  page78_i83
#ISCELL
  mstr_standard tap *
  page78_i84
#ISCELL
  mstr_standard tap *
  page78_i85
#ISCELL
  mstr_standard tap *
  page78_i86
#ISCELL
  mstr_standard tap *
  page78_i87
#ISCELL
  mstr_standard tap *
  page78_i88
#ISCELL
  mstr_standard tap *
  page78_i89
#ISCELL
  mstr_standard offpage *
  page78_i9
#ISCELL
  mstr_standard tap *
  page78_i90
#ISCELL
  mstr_standard tap *
  page78_i91
#ISCELL
  mstr_standard tap *
  page78_i92
#ISCELL
  mstr_standard tap *
  page78_i93
#ISCELL
  mstr_standard tap *
  page78_i94
#ISCELL
  mstr_standard tap *
  page78_i95
#ISCELL
  mstr_symbols pvddq_ghj *
  page78_i96
#ISCELL
  mstr_symbols pvtt_ghj *
  page78_i97
#ISCELL
  mstr_standard tap *
  page78_i98
#ISCELL
  mstr_standard tap *
  page78_i99
#ISCELL
  mstr_symbols bom_note *
  *
#ISCELL
  mstr_symbols intel_corp_bpage *
  *
#ISCELL
  mstr_standard offpage *
  page79_i1
#ISCELL
  mstr_standard tap *
  page79_i10
#ISCELL
  mstr_standard tap *
  page79_i100
#ISCELL
  mstr_standard tap *
  page79_i101
#ISCELL
  mstr_standard tap *
  page79_i102
#ISCELL
  mstr_standard tap *
  page79_i103
#ISCELL
  mstr_standard tap *
  page79_i104
#ISCELL
  mstr_standard tap *
  page79_i105
#ISCELL
  mstr_standard tap *
  page79_i106
#ISCELL
  mstr_standard tap *
  page79_i107
#ISCELL
  mstr_standard tap *
  page79_i108
#ISCELL
  mstr_standard tap *
  page79_i109
#ISCELL
  mstr_standard tap *
  page79_i11
#ISCELL
  mstr_standard tap *
  page79_i110
#CELL
  mstr_sconn sconn288_h44441004 *
  page79_i111
#ISCELL
  mstr_standard tap *
  page79_i112
#ISCELL
  mstr_standard tap *
  page79_i113
#ISCELL
  mstr_standard tap *
  page79_i114
#ISCELL
  mstr_standard tap *
  page79_i115
#ISCELL
  mstr_standard tap *
  page79_i116
#ISCELL
  mstr_standard tap *
  page79_i117
#ISCELL
  mstr_standard tap *
  page79_i118
#ISCELL
  mstr_standard tap *
  page79_i119
#ISCELL
  mstr_standard tap *
  page79_i12
#ISCELL
  mstr_standard tap *
  page79_i120
#ISCELL
  mstr_standard tap *
  page79_i121
#ISCELL
  mstr_standard tap *
  page79_i122
#ISCELL
  mstr_standard tap *
  page79_i123
#ISCELL
  mstr_standard tap *
  page79_i124
#ISCELL
  mstr_standard tap *
  page79_i125
#ISCELL
  mstr_standard tap *
  page79_i126
#ISCELL
  mstr_standard tap *
  page79_i127
#ISCELL
  mstr_standard tap *
  page79_i128
#ISCELL
  mstr_standard tap *
  page79_i129
#ISCELL
  mstr_standard tap *
  page79_i13
#ISCELL
  mstr_standard offpage *
  page79_i130
#ISCELL
  mstr_standard tap *
  page79_i131
#ISCELL
  mstr_standard tap *
  page79_i132
#ISCELL
  mstr_standard tap *
  page79_i133
#ISCELL
  mstr_standard tap *
  page79_i134
#ISCELL
  mstr_standard offpage *
  page79_i135
#ISCELL
  mstr_standard offpage *
  page79_i136
#ISCELL
  mstr_standard offpage *
  page79_i137
#ISCELL
  mstr_standard tap *
  page79_i138
#ISCELL
  mstr_standard tap *
  page79_i139
#ISCELL
  mstr_symbols pvddq_ghj *
  page79_i14
#ISCELL
  mstr_standard tap *
  page79_i140
#ISCELL
  mstr_standard tap *
  page79_i141
#ISCELL
  mstr_standard tap *
  page79_i142
#ISCELL
  mstr_standard tap *
  page79_i143
#ISCELL
  mstr_standard tap *
  page79_i144
#ISCELL
  mstr_standard tap *
  page79_i145
#ISCELL
  mstr_standard offpage *
  page79_i146
#ISCELL
  mstr_standard offpage *
  page79_i147
#ISCELL
  mstr_standard offpage *
  page79_i148
#ISCELL
  mstr_standard offpage *
  page79_i149
#ISCELL
  mstr_standard offpage *
  page79_i150
#ISCELL
  mstr_standard tap *
  page79_i152
#ISCELL
  mstr_standard tap *
  page79_i153
#ISCELL
  mstr_standard tap *
  page79_i154
#ISCELL
  mstr_standard tap *
  page79_i155
#ISCELL
  mstr_standard offpage *
  page79_i156
#ISCELL
  mstr_standard offpage *
  page79_i157
#ISCELL
  mstr_standard tap *
  page79_i158
#ISCELL
  mstr_standard tap *
  page79_i159
#ISCELL
  mstr_symbols pvtt_ghj *
  page79_i16
#ISCELL
  mstr_standard tap *
  page79_i160
#ISCELL
  mstr_standard tap *
  page79_i161
#ISCELL
  mstr_standard tap *
  page79_i162
#ISCELL
  mstr_standard tap *
  page79_i163
#ISCELL
  mstr_standard tap *
  page79_i164
#ISCELL
  mstr_standard offpage *
  page79_i165
#ISCELL
  mstr_standard offpage *
  page79_i166
#ISCELL
  mstr_standard offpage *
  page79_i167
#ISCELL
  mstr_standard tap *
  page79_i168
#CELL
  mstr_sconn sconn288_h44441004 *
  page79_i169
#ISCELL
  mstr_standard tap *
  page79_i17
#ISCELL
  mstr_symbols gnd *
  page79_i170
#ISCELL
  mstr_standard offpage *
  page79_i171
#ISCELL
  mstr_standard offpage *
  page79_i172
#ISCELL
  mstr_standard offpage *
  page79_i173
#ISCELL
  mstr_symbols gnd *
  page79_i175
#ISCELL
  mstr_standard offpage *
  page79_i176
#ISCELL
  mstr_symbols gnd *
  page79_i177
#CELL
  dev_discrete cap_a *
  page79_i178
#ISCELL
  mstr_symbols pvpp_ghj *
  page79_i179
#ISCELL
  mstr_standard tap *
  page79_i18
#ISCELL
  mstr_symbols pvpp_ghj *
  page79_i180
#ISCELL
  mstr_standard offpage *
  page79_i181
#ISCELL
  mstr_standard tap *
  page79_i185
#ISCELL
  mstr_symbols p12v_nvdimm_ghj *
  page79_i186
#ISCELL
  mstr_standard tap *
  page79_i19
#ISCELL
  mstr_standard offpage *
  page79_i2
#ISCELL
  mstr_standard tap *
  page79_i20
#ISCELL
  mstr_standard tap *
  page79_i21
#ISCELL
  mstr_standard tap *
  page79_i22
#ISCELL
  mstr_standard tap *
  page79_i23
#ISCELL
  mstr_standard tap *
  page79_i24
#ISCELL
  mstr_standard tap *
  page79_i25
#ISCELL
  mstr_standard tap *
  page79_i26
#ISCELL
  mstr_standard tap *
  page79_i27
#ISCELL
  mstr_standard tap *
  page79_i28
#ISCELL
  mstr_standard tap *
  page79_i29
#ISCELL
  mstr_standard tap *
  page79_i3
#ISCELL
  mstr_standard tap *
  page79_i30
#ISCELL
  mstr_standard tap *
  page79_i31
#ISCELL
  mstr_standard tap *
  page79_i32
#ISCELL
  mstr_standard tap *
  page79_i33
#ISCELL
  mstr_standard tap *
  page79_i34
#ISCELL
  mstr_standard tap *
  page79_i35
#ISCELL
  mstr_standard tap *
  page79_i36
#ISCELL
  mstr_standard tap *
  page79_i37
#ISCELL
  mstr_standard tap *
  page79_i38
#ISCELL
  mstr_standard tap *
  page79_i39
#ISCELL
  mstr_standard tap *
  page79_i4
#ISCELL
  mstr_standard tap *
  page79_i40
#CELL
  mstr_sconn sconn288_h44441004 *
  page79_i43
#ISCELL
  mstr_symbols gnd *
  page79_i44
#ISCELL
  mstr_standard offpage *
  page79_i45
#ISCELL
  mstr_standard tap *
  page79_i46
#ISCELL
  mstr_standard tap *
  page79_i47
#ISCELL
  mstr_standard tap *
  page79_i48
#ISCELL
  mstr_standard tap *
  page79_i49
#ISCELL
  mstr_standard tap *
  page79_i5
#ISCELL
  mstr_standard tap *
  page79_i50
#ISCELL
  mstr_standard tap *
  page79_i51
#ISCELL
  mstr_standard tap *
  page79_i52
#ISCELL
  mstr_standard tap *
  page79_i53
#ISCELL
  mstr_standard tap *
  page79_i54
#ISCELL
  mstr_standard tap *
  page79_i55
#ISCELL
  mstr_standard tap *
  page79_i56
#ISCELL
  mstr_standard tap *
  page79_i57
#ISCELL
  mstr_standard tap *
  page79_i58
#ISCELL
  mstr_standard tap *
  page79_i59
#ISCELL
  mstr_standard tap *
  page79_i6
#ISCELL
  mstr_standard tap *
  page79_i60
#ISCELL
  mstr_standard tap *
  page79_i61
#ISCELL
  mstr_standard tap *
  page79_i62
#ISCELL
  mstr_standard tap *
  page79_i63
#CELL
  mstr_sconn sconn288_h44441004 *
  page79_i64
#ISCELL
  mstr_standard tap *
  page79_i65
#ISCELL
  mstr_standard tap *
  page79_i66
#ISCELL
  mstr_standard tap *
  page79_i67
#ISCELL
  mstr_standard tap *
  page79_i68
#ISCELL
  mstr_standard tap *
  page79_i69
#ISCELL
  mstr_standard tap *
  page79_i7
#ISCELL
  mstr_standard tap *
  page79_i70
#ISCELL
  mstr_standard tap *
  page79_i71
#ISCELL
  mstr_standard tap *
  page79_i72
#ISCELL
  mstr_standard tap *
  page79_i73
#ISCELL
  mstr_standard tap *
  page79_i74
#ISCELL
  mstr_standard tap *
  page79_i75
#ISCELL
  mstr_standard tap *
  page79_i76
#ISCELL
  mstr_standard tap *
  page79_i77
#ISCELL
  mstr_standard tap *
  page79_i78
#ISCELL
  mstr_standard tap *
  page79_i79
#ISCELL
  mstr_standard tap *
  page79_i8
#ISCELL
  mstr_standard tap *
  page79_i80
#ISCELL
  mstr_standard tap *
  page79_i81
#ISCELL
  mstr_standard tap *
  page79_i82
#ISCELL
  mstr_standard tap *
  page79_i83
#ISCELL
  mstr_standard tap *
  page79_i84
#ISCELL
  mstr_standard tap *
  page79_i85
#ISCELL
  mstr_standard tap *
  page79_i86
#ISCELL
  mstr_standard tap *
  page79_i87
#ISCELL
  mstr_standard tap *
  page79_i88
#ISCELL
  mstr_standard tap *
  page79_i89
#ISCELL
  mstr_standard tap *
  page79_i9
#ISCELL
  mstr_standard tap *
  page79_i90
#ISCELL
  mstr_standard tap *
  page79_i91
#ISCELL
  mstr_standard tap *
  page79_i92
#ISCELL
  mstr_standard tap *
  page79_i93
#ISCELL
  mstr_standard tap *
  page79_i94
#ISCELL
  mstr_standard tap *
  page79_i95
#ISCELL
  mstr_standard tap *
  page79_i96
#ISCELL
  mstr_standard tap *
  page79_i97
#ISCELL
  mstr_standard tap *
  page79_i98
#ISCELL
  mstr_standard tap *
  page79_i99
#ISCELL
  mstr_symbols bom_note *
  *
#ISCELL
  mstr_symbols intel_corp_bpage *
  *
#ISCELL
  mstr_symbols gnd *
  page80_i1
#ISCELL
  mstr_standard offpage *
  page80_i10
#ISCELL
  mstr_standard tap *
  page80_i100
#CELL
  mstr_sconn sconn288_h44441003 *
  page80_i101
#ISCELL
  mstr_standard tap *
  page80_i102
#ISCELL
  mstr_standard tap *
  page80_i103
#ISCELL
  mstr_standard tap *
  page80_i104
#ISCELL
  mstr_standard tap *
  page80_i105
#ISCELL
  mstr_standard tap *
  page80_i106
#ISCELL
  mstr_standard tap *
  page80_i107
#ISCELL
  mstr_standard tap *
  page80_i108
#ISCELL
  mstr_standard tap *
  page80_i109
#ISCELL
  mstr_standard offpage *
  page80_i11
#ISCELL
  mstr_standard tap *
  page80_i110
#ISCELL
  mstr_standard tap *
  page80_i111
#ISCELL
  mstr_standard tap *
  page80_i112
#ISCELL
  mstr_standard tap *
  page80_i113
#ISCELL
  mstr_standard tap *
  page80_i114
#ISCELL
  mstr_standard tap *
  page80_i115
#ISCELL
  mstr_standard tap *
  page80_i116
#ISCELL
  mstr_standard tap *
  page80_i117
#ISCELL
  mstr_standard tap *
  page80_i118
#ISCELL
  mstr_standard tap *
  page80_i119
#ISCELL
  mstr_standard offpage *
  page80_i12
#ISCELL
  mstr_standard tap *
  page80_i120
#ISCELL
  mstr_standard tap *
  page80_i121
#ISCELL
  mstr_standard tap *
  page80_i122
#ISCELL
  mstr_standard tap *
  page80_i123
#ISCELL
  mstr_standard tap *
  page80_i124
#ISCELL
  mstr_standard tap *
  page80_i125
#ISCELL
  mstr_standard tap *
  page80_i126
#ISCELL
  mstr_standard tap *
  page80_i127
#ISCELL
  mstr_standard tap *
  page80_i128
#ISCELL
  mstr_standard tap *
  page80_i129
#ISCELL
  mstr_standard offpage *
  page80_i13
#ISCELL
  mstr_standard tap *
  page80_i130
#ISCELL
  mstr_standard tap *
  page80_i131
#ISCELL
  mstr_standard tap *
  page80_i132
#ISCELL
  mstr_standard tap *
  page80_i133
#ISCELL
  mstr_standard tap *
  page80_i134
#ISCELL
  mstr_standard tap *
  page80_i135
#ISCELL
  mstr_standard offpage *
  page80_i136
#ISCELL
  mstr_symbols gnd *
  page80_i137
#CELL
  mstr_sconn sconn288_h44441003 *
  page80_i138
#ISCELL
  mstr_standard offpage *
  page80_i14
#ISCELL
  mstr_standard tap *
  page80_i142
#ISCELL
  mstr_standard tap *
  page80_i143
#ISCELL
  mstr_standard tap *
  page80_i144
#ISCELL
  mstr_standard tap *
  page80_i145
#ISCELL
  mstr_standard tap *
  page80_i146
#ISCELL
  mstr_standard tap *
  page80_i147
#ISCELL
  mstr_standard tap *
  page80_i148
#ISCELL
  mstr_standard tap *
  page80_i149
#ISCELL
  mstr_standard offpage *
  page80_i15
#ISCELL
  mstr_standard tap *
  page80_i150
#ISCELL
  mstr_standard tap *
  page80_i151
#ISCELL
  mstr_standard tap *
  page80_i152
#ISCELL
  mstr_standard tap *
  page80_i153
#ISCELL
  mstr_standard tap *
  page80_i154
#ISCELL
  mstr_standard tap *
  page80_i155
#ISCELL
  mstr_symbols gnd *
  page80_i156
#ISCELL
  mstr_standard tap *
  page80_i157
#ISCELL
  mstr_standard tap *
  page80_i158
#ISCELL
  mstr_standard tap *
  page80_i159
#ISCELL
  mstr_standard offpage *
  page80_i16
#ISCELL
  mstr_standard tap *
  page80_i160
#ISCELL
  mstr_standard tap *
  page80_i161
#ISCELL
  mstr_standard tap *
  page80_i162
#ISCELL
  mstr_standard tap *
  page80_i163
#ISCELL
  mstr_standard tap *
  page80_i164
#ISCELL
  mstr_standard tap *
  page80_i165
#ISCELL
  mstr_standard tap *
  page80_i166
#ISCELL
  mstr_standard tap *
  page80_i167
#ISCELL
  mstr_standard tap *
  page80_i168
#ISCELL
  mstr_standard tap *
  page80_i169
#ISCELL
  mstr_standard offpage *
  page80_i17
#ISCELL
  mstr_standard tap *
  page80_i170
#ISCELL
  mstr_standard tap *
  page80_i171
#ISCELL
  mstr_standard tap *
  page80_i172
#ISCELL
  mstr_standard tap *
  page80_i173
#ISCELL
  mstr_standard tap *
  page80_i174
#ISCELL
  mstr_standard tap *
  page80_i175
#ISCELL
  mstr_standard tap *
  page80_i176
#ISCELL
  mstr_standard tap *
  page80_i177
#ISCELL
  mstr_standard tap *
  page80_i178
#ISCELL
  mstr_standard offpage *
  page80_i179
#ISCELL
  mstr_standard offpage *
  page80_i18
#ISCELL
  mstr_standard offpage *
  page80_i180
#ISCELL
  mstr_symbols p12v_nvdimm_ghj *
  page80_i181
#ISCELL
  mstr_standard offpage *
  page80_i19
#ISCELL
  mstr_standard offpage *
  page80_i2
#ISCELL
  mstr_standard offpage *
  page80_i20
#ISCELL
  mstr_standard offpage *
  page80_i21
#ISCELL
  mstr_standard offpage *
  page80_i22
#ISCELL
  mstr_standard offpage *
  page80_i23
#CELL
  mstr_sconn sconn288_h44441003 *
  page80_i24
#ISCELL
  mstr_standard tap *
  page80_i25
#ISCELL
  mstr_standard tap *
  page80_i26
#ISCELL
  mstr_standard tap *
  page80_i27
#ISCELL
  mstr_standard tap *
  page80_i28
#ISCELL
  mstr_standard tap *
  page80_i29
#CELL
  dev_discrete cap_a *
  page80_i3
#ISCELL
  mstr_standard tap *
  page80_i30
#ISCELL
  mstr_standard tap *
  page80_i31
#ISCELL
  mstr_standard tap *
  page80_i32
#ISCELL
  mstr_standard tap *
  page80_i33
#ISCELL
  mstr_standard tap *
  page80_i34
#ISCELL
  mstr_standard tap *
  page80_i35
#ISCELL
  mstr_standard tap *
  page80_i36
#ISCELL
  mstr_standard tap *
  page80_i37
#ISCELL
  mstr_standard tap *
  page80_i38
#ISCELL
  mstr_standard tap *
  page80_i39
#ISCELL
  mstr_symbols gnd *
  page80_i4
#ISCELL
  mstr_standard tap *
  page80_i40
#ISCELL
  mstr_standard tap *
  page80_i41
#ISCELL
  mstr_standard tap *
  page80_i42
#ISCELL
  mstr_standard tap *
  page80_i43
#ISCELL
  mstr_standard tap *
  page80_i44
#ISCELL
  mstr_standard tap *
  page80_i45
#ISCELL
  mstr_standard tap *
  page80_i46
#ISCELL
  mstr_standard tap *
  page80_i47
#ISCELL
  mstr_standard tap *
  page80_i48
#ISCELL
  mstr_standard tap *
  page80_i49
#ISCELL
  mstr_standard offpage *
  page80_i5
#ISCELL
  mstr_standard tap *
  page80_i50
#ISCELL
  mstr_standard tap *
  page80_i51
#ISCELL
  mstr_standard tap *
  page80_i52
#ISCELL
  mstr_standard tap *
  page80_i53
#ISCELL
  mstr_standard tap *
  page80_i54
#ISCELL
  mstr_standard tap *
  page80_i55
#CELL
  mstr_sconn sconn288_h44441003 *
  page80_i56
#ISCELL
  mstr_standard tap *
  page80_i57
#ISCELL
  mstr_standard tap *
  page80_i58
#ISCELL
  mstr_standard tap *
  page80_i59
#ISCELL
  mstr_standard offpage *
  page80_i6
#ISCELL
  mstr_standard tap *
  page80_i60
#ISCELL
  mstr_standard tap *
  page80_i61
#ISCELL
  mstr_standard tap *
  page80_i62
#ISCELL
  mstr_standard tap *
  page80_i63
#ISCELL
  mstr_standard tap *
  page80_i64
#ISCELL
  mstr_standard tap *
  page80_i65
#ISCELL
  mstr_standard tap *
  page80_i66
#ISCELL
  mstr_standard tap *
  page80_i67
#ISCELL
  mstr_standard tap *
  page80_i68
#ISCELL
  mstr_standard tap *
  page80_i69
#ISCELL
  mstr_standard offpage *
  page80_i7
#ISCELL
  mstr_standard tap *
  page80_i70
#ISCELL
  mstr_standard tap *
  page80_i71
#ISCELL
  mstr_standard tap *
  page80_i72
#ISCELL
  mstr_standard tap *
  page80_i73
#ISCELL
  mstr_standard tap *
  page80_i74
#ISCELL
  mstr_standard tap *
  page80_i75
#ISCELL
  mstr_standard tap *
  page80_i76
#ISCELL
  mstr_standard tap *
  page80_i77
#ISCELL
  mstr_symbols pvddq_ghj *
  page80_i78
#ISCELL
  mstr_symbols pvtt_ghj *
  page80_i79
#ISCELL
  mstr_symbols pvpp_ghj *
  page80_i8
#ISCELL
  mstr_symbols pvpp_ghj *
  page80_i80
#ISCELL
  mstr_standard tap *
  page80_i81
#ISCELL
  mstr_standard tap *
  page80_i82
#ISCELL
  mstr_standard tap *
  page80_i83
#ISCELL
  mstr_standard tap *
  page80_i84
#ISCELL
  mstr_standard tap *
  page80_i85
#ISCELL
  mstr_standard tap *
  page80_i86
#ISCELL
  mstr_standard tap *
  page80_i87
#ISCELL
  mstr_standard tap *
  page80_i88
#ISCELL
  mstr_standard tap *
  page80_i89
#ISCELL
  mstr_standard offpage *
  page80_i9
#ISCELL
  mstr_standard tap *
  page80_i90
#ISCELL
  mstr_standard tap *
  page80_i91
#ISCELL
  mstr_standard tap *
  page80_i92
#ISCELL
  mstr_standard tap *
  page80_i93
#ISCELL
  mstr_standard tap *
  page80_i94
#ISCELL
  mstr_standard tap *
  page80_i95
#ISCELL
  mstr_standard tap *
  page80_i96
#ISCELL
  mstr_standard tap *
  page80_i97
#ISCELL
  mstr_standard tap *
  page80_i98
#ISCELL
  mstr_standard tap *
  page80_i99
#ISCELL
  mstr_symbols bom_note *
  *
#ISCELL
  mstr_symbols intel_corp_bpage *
  *
#ISCELL
  mstr_standard offpage *
  page81_i1
#ISCELL
  mstr_standard tap *
  page81_i10
#ISCELL
  mstr_standard tap *
  page81_i100
#ISCELL
  mstr_standard tap *
  page81_i101
#ISCELL
  mstr_standard tap *
  page81_i102
#ISCELL
  mstr_standard tap *
  page81_i103
#ISCELL
  mstr_standard tap *
  page81_i104
#ISCELL
  mstr_standard tap *
  page81_i105
#ISCELL
  mstr_standard tap *
  page81_i106
#ISCELL
  mstr_standard tap *
  page81_i107
#ISCELL
  mstr_standard tap *
  page81_i108
#ISCELL
  mstr_standard tap *
  page81_i109
#ISCELL
  mstr_standard tap *
  page81_i11
#ISCELL
  mstr_standard tap *
  page81_i110
#ISCELL
  mstr_standard tap *
  page81_i112
#ISCELL
  mstr_standard offpage *
  page81_i113
#ISCELL
  mstr_standard tap *
  page81_i114
#ISCELL
  mstr_standard tap *
  page81_i115
#ISCELL
  mstr_standard tap *
  page81_i116
#ISCELL
  mstr_standard tap *
  page81_i117
#ISCELL
  mstr_standard tap *
  page81_i118
#ISCELL
  mstr_standard tap *
  page81_i119
#ISCELL
  mstr_standard tap *
  page81_i12
#ISCELL
  mstr_standard tap *
  page81_i120
#ISCELL
  mstr_standard tap *
  page81_i121
#ISCELL
  mstr_standard tap *
  page81_i122
#ISCELL
  mstr_standard tap *
  page81_i123
#ISCELL
  mstr_standard tap *
  page81_i124
#ISCELL
  mstr_standard tap *
  page81_i125
#ISCELL
  mstr_standard tap *
  page81_i126
#ISCELL
  mstr_standard tap *
  page81_i127
#ISCELL
  mstr_standard tap *
  page81_i128
#ISCELL
  mstr_standard tap *
  page81_i129
#ISCELL
  mstr_standard tap *
  page81_i13
#ISCELL
  mstr_standard tap *
  page81_i130
#ISCELL
  mstr_standard tap *
  page81_i131
#ISCELL
  mstr_standard tap *
  page81_i132
#ISCELL
  mstr_standard offpage *
  page81_i133
#ISCELL
  mstr_standard tap *
  page81_i134
#ISCELL
  mstr_standard tap *
  page81_i135
#ISCELL
  mstr_standard offpage *
  page81_i136
#ISCELL
  mstr_standard tap *
  page81_i137
#ISCELL
  mstr_standard offpage *
  page81_i138
#ISCELL
  mstr_standard offpage *
  page81_i139
#ISCELL
  mstr_standard tap *
  page81_i14
#ISCELL
  mstr_standard tap *
  page81_i140
#ISCELL
  mstr_standard tap *
  page81_i141
#ISCELL
  mstr_standard tap *
  page81_i142
#ISCELL
  mstr_standard tap *
  page81_i143
#ISCELL
  mstr_standard tap *
  page81_i144
#ISCELL
  mstr_standard tap *
  page81_i145
#ISCELL
  mstr_standard tap *
  page81_i146
#ISCELL
  mstr_standard offpage *
  page81_i147
#ISCELL
  mstr_standard offpage *
  page81_i148
#ISCELL
  mstr_standard offpage *
  page81_i149
#ISCELL
  mstr_standard tap *
  page81_i15
#ISCELL
  mstr_standard offpage *
  page81_i150
#ISCELL
  mstr_standard tap *
  page81_i152
#ISCELL
  mstr_standard tap *
  page81_i153
#ISCELL
  mstr_standard tap *
  page81_i154
#ISCELL
  mstr_standard tap *
  page81_i155
#ISCELL
  mstr_standard offpage *
  page81_i156
#ISCELL
  mstr_standard offpage *
  page81_i157
#ISCELL
  mstr_standard tap *
  page81_i158
#ISCELL
  mstr_standard tap *
  page81_i159
#ISCELL
  mstr_standard tap *
  page81_i16
#ISCELL
  mstr_standard tap *
  page81_i160
#ISCELL
  mstr_standard tap *
  page81_i161
#ISCELL
  mstr_standard tap *
  page81_i162
#ISCELL
  mstr_standard tap *
  page81_i163
#ISCELL
  mstr_standard tap *
  page81_i164
#ISCELL
  mstr_standard offpage *
  page81_i165
#ISCELL
  mstr_standard offpage *
  page81_i166
#ISCELL
  mstr_standard offpage *
  page81_i167
#ISCELL
  mstr_standard tap *
  page81_i168
#CELL
  mstr_sconn sconn288_h44441004 *
  page81_i169
#ISCELL
  mstr_symbols pvddq_ghj *
  page81_i17
#ISCELL
  mstr_symbols gnd *
  page81_i170
#ISCELL
  mstr_standard offpage *
  page81_i171
#ISCELL
  mstr_standard offpage *
  page81_i172
#ISCELL
  mstr_standard offpage *
  page81_i173
#ISCELL
  mstr_symbols gnd *
  page81_i175
#ISCELL
  mstr_standard offpage *
  page81_i176
#ISCELL
  mstr_symbols gnd *
  page81_i177
#CELL
  dev_discrete cap_a *
  page81_i178
#ISCELL
  mstr_symbols pvpp_ghj *
  page81_i179
#ISCELL
  mstr_symbols pvtt_ghj *
  page81_i18
#ISCELL
  mstr_symbols pvpp_ghj *
  page81_i180
#ISCELL
  mstr_standard offpage *
  page81_i181
#CELL
  mstr_sconn sconn288_h44441004 *
  page81_i185
#CELL
  mstr_sconn sconn288_h44441004 *
  page81_i186
#ISCELL
  mstr_symbols p12v_nvdimm_ghj *
  page81_i187
#ISCELL
  mstr_standard offpage *
  page81_i2
#ISCELL
  mstr_standard tap *
  page81_i20
#ISCELL
  mstr_standard tap *
  page81_i21
#ISCELL
  mstr_standard tap *
  page81_i22
#ISCELL
  mstr_standard tap *
  page81_i23
#ISCELL
  mstr_standard tap *
  page81_i24
#ISCELL
  mstr_standard tap *
  page81_i25
#ISCELL
  mstr_standard tap *
  page81_i26
#ISCELL
  mstr_standard tap *
  page81_i27
#ISCELL
  mstr_standard tap *
  page81_i28
#ISCELL
  mstr_standard tap *
  page81_i29
#ISCELL
  mstr_standard tap *
  page81_i3
#ISCELL
  mstr_standard tap *
  page81_i30
#ISCELL
  mstr_standard tap *
  page81_i31
#ISCELL
  mstr_standard tap *
  page81_i32
#ISCELL
  mstr_standard tap *
  page81_i33
#ISCELL
  mstr_standard tap *
  page81_i34
#ISCELL
  mstr_standard tap *
  page81_i35
#ISCELL
  mstr_standard tap *
  page81_i36
#ISCELL
  mstr_standard tap *
  page81_i37
#ISCELL
  mstr_standard tap *
  page81_i38
#ISCELL
  mstr_standard tap *
  page81_i39
#ISCELL
  mstr_standard tap *
  page81_i4
#ISCELL
  mstr_standard tap *
  page81_i40
#ISCELL
  mstr_standard tap *
  page81_i41
#ISCELL
  mstr_symbols gnd *
  page81_i44
#ISCELL
  mstr_standard offpage *
  page81_i45
#ISCELL
  mstr_standard tap *
  page81_i46
#ISCELL
  mstr_standard tap *
  page81_i47
#ISCELL
  mstr_standard tap *
  page81_i48
#ISCELL
  mstr_standard tap *
  page81_i49
#ISCELL
  mstr_standard tap *
  page81_i5
#ISCELL
  mstr_standard tap *
  page81_i50
#ISCELL
  mstr_standard tap *
  page81_i51
#ISCELL
  mstr_standard tap *
  page81_i52
#ISCELL
  mstr_standard tap *
  page81_i53
#ISCELL
  mstr_standard tap *
  page81_i54
#ISCELL
  mstr_standard tap *
  page81_i55
#ISCELL
  mstr_standard tap *
  page81_i56
#ISCELL
  mstr_standard tap *
  page81_i57
#ISCELL
  mstr_standard tap *
  page81_i58
#ISCELL
  mstr_standard tap *
  page81_i59
#ISCELL
  mstr_standard tap *
  page81_i6
#ISCELL
  mstr_standard tap *
  page81_i60
#ISCELL
  mstr_standard tap *
  page81_i61
#ISCELL
  mstr_standard tap *
  page81_i62
#ISCELL
  mstr_standard tap *
  page81_i63
#ISCELL
  mstr_standard tap *
  page81_i64
#ISCELL
  mstr_standard tap *
  page81_i65
#ISCELL
  mstr_standard tap *
  page81_i66
#CELL
  mstr_sconn sconn288_h44441004 *
  page81_i67
#ISCELL
  mstr_standard tap *
  page81_i68
#ISCELL
  mstr_standard tap *
  page81_i69
#ISCELL
  mstr_standard tap *
  page81_i7
#ISCELL
  mstr_standard tap *
  page81_i70
#ISCELL
  mstr_standard tap *
  page81_i71
#ISCELL
  mstr_standard tap *
  page81_i72
#ISCELL
  mstr_standard tap *
  page81_i73
#ISCELL
  mstr_standard tap *
  page81_i74
#ISCELL
  mstr_standard tap *
  page81_i75
#ISCELL
  mstr_standard tap *
  page81_i76
#ISCELL
  mstr_standard tap *
  page81_i77
#ISCELL
  mstr_standard tap *
  page81_i78
#ISCELL
  mstr_standard tap *
  page81_i79
#ISCELL
  mstr_standard tap *
  page81_i8
#ISCELL
  mstr_standard tap *
  page81_i80
#ISCELL
  mstr_standard tap *
  page81_i81
#ISCELL
  mstr_standard tap *
  page81_i82
#ISCELL
  mstr_standard tap *
  page81_i83
#ISCELL
  mstr_standard tap *
  page81_i84
#ISCELL
  mstr_standard tap *
  page81_i85
#ISCELL
  mstr_standard tap *
  page81_i86
#ISCELL
  mstr_standard tap *
  page81_i87
#ISCELL
  mstr_standard tap *
  page81_i88
#ISCELL
  mstr_standard tap *
  page81_i89
#ISCELL
  mstr_standard tap *
  page81_i9
#ISCELL
  mstr_standard tap *
  page81_i90
#ISCELL
  mstr_standard tap *
  page81_i91
#ISCELL
  mstr_standard tap *
  page81_i92
#ISCELL
  mstr_standard tap *
  page81_i93
#ISCELL
  mstr_standard tap *
  page81_i94
#ISCELL
  mstr_standard tap *
  page81_i95
#ISCELL
  mstr_standard tap *
  page81_i96
#ISCELL
  mstr_standard tap *
  page81_i97
#ISCELL
  mstr_standard tap *
  page81_i98
#ISCELL
  mstr_standard tap *
  page81_i99
#ISCELL
  mstr_symbols bom_note *
  *
#ISCELL
  mstr_symbols intel_corp_bpage *
  *
#ISCELL
  mstr_standard offpage *
  page82_i1
#ISCELL
  mstr_standard tap *
  page82_i10
#ISCELL
  mstr_standard tap *
  page82_i100
#ISCELL
  mstr_standard tap *
  page82_i101
#ISCELL
  mstr_standard tap *
  page82_i102
#ISCELL
  mstr_standard tap *
  page82_i103
#ISCELL
  mstr_standard tap *
  page82_i104
#ISCELL
  mstr_standard tap *
  page82_i105
#ISCELL
  mstr_standard tap *
  page82_i106
#ISCELL
  mstr_standard tap *
  page82_i107
#ISCELL
  mstr_standard tap *
  page82_i108
#ISCELL
  mstr_standard tap *
  page82_i109
#ISCELL
  mstr_standard tap *
  page82_i11
#ISCELL
  mstr_standard tap *
  page82_i110
#ISCELL
  mstr_standard tap *
  page82_i112
#ISCELL
  mstr_standard tap *
  page82_i113
#ISCELL
  mstr_standard tap *
  page82_i114
#ISCELL
  mstr_standard tap *
  page82_i115
#ISCELL
  mstr_standard tap *
  page82_i116
#ISCELL
  mstr_standard tap *
  page82_i117
#ISCELL
  mstr_standard tap *
  page82_i118
#ISCELL
  mstr_standard tap *
  page82_i119
#ISCELL
  mstr_standard tap *
  page82_i12
#ISCELL
  mstr_standard tap *
  page82_i120
#ISCELL
  mstr_standard tap *
  page82_i121
#ISCELL
  mstr_standard tap *
  page82_i122
#ISCELL
  mstr_standard tap *
  page82_i123
#ISCELL
  mstr_standard tap *
  page82_i124
#ISCELL
  mstr_standard tap *
  page82_i125
#ISCELL
  mstr_standard tap *
  page82_i126
#ISCELL
  mstr_standard tap *
  page82_i127
#ISCELL
  mstr_standard tap *
  page82_i128
#ISCELL
  mstr_standard tap *
  page82_i129
#ISCELL
  mstr_standard tap *
  page82_i13
#ISCELL
  mstr_standard offpage *
  page82_i130
#ISCELL
  mstr_standard tap *
  page82_i131
#ISCELL
  mstr_standard tap *
  page82_i132
#ISCELL
  mstr_standard tap *
  page82_i133
#ISCELL
  mstr_standard tap *
  page82_i134
#ISCELL
  mstr_standard offpage *
  page82_i135
#ISCELL
  mstr_standard offpage *
  page82_i136
#ISCELL
  mstr_standard offpage *
  page82_i137
#ISCELL
  mstr_standard tap *
  page82_i138
#ISCELL
  mstr_standard tap *
  page82_i139
#ISCELL
  mstr_symbols pvddq_ghj *
  page82_i14
#ISCELL
  mstr_standard tap *
  page82_i140
#ISCELL
  mstr_standard tap *
  page82_i141
#ISCELL
  mstr_standard tap *
  page82_i142
#ISCELL
  mstr_standard tap *
  page82_i143
#ISCELL
  mstr_standard tap *
  page82_i144
#ISCELL
  mstr_standard tap *
  page82_i145
#ISCELL
  mstr_standard offpage *
  page82_i146
#ISCELL
  mstr_standard offpage *
  page82_i147
#ISCELL
  mstr_standard offpage *
  page82_i148
#ISCELL
  mstr_standard offpage *
  page82_i149
#ISCELL
  mstr_standard offpage *
  page82_i150
#ISCELL
  mstr_standard tap *
  page82_i152
#ISCELL
  mstr_standard tap *
  page82_i153
#ISCELL
  mstr_standard tap *
  page82_i154
#ISCELL
  mstr_standard tap *
  page82_i155
#ISCELL
  mstr_standard offpage *
  page82_i156
#ISCELL
  mstr_standard offpage *
  page82_i157
#ISCELL
  mstr_standard tap *
  page82_i158
#ISCELL
  mstr_standard tap *
  page82_i159
#ISCELL
  mstr_symbols pvtt_ghj *
  page82_i16
#ISCELL
  mstr_standard tap *
  page82_i160
#ISCELL
  mstr_standard tap *
  page82_i161
#ISCELL
  mstr_standard tap *
  page82_i162
#ISCELL
  mstr_standard offpage *
  page82_i163
#ISCELL
  mstr_standard offpage *
  page82_i164
#ISCELL
  mstr_standard tap *
  page82_i165
#ISCELL
  mstr_standard tap *
  page82_i166
#ISCELL
  mstr_standard offpage *
  page82_i167
#ISCELL
  mstr_standard tap *
  page82_i168
#ISCELL
  mstr_standard tap *
  page82_i17
#CELL
  mstr_sconn sconn288_h44441003 *
  page82_i171
#ISCELL
  mstr_symbols gnd *
  page82_i172
#ISCELL
  mstr_standard offpage *
  page82_i173
#ISCELL
  mstr_standard offpage *
  page82_i174
#ISCELL
  mstr_standard offpage *
  page82_i175
#ISCELL
  mstr_standard offpage *
  page82_i178
#ISCELL
  mstr_symbols gnd *
  page82_i179
#ISCELL
  mstr_standard tap *
  page82_i18
#CELL
  dev_discrete cap_a *
  page82_i180
#ISCELL
  mstr_symbols pvpp_ghj *
  page82_i181
#ISCELL
  mstr_symbols pvpp_ghj *
  page82_i182
#ISCELL
  mstr_standard offpage *
  page82_i183
#CELL
  mstr_sconn sconn288_h44441003 *
  page82_i187
#CELL
  mstr_sconn sconn288_h44441003 *
  page82_i188
#ISCELL
  mstr_symbols gnd *
  page82_i189
#ISCELL
  mstr_standard tap *
  page82_i19
#ISCELL
  mstr_symbols p12v_nvdimm_ghj *
  page82_i190
#ISCELL
  mstr_standard offpage *
  page82_i2
#ISCELL
  mstr_standard tap *
  page82_i20
#ISCELL
  mstr_standard tap *
  page82_i21
#ISCELL
  mstr_standard tap *
  page82_i22
#ISCELL
  mstr_standard tap *
  page82_i23
#ISCELL
  mstr_standard tap *
  page82_i24
#ISCELL
  mstr_standard tap *
  page82_i25
#ISCELL
  mstr_standard tap *
  page82_i26
#ISCELL
  mstr_standard tap *
  page82_i27
#ISCELL
  mstr_standard tap *
  page82_i28
#ISCELL
  mstr_standard tap *
  page82_i29
#ISCELL
  mstr_standard tap *
  page82_i3
#ISCELL
  mstr_standard tap *
  page82_i30
#ISCELL
  mstr_standard tap *
  page82_i31
#ISCELL
  mstr_standard tap *
  page82_i32
#ISCELL
  mstr_standard tap *
  page82_i33
#ISCELL
  mstr_standard tap *
  page82_i34
#ISCELL
  mstr_standard tap *
  page82_i35
#ISCELL
  mstr_standard tap *
  page82_i36
#ISCELL
  mstr_standard tap *
  page82_i37
#ISCELL
  mstr_standard tap *
  page82_i38
#ISCELL
  mstr_standard tap *
  page82_i39
#ISCELL
  mstr_standard tap *
  page82_i4
#ISCELL
  mstr_standard tap *
  page82_i40
#ISCELL
  mstr_standard tap *
  page82_i41
#ISCELL
  mstr_symbols gnd *
  page82_i44
#ISCELL
  mstr_standard offpage *
  page82_i45
#ISCELL
  mstr_standard tap *
  page82_i46
#ISCELL
  mstr_standard tap *
  page82_i47
#ISCELL
  mstr_standard tap *
  page82_i48
#ISCELL
  mstr_standard tap *
  page82_i49
#ISCELL
  mstr_standard tap *
  page82_i5
#ISCELL
  mstr_standard tap *
  page82_i50
#ISCELL
  mstr_standard tap *
  page82_i51
#ISCELL
  mstr_standard tap *
  page82_i52
#ISCELL
  mstr_standard tap *
  page82_i53
#ISCELL
  mstr_standard tap *
  page82_i54
#ISCELL
  mstr_standard tap *
  page82_i55
#ISCELL
  mstr_standard tap *
  page82_i56
#ISCELL
  mstr_standard tap *
  page82_i57
#ISCELL
  mstr_standard tap *
  page82_i58
#ISCELL
  mstr_standard tap *
  page82_i59
#ISCELL
  mstr_standard tap *
  page82_i6
#ISCELL
  mstr_standard tap *
  page82_i60
#ISCELL
  mstr_standard tap *
  page82_i61
#ISCELL
  mstr_standard tap *
  page82_i62
#ISCELL
  mstr_standard tap *
  page82_i63
#CELL
  mstr_sconn sconn288_h44441003 *
  page82_i64
#ISCELL
  mstr_standard tap *
  page82_i65
#ISCELL
  mstr_standard tap *
  page82_i66
#ISCELL
  mstr_standard tap *
  page82_i67
#ISCELL
  mstr_standard tap *
  page82_i68
#ISCELL
  mstr_standard tap *
  page82_i69
#ISCELL
  mstr_standard tap *
  page82_i7
#ISCELL
  mstr_standard tap *
  page82_i70
#ISCELL
  mstr_standard tap *
  page82_i71
#ISCELL
  mstr_standard tap *
  page82_i72
#ISCELL
  mstr_standard tap *
  page82_i73
#ISCELL
  mstr_standard tap *
  page82_i74
#ISCELL
  mstr_standard tap *
  page82_i75
#ISCELL
  mstr_standard tap *
  page82_i76
#ISCELL
  mstr_standard tap *
  page82_i77
#ISCELL
  mstr_standard tap *
  page82_i78
#ISCELL
  mstr_standard tap *
  page82_i79
#ISCELL
  mstr_standard tap *
  page82_i8
#ISCELL
  mstr_standard tap *
  page82_i80
#ISCELL
  mstr_standard tap *
  page82_i81
#ISCELL
  mstr_standard tap *
  page82_i82
#ISCELL
  mstr_standard tap *
  page82_i83
#ISCELL
  mstr_standard tap *
  page82_i84
#ISCELL
  mstr_standard tap *
  page82_i85
#ISCELL
  mstr_standard tap *
  page82_i86
#ISCELL
  mstr_standard tap *
  page82_i87
#ISCELL
  mstr_standard tap *
  page82_i88
#ISCELL
  mstr_standard tap *
  page82_i89
#ISCELL
  mstr_standard tap *
  page82_i9
#ISCELL
  mstr_standard tap *
  page82_i90
#ISCELL
  mstr_standard tap *
  page82_i91
#ISCELL
  mstr_standard tap *
  page82_i92
#ISCELL
  mstr_standard tap *
  page82_i93
#ISCELL
  mstr_standard tap *
  page82_i94
#ISCELL
  mstr_standard tap *
  page82_i95
#ISCELL
  mstr_standard tap *
  page82_i96
#ISCELL
  mstr_standard tap *
  page82_i97
#ISCELL
  mstr_standard tap *
  page82_i98
#ISCELL
  mstr_standard tap *
  page82_i99
#ISCELL
  mstr_symbols bom_note *
  *
#ISCELL
  mstr_symbols intel_corp_bpage *
  *
#ISCELL
  mstr_standard offpage *
  page83_i1
#ISCELL
  mstr_standard tap *
  page83_i10
#ISCELL
  mstr_standard tap *
  page83_i100
#ISCELL
  mstr_standard tap *
  page83_i101
#ISCELL
  mstr_standard tap *
  page83_i102
#ISCELL
  mstr_standard tap *
  page83_i103
#ISCELL
  mstr_standard tap *
  page83_i104
#ISCELL
  mstr_standard tap *
  page83_i105
#ISCELL
  mstr_standard tap *
  page83_i106
#ISCELL
  mstr_standard tap *
  page83_i107
#ISCELL
  mstr_standard tap *
  page83_i108
#ISCELL
  mstr_standard tap *
  page83_i109
#ISCELL
  mstr_standard tap *
  page83_i11
#ISCELL
  mstr_standard tap *
  page83_i110
#CELL
  mstr_sconn sconn288_h44441004 *
  page83_i111
#ISCELL
  mstr_standard tap *
  page83_i112
#ISCELL
  mstr_standard tap *
  page83_i113
#ISCELL
  mstr_standard tap *
  page83_i114
#ISCELL
  mstr_standard tap *
  page83_i115
#ISCELL
  mstr_standard tap *
  page83_i116
#ISCELL
  mstr_standard tap *
  page83_i117
#ISCELL
  mstr_standard tap *
  page83_i118
#ISCELL
  mstr_standard tap *
  page83_i119
#ISCELL
  mstr_standard tap *
  page83_i12
#ISCELL
  mstr_standard tap *
  page83_i120
#ISCELL
  mstr_standard tap *
  page83_i121
#ISCELL
  mstr_standard tap *
  page83_i122
#ISCELL
  mstr_standard tap *
  page83_i123
#ISCELL
  mstr_standard tap *
  page83_i124
#ISCELL
  mstr_standard tap *
  page83_i125
#ISCELL
  mstr_standard tap *
  page83_i126
#ISCELL
  mstr_standard tap *
  page83_i127
#ISCELL
  mstr_standard tap *
  page83_i128
#ISCELL
  mstr_standard tap *
  page83_i129
#ISCELL
  mstr_standard tap *
  page83_i13
#ISCELL
  mstr_standard tap *
  page83_i130
#ISCELL
  mstr_standard offpage *
  page83_i131
#ISCELL
  mstr_standard offpage *
  page83_i132
#ISCELL
  mstr_standard tap *
  page83_i133
#ISCELL
  mstr_standard tap *
  page83_i134
#ISCELL
  mstr_standard tap *
  page83_i135
#ISCELL
  mstr_standard offpage *
  page83_i136
#ISCELL
  mstr_standard offpage *
  page83_i137
#ISCELL
  mstr_standard tap *
  page83_i138
#ISCELL
  mstr_standard tap *
  page83_i139
#ISCELL
  mstr_standard tap *
  page83_i14
#ISCELL
  mstr_standard tap *
  page83_i140
#ISCELL
  mstr_standard tap *
  page83_i141
#ISCELL
  mstr_standard tap *
  page83_i142
#ISCELL
  mstr_standard tap *
  page83_i143
#ISCELL
  mstr_standard tap *
  page83_i144
#ISCELL
  mstr_standard tap *
  page83_i145
#ISCELL
  mstr_standard offpage *
  page83_i146
#ISCELL
  mstr_standard offpage *
  page83_i147
#ISCELL
  mstr_standard offpage *
  page83_i148
#ISCELL
  mstr_standard offpage *
  page83_i149
#ISCELL
  mstr_standard tap *
  page83_i15
#ISCELL
  mstr_standard offpage *
  page83_i150
#ISCELL
  mstr_standard tap *
  page83_i152
#ISCELL
  mstr_standard tap *
  page83_i153
#ISCELL
  mstr_standard tap *
  page83_i154
#ISCELL
  mstr_standard tap *
  page83_i155
#ISCELL
  mstr_standard tap *
  page83_i156
#ISCELL
  mstr_standard offpage *
  page83_i157
#ISCELL
  mstr_standard offpage *
  page83_i158
#ISCELL
  mstr_standard tap *
  page83_i159
#ISCELL
  mstr_symbols pvddq_klm *
  page83_i16
#ISCELL
  mstr_standard offpage *
  page83_i160
#ISCELL
  mstr_standard offpage *
  page83_i161
#ISCELL
  mstr_standard offpage *
  page83_i162
#ISCELL
  mstr_standard tap *
  page83_i163
#ISCELL
  mstr_standard tap *
  page83_i164
#ISCELL
  mstr_standard tap *
  page83_i165
#ISCELL
  mstr_standard tap *
  page83_i166
#CELL
  mstr_sconn sconn288_h44441004 *
  page83_i167
#ISCELL
  mstr_symbols gnd *
  page83_i168
#ISCELL
  mstr_standard offpage *
  page83_i169
#ISCELL
  mstr_symbols pvtt_klm *
  page83_i17
#ISCELL
  mstr_standard offpage *
  page83_i170
#ISCELL
  mstr_standard offpage *
  page83_i171
#ISCELL
  mstr_symbols gnd *
  page83_i173
#ISCELL
  mstr_standard offpage *
  page83_i174
#ISCELL
  mstr_symbols gnd *
  page83_i175
#CELL
  dev_discrete cap_a *
  page83_i176
#ISCELL
  mstr_symbols pvpp_klm *
  page83_i177
#ISCELL
  mstr_symbols pvpp_klm *
  page83_i178
#ISCELL
  mstr_standard offpage *
  page83_i179
#ISCELL
  mstr_standard tap *
  page83_i183
#ISCELL
  mstr_standard tap *
  page83_i184
#ISCELL
  mstr_symbols p12v_nvdimm_klm *
  page83_i185
#ISCELL
  mstr_standard tap *
  page83_i19
#ISCELL
  mstr_standard offpage *
  page83_i2
#ISCELL
  mstr_standard tap *
  page83_i20
#ISCELL
  mstr_standard tap *
  page83_i21
#ISCELL
  mstr_standard tap *
  page83_i22
#ISCELL
  mstr_standard tap *
  page83_i23
#ISCELL
  mstr_standard tap *
  page83_i24
#ISCELL
  mstr_standard tap *
  page83_i25
#ISCELL
  mstr_standard tap *
  page83_i26
#ISCELL
  mstr_standard tap *
  page83_i27
#ISCELL
  mstr_standard tap *
  page83_i28
#ISCELL
  mstr_standard tap *
  page83_i29
#ISCELL
  mstr_standard tap *
  page83_i3
#ISCELL
  mstr_standard tap *
  page83_i30
#ISCELL
  mstr_standard tap *
  page83_i31
#ISCELL
  mstr_standard tap *
  page83_i32
#ISCELL
  mstr_standard tap *
  page83_i33
#ISCELL
  mstr_standard tap *
  page83_i34
#ISCELL
  mstr_standard tap *
  page83_i35
#ISCELL
  mstr_standard tap *
  page83_i36
#ISCELL
  mstr_standard tap *
  page83_i37
#ISCELL
  mstr_standard tap *
  page83_i38
#ISCELL
  mstr_standard tap *
  page83_i39
#ISCELL
  mstr_standard tap *
  page83_i4
#ISCELL
  mstr_standard tap *
  page83_i40
#ISCELL
  mstr_standard tap *
  page83_i41
#CELL
  mstr_sconn sconn288_h44441004 *
  page83_i43
#ISCELL
  mstr_symbols gnd *
  page83_i44
#ISCELL
  mstr_standard offpage *
  page83_i45
#ISCELL
  mstr_standard tap *
  page83_i46
#ISCELL
  mstr_standard tap *
  page83_i47
#ISCELL
  mstr_standard tap *
  page83_i48
#ISCELL
  mstr_standard tap *
  page83_i49
#ISCELL
  mstr_standard tap *
  page83_i5
#ISCELL
  mstr_standard tap *
  page83_i50
#ISCELL
  mstr_standard tap *
  page83_i51
#ISCELL
  mstr_standard tap *
  page83_i52
#ISCELL
  mstr_standard tap *
  page83_i53
#ISCELL
  mstr_standard tap *
  page83_i54
#ISCELL
  mstr_standard tap *
  page83_i55
#ISCELL
  mstr_standard tap *
  page83_i56
#ISCELL
  mstr_standard tap *
  page83_i57
#ISCELL
  mstr_standard tap *
  page83_i58
#ISCELL
  mstr_standard tap *
  page83_i59
#ISCELL
  mstr_standard tap *
  page83_i6
#ISCELL
  mstr_standard tap *
  page83_i60
#ISCELL
  mstr_standard tap *
  page83_i61
#ISCELL
  mstr_standard tap *
  page83_i62
#ISCELL
  mstr_standard tap *
  page83_i63
#ISCELL
  mstr_standard tap *
  page83_i64
#ISCELL
  mstr_standard tap *
  page83_i65
#CELL
  mstr_sconn sconn288_h44441004 *
  page83_i66
#ISCELL
  mstr_standard tap *
  page83_i67
#ISCELL
  mstr_standard tap *
  page83_i68
#ISCELL
  mstr_standard tap *
  page83_i69
#ISCELL
  mstr_standard tap *
  page83_i7
#ISCELL
  mstr_standard tap *
  page83_i70
#ISCELL
  mstr_standard tap *
  page83_i71
#ISCELL
  mstr_standard tap *
  page83_i72
#ISCELL
  mstr_standard tap *
  page83_i73
#ISCELL
  mstr_standard tap *
  page83_i74
#ISCELL
  mstr_standard tap *
  page83_i75
#ISCELL
  mstr_standard tap *
  page83_i76
#ISCELL
  mstr_standard tap *
  page83_i77
#ISCELL
  mstr_standard tap *
  page83_i78
#ISCELL
  mstr_standard tap *
  page83_i79
#ISCELL
  mstr_standard tap *
  page83_i8
#ISCELL
  mstr_standard tap *
  page83_i80
#ISCELL
  mstr_standard tap *
  page83_i81
#ISCELL
  mstr_standard tap *
  page83_i82
#ISCELL
  mstr_standard tap *
  page83_i83
#ISCELL
  mstr_standard tap *
  page83_i84
#ISCELL
  mstr_standard tap *
  page83_i85
#ISCELL
  mstr_standard tap *
  page83_i86
#ISCELL
  mstr_standard tap *
  page83_i87
#ISCELL
  mstr_standard tap *
  page83_i88
#ISCELL
  mstr_standard tap *
  page83_i89
#ISCELL
  mstr_standard tap *
  page83_i9
#ISCELL
  mstr_standard tap *
  page83_i90
#ISCELL
  mstr_standard tap *
  page83_i91
#ISCELL
  mstr_standard tap *
  page83_i92
#ISCELL
  mstr_standard tap *
  page83_i93
#ISCELL
  mstr_standard tap *
  page83_i94
#ISCELL
  mstr_standard tap *
  page83_i95
#ISCELL
  mstr_standard tap *
  page83_i96
#ISCELL
  mstr_standard tap *
  page83_i97
#ISCELL
  mstr_standard tap *
  page83_i98
#ISCELL
  mstr_standard tap *
  page83_i99
#ISCELL
  mstr_symbols bom_note *
  *
#ISCELL
  mstr_symbols intel_corp_bpage *
  *
#ISCELL
  mstr_symbols gnd *
  page84_i1
#ISCELL
  mstr_standard offpage *
  page84_i10
#ISCELL
  mstr_symbols pvtt_klm *
  page84_i100
#ISCELL
  mstr_symbols pvpp_klm *
  page84_i101
#CELL
  mstr_sconn sconn288_h44441003 *
  page84_i102
#ISCELL
  mstr_standard offpage *
  page84_i103
#ISCELL
  mstr_standard tap *
  page84_i104
#ISCELL
  mstr_standard tap *
  page84_i105
#ISCELL
  mstr_standard tap *
  page84_i106
#ISCELL
  mstr_standard tap *
  page84_i107
#ISCELL
  mstr_standard tap *
  page84_i108
#ISCELL
  mstr_standard tap *
  page84_i109
#ISCELL
  mstr_standard offpage *
  page84_i11
#ISCELL
  mstr_standard tap *
  page84_i110
#ISCELL
  mstr_standard tap *
  page84_i111
#ISCELL
  mstr_standard tap *
  page84_i112
#ISCELL
  mstr_standard tap *
  page84_i113
#ISCELL
  mstr_standard tap *
  page84_i114
#ISCELL
  mstr_standard tap *
  page84_i115
#ISCELL
  mstr_standard tap *
  page84_i116
#ISCELL
  mstr_standard tap *
  page84_i117
#ISCELL
  mstr_standard tap *
  page84_i118
#ISCELL
  mstr_standard tap *
  page84_i119
#ISCELL
  mstr_standard offpage *
  page84_i12
#ISCELL
  mstr_standard tap *
  page84_i120
#ISCELL
  mstr_standard tap *
  page84_i121
#ISCELL
  mstr_standard tap *
  page84_i122
#ISCELL
  mstr_standard tap *
  page84_i123
#ISCELL
  mstr_standard tap *
  page84_i124
#ISCELL
  mstr_standard tap *
  page84_i125
#ISCELL
  mstr_standard tap *
  page84_i126
#ISCELL
  mstr_standard tap *
  page84_i127
#ISCELL
  mstr_standard tap *
  page84_i128
#ISCELL
  mstr_standard tap *
  page84_i129
#ISCELL
  mstr_standard offpage *
  page84_i13
#ISCELL
  mstr_standard tap *
  page84_i130
#ISCELL
  mstr_standard tap *
  page84_i131
#ISCELL
  mstr_standard tap *
  page84_i132
#ISCELL
  mstr_standard tap *
  page84_i133
#ISCELL
  mstr_standard tap *
  page84_i134
#ISCELL
  mstr_standard tap *
  page84_i135
#ISCELL
  mstr_standard offpage *
  page84_i136
#ISCELL
  mstr_symbols gnd *
  page84_i137
#CELL
  mstr_sconn sconn288_h44441003 *
  page84_i138
#CELL
  mstr_sconn sconn288_h44441003 *
  page84_i14
#ISCELL
  mstr_standard tap *
  page84_i142
#ISCELL
  mstr_standard tap *
  page84_i143
#ISCELL
  mstr_standard tap *
  page84_i144
#ISCELL
  mstr_standard tap *
  page84_i145
#ISCELL
  mstr_standard tap *
  page84_i146
#ISCELL
  mstr_standard tap *
  page84_i147
#ISCELL
  mstr_standard tap *
  page84_i148
#ISCELL
  mstr_standard tap *
  page84_i149
#ISCELL
  mstr_standard offpage *
  page84_i15
#ISCELL
  mstr_standard tap *
  page84_i150
#ISCELL
  mstr_standard tap *
  page84_i151
#ISCELL
  mstr_standard tap *
  page84_i152
#ISCELL
  mstr_standard tap *
  page84_i153
#ISCELL
  mstr_standard tap *
  page84_i154
#ISCELL
  mstr_symbols gnd *
  page84_i155
#ISCELL
  mstr_standard tap *
  page84_i156
#ISCELL
  mstr_standard tap *
  page84_i157
#ISCELL
  mstr_standard tap *
  page84_i158
#ISCELL
  mstr_standard tap *
  page84_i159
#ISCELL
  mstr_standard offpage *
  page84_i16
#ISCELL
  mstr_standard tap *
  page84_i160
#ISCELL
  mstr_standard tap *
  page84_i161
#ISCELL
  mstr_standard tap *
  page84_i162
#ISCELL
  mstr_standard tap *
  page84_i163
#ISCELL
  mstr_standard tap *
  page84_i164
#ISCELL
  mstr_standard tap *
  page84_i165
#ISCELL
  mstr_standard tap *
  page84_i166
#ISCELL
  mstr_standard tap *
  page84_i167
#ISCELL
  mstr_standard tap *
  page84_i168
#ISCELL
  mstr_standard tap *
  page84_i169
#ISCELL
  mstr_standard offpage *
  page84_i17
#ISCELL
  mstr_standard tap *
  page84_i170
#ISCELL
  mstr_standard tap *
  page84_i171
#ISCELL
  mstr_standard tap *
  page84_i172
#ISCELL
  mstr_standard tap *
  page84_i173
#ISCELL
  mstr_standard tap *
  page84_i174
#ISCELL
  mstr_standard tap *
  page84_i175
#ISCELL
  mstr_standard tap *
  page84_i176
#ISCELL
  mstr_standard tap *
  page84_i177
#ISCELL
  mstr_standard tap *
  page84_i178
#ISCELL
  mstr_standard offpage *
  page84_i179
#ISCELL
  mstr_standard offpage *
  page84_i18
#ISCELL
  mstr_standard offpage *
  page84_i180
#ISCELL
  mstr_symbols p12v_nvdimm_klm *
  page84_i181
#ISCELL
  mstr_standard tap *
  page84_i19
#ISCELL
  mstr_standard offpage *
  page84_i2
#ISCELL
  mstr_standard tap *
  page84_i20
#ISCELL
  mstr_standard tap *
  page84_i21
#ISCELL
  mstr_standard tap *
  page84_i22
#ISCELL
  mstr_standard tap *
  page84_i23
#ISCELL
  mstr_standard tap *
  page84_i24
#ISCELL
  mstr_standard tap *
  page84_i25
#ISCELL
  mstr_standard tap *
  page84_i26
#ISCELL
  mstr_standard tap *
  page84_i27
#ISCELL
  mstr_standard tap *
  page84_i28
#ISCELL
  mstr_standard tap *
  page84_i29
#ISCELL
  mstr_symbols gnd *
  page84_i3
#ISCELL
  mstr_standard offpage *
  page84_i30
#ISCELL
  mstr_standard offpage *
  page84_i31
#ISCELL
  mstr_standard offpage *
  page84_i32
#ISCELL
  mstr_standard tap *
  page84_i33
#ISCELL
  mstr_standard tap *
  page84_i34
#ISCELL
  mstr_standard offpage *
  page84_i35
#ISCELL
  mstr_standard offpage *
  page84_i36
#ISCELL
  mstr_standard tap *
  page84_i37
#ISCELL
  mstr_standard tap *
  page84_i38
#ISCELL
  mstr_standard tap *
  page84_i39
#CELL
  dev_discrete cap_a *
  page84_i4
#ISCELL
  mstr_standard tap *
  page84_i40
#ISCELL
  mstr_standard tap *
  page84_i41
#ISCELL
  mstr_standard tap *
  page84_i42
#ISCELL
  mstr_standard tap *
  page84_i43
#ISCELL
  mstr_standard tap *
  page84_i44
#ISCELL
  mstr_standard tap *
  page84_i45
#ISCELL
  mstr_standard tap *
  page84_i46
#ISCELL
  mstr_standard tap *
  page84_i47
#ISCELL
  mstr_standard tap *
  page84_i48
#ISCELL
  mstr_standard tap *
  page84_i49
#ISCELL
  mstr_symbols pvpp_klm *
  page84_i5
#ISCELL
  mstr_standard tap *
  page84_i50
#ISCELL
  mstr_standard tap *
  page84_i51
#ISCELL
  mstr_standard tap *
  page84_i52
#ISCELL
  mstr_standard tap *
  page84_i53
#ISCELL
  mstr_standard tap *
  page84_i54
#ISCELL
  mstr_standard tap *
  page84_i55
#ISCELL
  mstr_standard tap *
  page84_i56
#CELL
  mstr_sconn sconn288_h44441003 *
  page84_i57
#ISCELL
  mstr_standard tap *
  page84_i58
#ISCELL
  mstr_standard tap *
  page84_i59
#ISCELL
  mstr_standard offpage *
  page84_i6
#ISCELL
  mstr_standard tap *
  page84_i60
#ISCELL
  mstr_standard tap *
  page84_i61
#ISCELL
  mstr_standard tap *
  page84_i62
#ISCELL
  mstr_standard tap *
  page84_i63
#ISCELL
  mstr_standard tap *
  page84_i64
#ISCELL
  mstr_standard tap *
  page84_i65
#ISCELL
  mstr_standard tap *
  page84_i66
#ISCELL
  mstr_standard tap *
  page84_i67
#ISCELL
  mstr_standard tap *
  page84_i68
#ISCELL
  mstr_standard tap *
  page84_i69
#ISCELL
  mstr_standard offpage *
  page84_i7
#ISCELL
  mstr_standard tap *
  page84_i70
#ISCELL
  mstr_standard tap *
  page84_i71
#ISCELL
  mstr_standard tap *
  page84_i72
#ISCELL
  mstr_standard tap *
  page84_i73
#ISCELL
  mstr_standard tap *
  page84_i74
#ISCELL
  mstr_standard tap *
  page84_i75
#ISCELL
  mstr_standard tap *
  page84_i76
#ISCELL
  mstr_standard tap *
  page84_i77
#ISCELL
  mstr_standard tap *
  page84_i78
#ISCELL
  mstr_symbols pvddq_klm *
  page84_i79
#ISCELL
  mstr_standard offpage *
  page84_i8
#ISCELL
  mstr_standard tap *
  page84_i80
#ISCELL
  mstr_standard tap *
  page84_i81
#ISCELL
  mstr_standard tap *
  page84_i82
#ISCELL
  mstr_standard tap *
  page84_i83
#ISCELL
  mstr_standard tap *
  page84_i84
#ISCELL
  mstr_standard tap *
  page84_i85
#ISCELL
  mstr_standard tap *
  page84_i86
#ISCELL
  mstr_standard tap *
  page84_i87
#ISCELL
  mstr_standard tap *
  page84_i88
#ISCELL
  mstr_standard tap *
  page84_i89
#ISCELL
  mstr_standard offpage *
  page84_i9
#ISCELL
  mstr_standard tap *
  page84_i90
#ISCELL
  mstr_standard tap *
  page84_i91
#ISCELL
  mstr_standard tap *
  page84_i92
#ISCELL
  mstr_standard tap *
  page84_i93
#ISCELL
  mstr_standard tap *
  page84_i94
#ISCELL
  mstr_standard tap *
  page84_i95
#ISCELL
  mstr_standard tap *
  page84_i96
#ISCELL
  mstr_standard tap *
  page84_i97
#ISCELL
  mstr_standard tap *
  page84_i98
#ISCELL
  mstr_standard tap *
  page84_i99
#ISCELL
  mstr_symbols bom_note *
  *
#ISCELL
  mstr_symbols intel_corp_bpage *
  *
#ISCELL
  mstr_standard offpage *
  page85_i1
#ISCELL
  mstr_standard tap *
  page85_i10
#ISCELL
  mstr_standard tap *
  page85_i100
#ISCELL
  mstr_standard tap *
  page85_i101
#ISCELL
  mstr_standard tap *
  page85_i102
#ISCELL
  mstr_standard tap *
  page85_i103
#ISCELL
  mstr_standard tap *
  page85_i104
#ISCELL
  mstr_standard tap *
  page85_i105
#ISCELL
  mstr_standard tap *
  page85_i106
#ISCELL
  mstr_standard tap *
  page85_i107
#ISCELL
  mstr_standard tap *
  page85_i108
#ISCELL
  mstr_standard tap *
  page85_i109
#ISCELL
  mstr_standard tap *
  page85_i11
#ISCELL
  mstr_standard tap *
  page85_i110
#CELL
  mstr_sconn sconn288_h44441004 *
  page85_i111
#ISCELL
  mstr_standard tap *
  page85_i112
#ISCELL
  mstr_standard tap *
  page85_i113
#ISCELL
  mstr_standard tap *
  page85_i114
#ISCELL
  mstr_standard tap *
  page85_i115
#ISCELL
  mstr_standard tap *
  page85_i116
#ISCELL
  mstr_standard tap *
  page85_i117
#ISCELL
  mstr_standard tap *
  page85_i118
#ISCELL
  mstr_standard tap *
  page85_i119
#ISCELL
  mstr_standard tap *
  page85_i12
#ISCELL
  mstr_standard tap *
  page85_i120
#ISCELL
  mstr_standard tap *
  page85_i121
#ISCELL
  mstr_standard tap *
  page85_i122
#ISCELL
  mstr_standard tap *
  page85_i123
#ISCELL
  mstr_standard tap *
  page85_i124
#ISCELL
  mstr_standard tap *
  page85_i125
#ISCELL
  mstr_standard tap *
  page85_i126
#ISCELL
  mstr_standard tap *
  page85_i127
#ISCELL
  mstr_standard tap *
  page85_i128
#ISCELL
  mstr_standard tap *
  page85_i129
#ISCELL
  mstr_standard tap *
  page85_i13
#ISCELL
  mstr_standard tap *
  page85_i130
#ISCELL
  mstr_standard offpage *
  page85_i131
#ISCELL
  mstr_standard offpage *
  page85_i132
#ISCELL
  mstr_standard tap *
  page85_i133
#ISCELL
  mstr_standard tap *
  page85_i134
#ISCELL
  mstr_standard tap *
  page85_i135
#ISCELL
  mstr_standard offpage *
  page85_i136
#ISCELL
  mstr_standard offpage *
  page85_i137
#ISCELL
  mstr_standard tap *
  page85_i138
#ISCELL
  mstr_standard tap *
  page85_i139
#ISCELL
  mstr_standard tap *
  page85_i14
#ISCELL
  mstr_standard tap *
  page85_i140
#ISCELL
  mstr_standard tap *
  page85_i141
#ISCELL
  mstr_standard tap *
  page85_i142
#ISCELL
  mstr_standard tap *
  page85_i143
#ISCELL
  mstr_standard tap *
  page85_i144
#ISCELL
  mstr_standard tap *
  page85_i145
#ISCELL
  mstr_standard offpage *
  page85_i146
#ISCELL
  mstr_standard offpage *
  page85_i147
#ISCELL
  mstr_standard offpage *
  page85_i148
#ISCELL
  mstr_standard offpage *
  page85_i149
#ISCELL
  mstr_standard tap *
  page85_i15
#ISCELL
  mstr_standard offpage *
  page85_i150
#ISCELL
  mstr_standard tap *
  page85_i152
#ISCELL
  mstr_standard tap *
  page85_i153
#ISCELL
  mstr_standard tap *
  page85_i154
#ISCELL
  mstr_standard tap *
  page85_i155
#ISCELL
  mstr_standard offpage *
  page85_i156
#ISCELL
  mstr_standard offpage *
  page85_i157
#ISCELL
  mstr_standard tap *
  page85_i159
#ISCELL
  mstr_symbols pvddq_klm *
  page85_i16
#ISCELL
  mstr_standard tap *
  page85_i160
#ISCELL
  mstr_standard tap *
  page85_i161
#ISCELL
  mstr_standard tap *
  page85_i162
#ISCELL
  mstr_standard tap *
  page85_i163
#ISCELL
  mstr_standard offpage *
  page85_i164
#ISCELL
  mstr_standard offpage *
  page85_i165
#ISCELL
  mstr_standard tap *
  page85_i166
#ISCELL
  mstr_standard tap *
  page85_i167
#ISCELL
  mstr_standard tap *
  page85_i168
#ISCELL
  mstr_standard offpage *
  page85_i169
#ISCELL
  mstr_symbols pvtt_klm *
  page85_i17
#CELL
  mstr_sconn sconn288_h44441004 *
  page85_i172
#ISCELL
  mstr_symbols gnd *
  page85_i173
#ISCELL
  mstr_symbols gnd *
  page85_i175
#ISCELL
  mstr_standard offpage *
  page85_i176
#ISCELL
  mstr_standard offpage *
  page85_i177
#ISCELL
  mstr_standard offpage *
  page85_i178
#ISCELL
  mstr_standard offpage *
  page85_i179
#ISCELL
  mstr_symbols gnd *
  page85_i180
#CELL
  dev_discrete cap_a *
  page85_i181
#ISCELL
  mstr_symbols pvpp_klm *
  page85_i182
#ISCELL
  mstr_symbols pvpp_klm *
  page85_i183
#ISCELL
  mstr_standard offpage *
  page85_i184
#ISCELL
  mstr_symbols p12v_nvdimm_klm *
  page85_i185
#ISCELL
  mstr_standard tap *
  page85_i19
#ISCELL
  mstr_standard offpage *
  page85_i2
#ISCELL
  mstr_standard tap *
  page85_i20
#ISCELL
  mstr_standard tap *
  page85_i21
#ISCELL
  mstr_standard tap *
  page85_i22
#ISCELL
  mstr_standard tap *
  page85_i23
#ISCELL
  mstr_standard tap *
  page85_i24
#ISCELL
  mstr_standard tap *
  page85_i25
#ISCELL
  mstr_standard tap *
  page85_i26
#ISCELL
  mstr_standard tap *
  page85_i27
#ISCELL
  mstr_standard tap *
  page85_i28
#ISCELL
  mstr_standard tap *
  page85_i29
#ISCELL
  mstr_standard tap *
  page85_i3
#ISCELL
  mstr_standard tap *
  page85_i30
#ISCELL
  mstr_standard tap *
  page85_i31
#ISCELL
  mstr_standard tap *
  page85_i32
#ISCELL
  mstr_standard tap *
  page85_i33
#ISCELL
  mstr_standard tap *
  page85_i34
#ISCELL
  mstr_standard tap *
  page85_i35
#ISCELL
  mstr_standard tap *
  page85_i36
#ISCELL
  mstr_standard tap *
  page85_i37
#ISCELL
  mstr_standard tap *
  page85_i38
#ISCELL
  mstr_standard tap *
  page85_i39
#ISCELL
  mstr_standard tap *
  page85_i4
#ISCELL
  mstr_standard tap *
  page85_i40
#ISCELL
  mstr_standard tap *
  page85_i41
#CELL
  mstr_sconn sconn288_h44441004 *
  page85_i43
#ISCELL
  mstr_symbols gnd *
  page85_i44
#ISCELL
  mstr_standard offpage *
  page85_i45
#ISCELL
  mstr_standard tap *
  page85_i46
#ISCELL
  mstr_standard tap *
  page85_i47
#ISCELL
  mstr_standard tap *
  page85_i48
#ISCELL
  mstr_standard tap *
  page85_i49
#ISCELL
  mstr_standard tap *
  page85_i5
#ISCELL
  mstr_standard tap *
  page85_i50
#ISCELL
  mstr_standard tap *
  page85_i51
#ISCELL
  mstr_standard tap *
  page85_i52
#ISCELL
  mstr_standard tap *
  page85_i53
#ISCELL
  mstr_standard tap *
  page85_i54
#ISCELL
  mstr_standard tap *
  page85_i55
#ISCELL
  mstr_standard tap *
  page85_i56
#ISCELL
  mstr_standard tap *
  page85_i57
#ISCELL
  mstr_standard tap *
  page85_i58
#ISCELL
  mstr_standard tap *
  page85_i59
#ISCELL
  mstr_standard tap *
  page85_i6
#ISCELL
  mstr_standard tap *
  page85_i60
#ISCELL
  mstr_standard tap *
  page85_i61
#ISCELL
  mstr_standard tap *
  page85_i62
#ISCELL
  mstr_standard tap *
  page85_i63
#ISCELL
  mstr_standard tap *
  page85_i64
#ISCELL
  mstr_standard tap *
  page85_i65
#CELL
  mstr_sconn sconn288_h44441004 *
  page85_i66
#ISCELL
  mstr_standard tap *
  page85_i67
#ISCELL
  mstr_standard tap *
  page85_i68
#ISCELL
  mstr_standard tap *
  page85_i69
#ISCELL
  mstr_standard tap *
  page85_i7
#ISCELL
  mstr_standard tap *
  page85_i70
#ISCELL
  mstr_standard tap *
  page85_i71
#ISCELL
  mstr_standard tap *
  page85_i72
#ISCELL
  mstr_standard tap *
  page85_i73
#ISCELL
  mstr_standard tap *
  page85_i74
#ISCELL
  mstr_standard tap *
  page85_i75
#ISCELL
  mstr_standard tap *
  page85_i76
#ISCELL
  mstr_standard tap *
  page85_i77
#ISCELL
  mstr_standard tap *
  page85_i78
#ISCELL
  mstr_standard tap *
  page85_i79
#ISCELL
  mstr_standard tap *
  page85_i8
#ISCELL
  mstr_standard tap *
  page85_i80
#ISCELL
  mstr_standard tap *
  page85_i81
#ISCELL
  mstr_standard tap *
  page85_i82
#ISCELL
  mstr_standard tap *
  page85_i83
#ISCELL
  mstr_standard tap *
  page85_i84
#ISCELL
  mstr_standard tap *
  page85_i85
#ISCELL
  mstr_standard tap *
  page85_i86
#ISCELL
  mstr_standard tap *
  page85_i87
#ISCELL
  mstr_standard tap *
  page85_i88
#ISCELL
  mstr_standard tap *
  page85_i89
#ISCELL
  mstr_standard tap *
  page85_i9
#ISCELL
  mstr_standard tap *
  page85_i90
#ISCELL
  mstr_standard tap *
  page85_i91
#ISCELL
  mstr_standard tap *
  page85_i92
#ISCELL
  mstr_standard tap *
  page85_i93
#ISCELL
  mstr_standard tap *
  page85_i94
#ISCELL
  mstr_standard tap *
  page85_i95
#ISCELL
  mstr_standard tap *
  page85_i96
#ISCELL
  mstr_standard tap *
  page85_i97
#ISCELL
  mstr_standard tap *
  page85_i98
#ISCELL
  mstr_standard tap *
  page85_i99
#ISCELL
  mstr_symbols bom_note *
  *
#ISCELL
  mstr_symbols intel_corp_bpage *
  *
#ISCELL
  mstr_symbols gnd *
  page86_i1
#ISCELL
  mstr_standard offpage *
  page86_i10
#CELL
  mstr_sconn sconn288_h44441003 *
  page86_i100
#ISCELL
  mstr_standard offpage *
  page86_i101
#ISCELL
  mstr_standard tap *
  page86_i102
#ISCELL
  mstr_standard tap *
  page86_i103
#ISCELL
  mstr_standard tap *
  page86_i104
#ISCELL
  mstr_standard tap *
  page86_i105
#ISCELL
  mstr_standard tap *
  page86_i106
#ISCELL
  mstr_standard tap *
  page86_i107
#ISCELL
  mstr_standard tap *
  page86_i108
#ISCELL
  mstr_standard tap *
  page86_i109
#ISCELL
  mstr_standard offpage *
  page86_i11
#ISCELL
  mstr_standard tap *
  page86_i110
#ISCELL
  mstr_standard tap *
  page86_i111
#ISCELL
  mstr_standard tap *
  page86_i112
#ISCELL
  mstr_standard tap *
  page86_i113
#ISCELL
  mstr_standard tap *
  page86_i114
#ISCELL
  mstr_standard tap *
  page86_i115
#ISCELL
  mstr_standard tap *
  page86_i116
#ISCELL
  mstr_standard tap *
  page86_i117
#ISCELL
  mstr_standard tap *
  page86_i118
#ISCELL
  mstr_standard tap *
  page86_i119
#CELL
  mstr_sconn sconn288_h44441003 *
  page86_i12
#ISCELL
  mstr_standard tap *
  page86_i120
#ISCELL
  mstr_standard tap *
  page86_i121
#ISCELL
  mstr_standard tap *
  page86_i122
#ISCELL
  mstr_standard tap *
  page86_i123
#ISCELL
  mstr_standard tap *
  page86_i124
#ISCELL
  mstr_standard tap *
  page86_i125
#ISCELL
  mstr_standard tap *
  page86_i126
#ISCELL
  mstr_standard tap *
  page86_i127
#ISCELL
  mstr_standard tap *
  page86_i128
#ISCELL
  mstr_standard tap *
  page86_i129
#ISCELL
  mstr_standard offpage *
  page86_i13
#ISCELL
  mstr_standard tap *
  page86_i130
#ISCELL
  mstr_standard tap *
  page86_i131
#ISCELL
  mstr_standard tap *
  page86_i132
#ISCELL
  mstr_standard tap *
  page86_i133
#ISCELL
  mstr_standard tap *
  page86_i134
#ISCELL
  mstr_standard tap *
  page86_i135
#ISCELL
  mstr_standard offpage *
  page86_i136
#ISCELL
  mstr_symbols gnd *
  page86_i137
#CELL
  mstr_sconn sconn288_h44441003 *
  page86_i138
#ISCELL
  mstr_standard offpage *
  page86_i14
#ISCELL
  mstr_standard tap *
  page86_i142
#ISCELL
  mstr_standard tap *
  page86_i143
#ISCELL
  mstr_standard tap *
  page86_i144
#ISCELL
  mstr_standard tap *
  page86_i145
#ISCELL
  mstr_standard tap *
  page86_i146
#ISCELL
  mstr_standard tap *
  page86_i147
#ISCELL
  mstr_standard tap *
  page86_i148
#ISCELL
  mstr_standard tap *
  page86_i149
#ISCELL
  mstr_standard offpage *
  page86_i15
#ISCELL
  mstr_standard tap *
  page86_i150
#ISCELL
  mstr_standard tap *
  page86_i151
#ISCELL
  mstr_standard tap *
  page86_i152
#ISCELL
  mstr_standard tap *
  page86_i153
#ISCELL
  mstr_standard tap *
  page86_i154
#ISCELL
  mstr_standard tap *
  page86_i155
#ISCELL
  mstr_symbols gnd *
  page86_i156
#ISCELL
  mstr_standard tap *
  page86_i157
#ISCELL
  mstr_standard tap *
  page86_i158
#ISCELL
  mstr_standard tap *
  page86_i159
#ISCELL
  mstr_standard offpage *
  page86_i16
#ISCELL
  mstr_standard tap *
  page86_i160
#ISCELL
  mstr_standard tap *
  page86_i161
#ISCELL
  mstr_standard tap *
  page86_i162
#ISCELL
  mstr_standard tap *
  page86_i163
#ISCELL
  mstr_standard tap *
  page86_i164
#ISCELL
  mstr_standard tap *
  page86_i165
#ISCELL
  mstr_standard tap *
  page86_i166
#ISCELL
  mstr_standard tap *
  page86_i167
#ISCELL
  mstr_standard tap *
  page86_i168
#ISCELL
  mstr_standard tap *
  page86_i169
#ISCELL
  mstr_standard tap *
  page86_i17
#ISCELL
  mstr_standard tap *
  page86_i170
#ISCELL
  mstr_standard tap *
  page86_i171
#ISCELL
  mstr_standard tap *
  page86_i172
#ISCELL
  mstr_standard tap *
  page86_i173
#ISCELL
  mstr_standard tap *
  page86_i174
#ISCELL
  mstr_standard tap *
  page86_i175
#ISCELL
  mstr_standard tap *
  page86_i176
#ISCELL
  mstr_standard tap *
  page86_i177
#ISCELL
  mstr_standard tap *
  page86_i178
#ISCELL
  mstr_standard offpage *
  page86_i179
#ISCELL
  mstr_standard tap *
  page86_i18
#ISCELL
  mstr_standard offpage *
  page86_i180
#ISCELL
  mstr_symbols p12v_nvdimm_klm *
  page86_i181
#CELL
  dev_discrete cap_a *
  page86_i182
#ISCELL
  mstr_standard tap *
  page86_i19
#ISCELL
  mstr_symbols gnd *
  page86_i2
#ISCELL
  mstr_standard tap *
  page86_i20
#ISCELL
  mstr_standard tap *
  page86_i21
#ISCELL
  mstr_standard tap *
  page86_i22
#ISCELL
  mstr_standard tap *
  page86_i23
#ISCELL
  mstr_standard tap *
  page86_i24
#ISCELL
  mstr_standard tap *
  page86_i25
#ISCELL
  mstr_standard tap *
  page86_i26
#ISCELL
  mstr_standard offpage *
  page86_i27
#ISCELL
  mstr_standard offpage *
  page86_i28
#ISCELL
  mstr_standard offpage *
  page86_i29
#ISCELL
  mstr_standard offpage *
  page86_i30
#ISCELL
  mstr_standard offpage *
  page86_i31
#ISCELL
  mstr_standard offpage *
  page86_i32
#ISCELL
  mstr_standard offpage *
  page86_i33
#ISCELL
  mstr_standard tap *
  page86_i34
#ISCELL
  mstr_standard tap *
  page86_i35
#ISCELL
  mstr_standard tap *
  page86_i36
#ISCELL
  mstr_standard tap *
  page86_i37
#ISCELL
  mstr_standard tap *
  page86_i38
#ISCELL
  mstr_standard tap *
  page86_i39
#ISCELL
  mstr_standard offpage *
  page86_i4
#ISCELL
  mstr_standard tap *
  page86_i40
#ISCELL
  mstr_standard tap *
  page86_i41
#ISCELL
  mstr_standard tap *
  page86_i42
#ISCELL
  mstr_standard tap *
  page86_i43
#ISCELL
  mstr_standard tap *
  page86_i44
#ISCELL
  mstr_standard tap *
  page86_i45
#ISCELL
  mstr_standard tap *
  page86_i46
#ISCELL
  mstr_standard tap *
  page86_i47
#ISCELL
  mstr_standard tap *
  page86_i48
#ISCELL
  mstr_standard tap *
  page86_i49
#ISCELL
  mstr_symbols pvpp_klm *
  page86_i5
#ISCELL
  mstr_standard tap *
  page86_i50
#ISCELL
  mstr_standard tap *
  page86_i51
#ISCELL
  mstr_standard tap *
  page86_i52
#ISCELL
  mstr_standard tap *
  page86_i53
#ISCELL
  mstr_standard tap *
  page86_i54
#CELL
  mstr_sconn sconn288_h44441003 *
  page86_i55
#ISCELL
  mstr_standard tap *
  page86_i56
#ISCELL
  mstr_standard tap *
  page86_i57
#ISCELL
  mstr_standard tap *
  page86_i58
#ISCELL
  mstr_standard tap *
  page86_i59
#ISCELL
  mstr_standard offpage *
  page86_i6
#ISCELL
  mstr_standard tap *
  page86_i60
#ISCELL
  mstr_standard tap *
  page86_i61
#ISCELL
  mstr_standard tap *
  page86_i62
#ISCELL
  mstr_standard tap *
  page86_i63
#ISCELL
  mstr_standard tap *
  page86_i64
#ISCELL
  mstr_standard tap *
  page86_i65
#ISCELL
  mstr_standard tap *
  page86_i66
#ISCELL
  mstr_standard tap *
  page86_i67
#ISCELL
  mstr_standard tap *
  page86_i68
#ISCELL
  mstr_standard tap *
  page86_i69
#ISCELL
  mstr_standard offpage *
  page86_i7
#ISCELL
  mstr_standard tap *
  page86_i70
#ISCELL
  mstr_standard tap *
  page86_i71
#ISCELL
  mstr_standard tap *
  page86_i72
#ISCELL
  mstr_standard tap *
  page86_i73
#ISCELL
  mstr_standard tap *
  page86_i74
#ISCELL
  mstr_standard tap *
  page86_i75
#ISCELL
  mstr_standard tap *
  page86_i76
#ISCELL
  mstr_symbols pvddq_klm *
  page86_i77
#ISCELL
  mstr_symbols pvtt_klm *
  page86_i78
#ISCELL
  mstr_standard tap *
  page86_i79
#ISCELL
  mstr_standard offpage *
  page86_i8
#ISCELL
  mstr_standard tap *
  page86_i80
#ISCELL
  mstr_standard tap *
  page86_i81
#ISCELL
  mstr_standard tap *
  page86_i82
#ISCELL
  mstr_standard tap *
  page86_i83
#ISCELL
  mstr_standard tap *
  page86_i84
#ISCELL
  mstr_standard tap *
  page86_i85
#ISCELL
  mstr_standard tap *
  page86_i86
#ISCELL
  mstr_standard tap *
  page86_i87
#ISCELL
  mstr_standard tap *
  page86_i88
#ISCELL
  mstr_standard tap *
  page86_i89
#ISCELL
  mstr_standard offpage *
  page86_i9
#ISCELL
  mstr_standard tap *
  page86_i90
#ISCELL
  mstr_standard tap *
  page86_i91
#ISCELL
  mstr_standard tap *
  page86_i92
#ISCELL
  mstr_standard tap *
  page86_i93
#ISCELL
  mstr_standard tap *
  page86_i94
#ISCELL
  mstr_standard tap *
  page86_i95
#ISCELL
  mstr_standard tap *
  page86_i96
#ISCELL
  mstr_standard tap *
  page86_i97
#ISCELL
  mstr_standard tap *
  page86_i98
#ISCELL
  mstr_symbols pvpp_klm *
  page86_i99
#ISCELL
  mstr_symbols bom_note *
  *
#ISCELL
  mstr_symbols intel_corp_bpage *
  *
#ISCELL
  mstr_standard offpage *
  page87_i1
#ISCELL
  mstr_standard tap *
  page87_i100
#ISCELL
  mstr_standard tap *
  page87_i101
#ISCELL
  mstr_standard tap *
  page87_i102
#ISCELL
  mstr_standard tap *
  page87_i103
#ISCELL
  mstr_standard tap *
  page87_i104
#ISCELL
  mstr_standard tap *
  page87_i105
#ISCELL
  mstr_standard tap *
  page87_i106
#ISCELL
  mstr_standard tap *
  page87_i107
#ISCELL
  mstr_standard tap *
  page87_i108
#ISCELL
  mstr_standard tap *
  page87_i109
#ISCELL
  mstr_symbols pvddq_klm *
  page87_i11
#ISCELL
  mstr_standard tap *
  page87_i110
#ISCELL
  mstr_standard tap *
  page87_i112
#ISCELL
  mstr_standard tap *
  page87_i113
#ISCELL
  mstr_standard tap *
  page87_i114
#ISCELL
  mstr_standard tap *
  page87_i115
#ISCELL
  mstr_standard tap *
  page87_i116
#ISCELL
  mstr_standard tap *
  page87_i117
#ISCELL
  mstr_standard tap *
  page87_i118
#ISCELL
  mstr_standard tap *
  page87_i119
#ISCELL
  mstr_standard tap *
  page87_i12
#ISCELL
  mstr_standard tap *
  page87_i120
#ISCELL
  mstr_standard tap *
  page87_i121
#ISCELL
  mstr_standard tap *
  page87_i122
#ISCELL
  mstr_standard tap *
  page87_i123
#ISCELL
  mstr_standard tap *
  page87_i124
#ISCELL
  mstr_standard tap *
  page87_i125
#ISCELL
  mstr_standard tap *
  page87_i126
#ISCELL
  mstr_standard tap *
  page87_i127
#ISCELL
  mstr_standard tap *
  page87_i128
#ISCELL
  mstr_standard tap *
  page87_i129
#ISCELL
  mstr_standard tap *
  page87_i13
#ISCELL
  mstr_standard tap *
  page87_i130
#ISCELL
  mstr_standard offpage *
  page87_i131
#ISCELL
  mstr_standard offpage *
  page87_i132
#ISCELL
  mstr_standard tap *
  page87_i133
#ISCELL
  mstr_standard tap *
  page87_i134
#ISCELL
  mstr_standard tap *
  page87_i135
#ISCELL
  mstr_standard offpage *
  page87_i136
#ISCELL
  mstr_standard offpage *
  page87_i137
#ISCELL
  mstr_standard tap *
  page87_i138
#ISCELL
  mstr_standard tap *
  page87_i139
#ISCELL
  mstr_standard tap *
  page87_i14
#ISCELL
  mstr_standard tap *
  page87_i140
#ISCELL
  mstr_standard tap *
  page87_i141
#ISCELL
  mstr_standard tap *
  page87_i142
#ISCELL
  mstr_standard tap *
  page87_i143
#ISCELL
  mstr_standard tap *
  page87_i144
#ISCELL
  mstr_standard tap *
  page87_i145
#ISCELL
  mstr_standard offpage *
  page87_i146
#ISCELL
  mstr_standard offpage *
  page87_i147
#ISCELL
  mstr_standard offpage *
  page87_i148
#ISCELL
  mstr_standard offpage *
  page87_i149
#ISCELL
  mstr_standard tap *
  page87_i15
#ISCELL
  mstr_standard offpage *
  page87_i150
#ISCELL
  mstr_standard tap *
  page87_i152
#ISCELL
  mstr_standard tap *
  page87_i153
#ISCELL
  mstr_standard tap *
  page87_i154
#ISCELL
  mstr_standard tap *
  page87_i155
#ISCELL
  mstr_standard offpage *
  page87_i156
#ISCELL
  mstr_standard offpage *
  page87_i157
#ISCELL
  mstr_standard tap *
  page87_i158
#ISCELL
  mstr_standard tap *
  page87_i159
#ISCELL
  mstr_standard tap *
  page87_i16
#ISCELL
  mstr_standard tap *
  page87_i160
#ISCELL
  mstr_standard tap *
  page87_i161
#ISCELL
  mstr_standard offpage *
  page87_i162
#ISCELL
  mstr_standard tap *
  page87_i163
#ISCELL
  mstr_standard tap *
  page87_i164
#ISCELL
  mstr_standard tap *
  page87_i165
#ISCELL
  mstr_standard tap *
  page87_i166
#ISCELL
  mstr_standard offpage *
  page87_i167
#ISCELL
  mstr_standard offpage *
  page87_i168
#CELL
  mstr_sconn sconn288_h44441004 *
  page87_i169
#ISCELL
  mstr_standard tap *
  page87_i17
#ISCELL
  mstr_symbols gnd *
  page87_i170
#ISCELL
  mstr_standard offpage *
  page87_i171
#ISCELL
  mstr_standard offpage *
  page87_i172
#ISCELL
  mstr_standard offpage *
  page87_i173
#ISCELL
  mstr_standard offpage *
  page87_i174
#ISCELL
  mstr_symbols gnd *
  page87_i176
#ISCELL
  mstr_symbols gnd *
  page87_i177
#CELL
  dev_discrete cap_a *
  page87_i178
#ISCELL
  mstr_symbols pvpp_klm *
  page87_i179
#ISCELL
  mstr_standard tap *
  page87_i18
#ISCELL
  mstr_symbols pvpp_klm *
  page87_i180
#ISCELL
  mstr_standard offpage *
  page87_i181
#CELL
  mstr_sconn sconn288_h44441004 *
  page87_i185
#CELL
  mstr_sconn sconn288_h44441004 *
  page87_i186
#CELL
  mstr_sconn sconn288_h44441004 *
  page87_i187
#ISCELL
  mstr_symbols p12v_nvdimm_klm *
  page87_i188
#ISCELL
  mstr_standard tap *
  page87_i19
#ISCELL
  mstr_standard offpage *
  page87_i2
#ISCELL
  mstr_standard tap *
  page87_i20
#ISCELL
  mstr_standard tap *
  page87_i21
#ISCELL
  mstr_standard tap *
  page87_i22
#ISCELL
  mstr_standard tap *
  page87_i23
#ISCELL
  mstr_symbols gnd *
  page87_i26
#ISCELL
  mstr_standard tap *
  page87_i27
#ISCELL
  mstr_standard tap *
  page87_i28
#ISCELL
  mstr_standard tap *
  page87_i29
#ISCELL
  mstr_standard tap *
  page87_i3
#ISCELL
  mstr_standard tap *
  page87_i30
#ISCELL
  mstr_standard tap *
  page87_i31
#ISCELL
  mstr_standard tap *
  page87_i32
#ISCELL
  mstr_standard tap *
  page87_i33
#ISCELL
  mstr_standard offpage *
  page87_i34
#ISCELL
  mstr_standard tap *
  page87_i35
#ISCELL
  mstr_standard tap *
  page87_i36
#ISCELL
  mstr_standard tap *
  page87_i37
#ISCELL
  mstr_standard tap *
  page87_i38
#ISCELL
  mstr_standard tap *
  page87_i39
#ISCELL
  mstr_standard tap *
  page87_i4
#ISCELL
  mstr_standard tap *
  page87_i40
#ISCELL
  mstr_standard tap *
  page87_i41
#ISCELL
  mstr_standard tap *
  page87_i42
#ISCELL
  mstr_standard tap *
  page87_i43
#ISCELL
  mstr_standard tap *
  page87_i44
#ISCELL
  mstr_standard tap *
  page87_i45
#ISCELL
  mstr_standard tap *
  page87_i46
#ISCELL
  mstr_standard tap *
  page87_i47
#ISCELL
  mstr_standard tap *
  page87_i48
#ISCELL
  mstr_standard tap *
  page87_i49
#ISCELL
  mstr_standard tap *
  page87_i5
#ISCELL
  mstr_standard tap *
  page87_i50
#ISCELL
  mstr_standard tap *
  page87_i51
#ISCELL
  mstr_standard tap *
  page87_i52
#ISCELL
  mstr_standard tap *
  page87_i53
#ISCELL
  mstr_standard tap *
  page87_i54
#ISCELL
  mstr_standard tap *
  page87_i55
#ISCELL
  mstr_standard tap *
  page87_i56
#ISCELL
  mstr_standard tap *
  page87_i57
#ISCELL
  mstr_standard tap *
  page87_i58
#ISCELL
  mstr_standard tap *
  page87_i59
#ISCELL
  mstr_standard tap *
  page87_i6
#ISCELL
  mstr_standard tap *
  page87_i60
#ISCELL
  mstr_standard tap *
  page87_i61
#ISCELL
  mstr_standard tap *
  page87_i62
#ISCELL
  mstr_standard tap *
  page87_i63
#ISCELL
  mstr_standard tap *
  page87_i64
#ISCELL
  mstr_standard tap *
  page87_i65
#ISCELL
  mstr_standard tap *
  page87_i66
#ISCELL
  mstr_standard tap *
  page87_i67
#ISCELL
  mstr_standard tap *
  page87_i68
#ISCELL
  mstr_standard tap *
  page87_i69
#ISCELL
  mstr_standard tap *
  page87_i7
#ISCELL
  mstr_standard tap *
  page87_i70
#ISCELL
  mstr_standard tap *
  page87_i71
#ISCELL
  mstr_standard tap *
  page87_i72
#ISCELL
  mstr_standard tap *
  page87_i73
#ISCELL
  mstr_standard tap *
  page87_i74
#ISCELL
  mstr_standard tap *
  page87_i75
#ISCELL
  mstr_standard tap *
  page87_i76
#ISCELL
  mstr_standard tap *
  page87_i77
#ISCELL
  mstr_standard tap *
  page87_i78
#ISCELL
  mstr_standard tap *
  page87_i79
#ISCELL
  mstr_standard tap *
  page87_i8
#ISCELL
  mstr_standard tap *
  page87_i80
#ISCELL
  mstr_standard tap *
  page87_i81
#ISCELL
  mstr_standard tap *
  page87_i82
#ISCELL
  mstr_standard tap *
  page87_i83
#ISCELL
  mstr_standard tap *
  page87_i84
#ISCELL
  mstr_standard tap *
  page87_i85
#ISCELL
  mstr_standard tap *
  page87_i86
#ISCELL
  mstr_standard tap *
  page87_i88
#ISCELL
  mstr_standard tap *
  page87_i89
#ISCELL
  mstr_symbols pvtt_klm *
  page87_i9
#ISCELL
  mstr_standard tap *
  page87_i90
#ISCELL
  mstr_standard tap *
  page87_i91
#ISCELL
  mstr_standard tap *
  page87_i92
#ISCELL
  mstr_standard tap *
  page87_i93
#ISCELL
  mstr_standard tap *
  page87_i94
#ISCELL
  mstr_standard tap *
  page87_i95
#ISCELL
  mstr_standard tap *
  page87_i96
#ISCELL
  mstr_standard tap *
  page87_i97
#ISCELL
  mstr_standard tap *
  page87_i98
#ISCELL
  mstr_standard tap *
  page87_i99
#ISCELL
  mstr_symbols bom_note *
  *
#ISCELL
  mstr_symbols intel_corp_bpage *
  *
#ISCELL
  mstr_standard offpage *
  page88_i1
#ISCELL
  mstr_standard tap *
  page88_i100
#ISCELL
  mstr_standard tap *
  page88_i101
#ISCELL
  mstr_standard tap *
  page88_i102
#ISCELL
  mstr_standard tap *
  page88_i103
#ISCELL
  mstr_standard tap *
  page88_i104
#ISCELL
  mstr_standard tap *
  page88_i105
#ISCELL
  mstr_standard tap *
  page88_i106
#ISCELL
  mstr_standard tap *
  page88_i107
#ISCELL
  mstr_standard tap *
  page88_i108
#ISCELL
  mstr_standard tap *
  page88_i109
#ISCELL
  mstr_symbols pvddq_klm *
  page88_i11
#ISCELL
  mstr_standard tap *
  page88_i110
#CELL
  mstr_sconn sconn288_h44441003 *
  page88_i111
#ISCELL
  mstr_standard tap *
  page88_i112
#ISCELL
  mstr_standard tap *
  page88_i113
#ISCELL
  mstr_standard tap *
  page88_i114
#ISCELL
  mstr_standard tap *
  page88_i115
#ISCELL
  mstr_standard tap *
  page88_i116
#ISCELL
  mstr_standard tap *
  page88_i117
#ISCELL
  mstr_standard tap *
  page88_i118
#ISCELL
  mstr_standard tap *
  page88_i119
#ISCELL
  mstr_standard tap *
  page88_i12
#ISCELL
  mstr_standard tap *
  page88_i120
#ISCELL
  mstr_standard tap *
  page88_i121
#ISCELL
  mstr_standard tap *
  page88_i122
#ISCELL
  mstr_standard tap *
  page88_i123
#ISCELL
  mstr_standard tap *
  page88_i124
#ISCELL
  mstr_standard tap *
  page88_i125
#ISCELL
  mstr_standard tap *
  page88_i126
#ISCELL
  mstr_standard tap *
  page88_i127
#ISCELL
  mstr_standard tap *
  page88_i128
#ISCELL
  mstr_standard tap *
  page88_i129
#ISCELL
  mstr_standard tap *
  page88_i13
#ISCELL
  mstr_standard tap *
  page88_i130
#ISCELL
  mstr_standard offpage *
  page88_i131
#ISCELL
  mstr_standard offpage *
  page88_i132
#ISCELL
  mstr_standard tap *
  page88_i133
#ISCELL
  mstr_standard tap *
  page88_i134
#ISCELL
  mstr_standard tap *
  page88_i135
#ISCELL
  mstr_standard offpage *
  page88_i136
#ISCELL
  mstr_standard offpage *
  page88_i137
#ISCELL
  mstr_standard tap *
  page88_i138
#ISCELL
  mstr_standard tap *
  page88_i139
#ISCELL
  mstr_standard tap *
  page88_i14
#ISCELL
  mstr_standard tap *
  page88_i140
#ISCELL
  mstr_standard tap *
  page88_i141
#ISCELL
  mstr_standard tap *
  page88_i142
#ISCELL
  mstr_standard tap *
  page88_i143
#ISCELL
  mstr_standard tap *
  page88_i144
#ISCELL
  mstr_standard tap *
  page88_i145
#ISCELL
  mstr_standard offpage *
  page88_i146
#ISCELL
  mstr_standard offpage *
  page88_i147
#ISCELL
  mstr_standard offpage *
  page88_i148
#ISCELL
  mstr_standard offpage *
  page88_i149
#ISCELL
  mstr_standard tap *
  page88_i15
#ISCELL
  mstr_standard offpage *
  page88_i150
#ISCELL
  mstr_standard tap *
  page88_i152
#ISCELL
  mstr_standard tap *
  page88_i153
#ISCELL
  mstr_standard offpage *
  page88_i155
#ISCELL
  mstr_standard offpage *
  page88_i156
#ISCELL
  mstr_standard offpage *
  page88_i157
#ISCELL
  mstr_standard offpage *
  page88_i158
#ISCELL
  mstr_standard offpage *
  page88_i159
#ISCELL
  mstr_standard tap *
  page88_i16
#ISCELL
  mstr_standard tap *
  page88_i160
#ISCELL
  mstr_standard tap *
  page88_i161
#ISCELL
  mstr_standard tap *
  page88_i162
#ISCELL
  mstr_standard tap *
  page88_i163
#ISCELL
  mstr_standard tap *
  page88_i164
#ISCELL
  mstr_standard tap *
  page88_i165
#ISCELL
  mstr_standard tap *
  page88_i166
#ISCELL
  mstr_standard tap *
  page88_i167
#CELL
  mstr_sconn sconn288_h44441003 *
  page88_i168
#ISCELL
  mstr_symbols gnd *
  page88_i169
#ISCELL
  mstr_standard tap *
  page88_i17
#ISCELL
  mstr_standard offpage *
  page88_i170
#ISCELL
  mstr_standard offpage *
  page88_i171
#ISCELL
  mstr_standard offpage *
  page88_i172
#ISCELL
  mstr_standard offpage *
  page88_i173
#ISCELL
  mstr_symbols gnd *
  page88_i175
#ISCELL
  mstr_symbols gnd *
  page88_i176
#CELL
  dev_discrete cap_a *
  page88_i177
#ISCELL
  mstr_symbols pvpp_klm *
  page88_i178
#ISCELL
  mstr_symbols pvpp_klm *
  page88_i179
#ISCELL
  mstr_standard tap *
  page88_i18
#ISCELL
  mstr_standard offpage *
  page88_i180
#ISCELL
  mstr_standard tap *
  page88_i184
#ISCELL
  mstr_standard tap *
  page88_i185
#ISCELL
  mstr_symbols p12v_nvdimm_klm *
  page88_i186
#ISCELL
  mstr_standard tap *
  page88_i19
#ISCELL
  mstr_standard offpage *
  page88_i2
#ISCELL
  mstr_standard tap *
  page88_i20
#ISCELL
  mstr_standard tap *
  page88_i21
#ISCELL
  mstr_standard tap *
  page88_i22
#ISCELL
  mstr_standard tap *
  page88_i23
#CELL
  mstr_sconn sconn288_h44441003 *
  page88_i25
#ISCELL
  mstr_symbols gnd *
  page88_i26
#ISCELL
  mstr_standard tap *
  page88_i27
#ISCELL
  mstr_standard tap *
  page88_i28
#ISCELL
  mstr_standard tap *
  page88_i29
#ISCELL
  mstr_standard tap *
  page88_i3
#ISCELL
  mstr_standard tap *
  page88_i30
#ISCELL
  mstr_standard tap *
  page88_i31
#ISCELL
  mstr_standard tap *
  page88_i32
#ISCELL
  mstr_standard tap *
  page88_i33
#ISCELL
  mstr_standard offpage *
  page88_i34
#ISCELL
  mstr_standard tap *
  page88_i35
#ISCELL
  mstr_standard tap *
  page88_i36
#ISCELL
  mstr_standard tap *
  page88_i37
#ISCELL
  mstr_standard tap *
  page88_i38
#ISCELL
  mstr_standard tap *
  page88_i39
#ISCELL
  mstr_standard tap *
  page88_i4
#ISCELL
  mstr_standard tap *
  page88_i40
#ISCELL
  mstr_standard tap *
  page88_i41
#ISCELL
  mstr_standard tap *
  page88_i42
#ISCELL
  mstr_standard tap *
  page88_i43
#ISCELL
  mstr_standard tap *
  page88_i44
#ISCELL
  mstr_standard tap *
  page88_i45
#ISCELL
  mstr_standard tap *
  page88_i46
#ISCELL
  mstr_standard tap *
  page88_i47
#ISCELL
  mstr_standard tap *
  page88_i48
#ISCELL
  mstr_standard tap *
  page88_i49
#ISCELL
  mstr_standard tap *
  page88_i5
#ISCELL
  mstr_standard tap *
  page88_i50
#ISCELL
  mstr_standard tap *
  page88_i51
#ISCELL
  mstr_standard tap *
  page88_i52
#ISCELL
  mstr_standard tap *
  page88_i53
#ISCELL
  mstr_standard tap *
  page88_i54
#ISCELL
  mstr_standard tap *
  page88_i55
#ISCELL
  mstr_standard tap *
  page88_i56
#ISCELL
  mstr_standard tap *
  page88_i57
#ISCELL
  mstr_standard tap *
  page88_i58
#ISCELL
  mstr_standard tap *
  page88_i59
#ISCELL
  mstr_standard tap *
  page88_i6
#ISCELL
  mstr_standard tap *
  page88_i60
#ISCELL
  mstr_standard tap *
  page88_i61
#ISCELL
  mstr_standard tap *
  page88_i62
#ISCELL
  mstr_standard tap *
  page88_i63
#ISCELL
  mstr_standard tap *
  page88_i64
#ISCELL
  mstr_standard tap *
  page88_i65
#ISCELL
  mstr_standard tap *
  page88_i66
#ISCELL
  mstr_standard tap *
  page88_i67
#ISCELL
  mstr_standard tap *
  page88_i68
#ISCELL
  mstr_standard tap *
  page88_i69
#ISCELL
  mstr_standard tap *
  page88_i7
#ISCELL
  mstr_standard tap *
  page88_i70
#ISCELL
  mstr_standard tap *
  page88_i71
#ISCELL
  mstr_standard tap *
  page88_i72
#ISCELL
  mstr_standard tap *
  page88_i73
#ISCELL
  mstr_standard tap *
  page88_i74
#ISCELL
  mstr_standard tap *
  page88_i75
#ISCELL
  mstr_standard tap *
  page88_i76
#ISCELL
  mstr_standard tap *
  page88_i77
#ISCELL
  mstr_standard tap *
  page88_i78
#ISCELL
  mstr_standard tap *
  page88_i79
#ISCELL
  mstr_standard tap *
  page88_i8
#ISCELL
  mstr_standard tap *
  page88_i80
#ISCELL
  mstr_standard tap *
  page88_i81
#ISCELL
  mstr_standard tap *
  page88_i82
#ISCELL
  mstr_standard tap *
  page88_i83
#ISCELL
  mstr_standard tap *
  page88_i84
#ISCELL
  mstr_standard tap *
  page88_i85
#ISCELL
  mstr_standard tap *
  page88_i86
#CELL
  mstr_sconn sconn288_h44441003 *
  page88_i87
#ISCELL
  mstr_standard tap *
  page88_i88
#ISCELL
  mstr_standard tap *
  page88_i89
#ISCELL
  mstr_symbols pvtt_klm *
  page88_i9
#ISCELL
  mstr_standard tap *
  page88_i90
#ISCELL
  mstr_standard tap *
  page88_i91
#ISCELL
  mstr_standard tap *
  page88_i92
#ISCELL
  mstr_standard tap *
  page88_i93
#ISCELL
  mstr_standard tap *
  page88_i94
#ISCELL
  mstr_standard tap *
  page88_i95
#ISCELL
  mstr_standard tap *
  page88_i96
#ISCELL
  mstr_standard tap *
  page88_i97
#ISCELL
  mstr_standard tap *
  page88_i98
#ISCELL
  mstr_standard tap *
  page88_i99
#ISCELL
  mstr_misc dns *
  *
#ISCELL
  mstr_symbols intel_corp_bpage *
  *
#CELL
  mstr_discrete res *
  page89_i1
#ISCELL
  mstr_standard offpage *
  page89_i10
#ISCELL
  mstr_standard offpage *
  page89_i11
#ISCELL
  mstr_standard offpage *
  page89_i12
#ISCELL
  mstr_standard offpage *
  page89_i13
#ISCELL
  mstr_standard offpage *
  page89_i14
#ISCELL
  mstr_symbols gnd *
  page89_i16
#ISCELL
  mstr_symbols pvpp_abc *
  page89_i17
#CELL
  mstr_discrete res *
  page89_i2
#ISCELL
  mstr_standard offpage *
  page89_i22
#CELL
  mstr_discrete res *
  page89_i23
#CELL
  mstr_discrete res *
  page89_i26
#CELL
  mstr_discrete res *
  page89_i27
#ISCELL
  mstr_symbols p3v3_stby *
  page89_i28
#ISCELL
  mstr_symbols p3v3_stby *
  page89_i29
#CELL
  mstr_discrete res *
  page89_i3
#ISCELL
  mstr_symbols gnd *
  page89_i30
#ISCELL
  mstr_symbols gnd *
  page89_i31
#ISCELL
  mstr_standard offpage *
  page89_i33
#CELL
  mstr_discrete res *
  page89_i34
#CELL
  mstr_discrete npn_dual *
  page89_i35
#ISCELL
  mstr_symbols gnd *
  page89_i39
#CELL
  mstr_discrete res *
  page89_i4
#CELL
  mstr_discrete res *
  page89_i40
#ISCELL
  mstr_symbols pvpp_abc *
  page89_i41
#CELL
  mstr_discrete res *
  page89_i45
#CELL
  mstr_discrete npn_dual *
  page89_i46
#ISCELL
  mstr_symbols gnd *
  page89_i47
#ISCELL
  mstr_symbols gnd *
  page89_i48
#CELL
  mstr_discrete res *
  page89_i49
#CELL
  mstr_discrete res *
  page89_i5
#ISCELL
  mstr_symbols p3v3_stby *
  page89_i50
#CELL
  mstr_discrete npn_dual *
  page89_i51
#CELL
  mstr_discrete npn_dual *
  page89_i52
#CELL
  mstr_discrete npn *
  page89_i53
#CELL
  mstr_discrete res *
  page89_i54
#CELL
  mstr_discrete npn *
  page89_i55
#CELL
  mstr_discrete res *
  page89_i56
#CELL
  mstr_discrete res *
  page89_i6
#CELL
  mstr_discrete res *
  page89_i7
#ISCELL
  mstr_standard offpage *
  page89_i9
#ISCELL
  mstr_misc dns *
  *
#ISCELL
  mstr_symbols cad_note *
  *
#ISCELL
  mstr_symbols design_note *
  *
#ISCELL
  mstr_symbols intel_corp_bpage *
  *
#ISCELL
  mstr_standard offpage *
  page90_i1
#ISCELL
  mstr_standard offpage *
  page90_i10
#CELL
  mstr_discrete res *
  page90_i100
#CELL
  mstr_discrete res *
  page90_i101
#CELL
  mstr_discrete res *
  page90_i102
#ISCELL
  mstr_standard offpage *
  page90_i14
#ISCELL
  mstr_standard offpage *
  page90_i16
#CELL
  mstr_discrete res *
  page90_i17
#ISCELL
  mstr_symbols gnd *
  page90_i18
#ISCELL
  mstr_standard offpage *
  page90_i19
#ISCELL
  mstr_standard offpage *
  page90_i2
#ISCELL
  mstr_standard offpage *
  page90_i20
#ISCELL
  mstr_standard offpage *
  page90_i23
#CELL
  mstr_discrete res *
  page90_i24
#CELL
  mstr_discrete res *
  page90_i25
#CELL
  mstr_discrete res *
  page90_i28
#CELL
  mstr_discrete res *
  page90_i29
#ISCELL
  mstr_symbols pvccio_cpu0 *
  page90_i30
#CELL
  mstr_discrete res *
  page90_i31
#CELL
  mstr_discrete res *
  page90_i33
#ISCELL
  mstr_standard offpage *
  page90_i45
#ISCELL
  mstr_standard offpage *
  page90_i46
#CELL
  mstr_discrete res *
  page90_i48
#CELL
  mstr_discrete res *
  page90_i49
#ISCELL
  mstr_symbols gnd *
  page90_i5
#ISCELL
  mstr_symbols pvccio_cpu0 *
  page90_i51
#CELL
  mstr_discrete res *
  page90_i52
#CELL
  mstr_discrete res *
  page90_i53
#ISCELL
  mstr_standard offpage *
  page90_i54
#ISCELL
  mstr_standard offpage *
  page90_i55
#ISCELL
  mstr_standard offpage *
  page90_i56
#ISCELL
  mstr_standard offpage *
  page90_i57
#CELL
  mstr_discrete res *
  page90_i59
#ISCELL
  mstr_standard offpage *
  page90_i6
#CELL
  mstr_discrete res *
  page90_i60
#ISCELL
  mstr_symbols pvccio_cpu1 *
  page90_i62
#ISCELL
  mstr_symbols pvccio_cpu1 *
  page90_i63
#ISCELL
  mstr_standard offpage *
  page90_i64
#CELL
  mstr_discrete res *
  page90_i66
#CELL
  mstr_discrete res *
  page90_i68
#ISCELL
  mstr_standard offpage *
  page90_i69
#ISCELL
  mstr_standard offpage *
  page90_i7
#ISCELL
  mstr_standard offpage *
  page90_i71
#CELL
  mstr_discrete res *
  page90_i72
#ISCELL
  mstr_standard offpage *
  page90_i73
#CELL
  mstr_discrete res *
  page90_i74
#ISCELL
  mstr_standard offpage *
  page90_i75
#CELL
  mstr_discrete res *
  page90_i76
#ISCELL
  mstr_standard offpage *
  page90_i77
#ISCELL
  mstr_symbols gnd *
  page90_i78
#CELL
  mstr_discrete res *
  page90_i79
#ISCELL
  mstr_standard offpage *
  page90_i8
#CELL
  mstr_discrete res *
  page90_i80
#CELL
  mstr_discrete res *
  page90_i81
#ISCELL
  mstr_standard offpage *
  page90_i82
#ISCELL
  mstr_standard offpage *
  page90_i83
#ISCELL
  mstr_standard offpage *
  page90_i84
#CELL
  mstr_discrete res *
  page90_i85
#CELL
  mstr_discrete res *
  page90_i86
#ISCELL
  mstr_symbols gnd *
  page90_i87
#CELL
  mstr_discrete res *
  page90_i88
#ISCELL
  mstr_standard offpage *
  page90_i89
#ISCELL
  mstr_standard offpage *
  page90_i9
#ISCELL
  mstr_standard offpage *
  page90_i90
#ISCELL
  mstr_standard offpage *
  page90_i91
#ISCELL
  mstr_symbols gnd *
  page90_i92
#ISCELL
  mstr_symbols gnd *
  page90_i93
#CELL
  mstr_discrete res *
  page90_i96
#CELL
  mstr_discrete res *
  page90_i98
#CELL
  mstr_discrete res *
  page90_i99
#ISCELL
  mstr_symbols design_note *
  *
#ISCELL
  mstr_symbols intel_corp_bpage *
  *
#CELL
  mstr_sconn sconn24_h46321001 *
  page91_i1
#ISCELL
  mstr_standard offpage *
  page91_i10
#ISCELL
  mstr_standard offpage *
  page91_i11
#ISCELL
  mstr_standard offpage *
  page91_i12
#CELL
  mstr_discrete res *
  page91_i14
#CELL
  mstr_discrete res *
  page91_i16
#CELL
  mstr_discrete res *
  page91_i17
#CELL
  mstr_discrete res *
  page91_i18
#ISCELL
  mstr_symbols gnd *
  page91_i2
#CELL
  mstr_discrete res *
  page91_i20
#CELL
  mstr_discrete res *
  page91_i21
#CELL
  mstr_discrete res *
  page91_i22
#CELL
  mstr_discrete res *
  page91_i24
#ISCELL
  mstr_standard offpage *
  page91_i25
#ISCELL
  mstr_standard offpage *
  page91_i26
#ISCELL
  mstr_standard offpage *
  page91_i27
#ISCELL
  mstr_standard offpage *
  page91_i28
#ISCELL
  mstr_standard offpage *
  page91_i29
#ISCELL
  mstr_standard offpage *
  page91_i3
#ISCELL
  mstr_symbols pvpp_abc *
  page91_i30
#ISCELL
  mstr_symbols pvpp_abc *
  page91_i31
#ISCELL
  mstr_symbols pvpp_abc *
  page91_i32
#ISCELL
  mstr_symbols p3v3 *
  page91_i33
#CELL
  mstr_discrete res *
  page91_i34
#CELL
  mstr_discrete res *
  page91_i35
#CELL
  mstr_discrete res *
  page91_i36
#CELL
  mstr_discrete res *
  page91_i37
#ISCELL
  mstr_symbols gnd *
  page91_i38
#ISCELL
  mstr_standard offpage *
  page91_i4
#ISCELL
  mstr_standard offpage *
  page91_i5
#ISCELL
  mstr_standard offpage *
  page91_i6
#ISCELL
  mstr_standard offpage *
  page91_i7
#ISCELL
  mstr_standard offpage *
  page91_i8
#ISCELL
  mstr_standard offpage *
  page91_i9
#ISCELL
  mstr_misc dns *
  *
#ISCELL
  mstr_symbols cad_note *
  *
#ISCELL
  mstr_symbols design_note *
  *
#ISCELL
  mstr_symbols intel_corp_bpage *
  *
#CELL
  mstr_digital gtl2014 *
  page92_i1
#ISCELL
  mstr_symbols pvccio_cpu1 *
  page92_i10
#CELL
  mstr_discrete res *
  page92_i100
#CELL
  mstr_discrete res *
  page92_i101
#ISCELL
  mstr_standard offpage *
  page92_i102
#ISCELL
  mstr_standard offpage *
  page92_i103
#ISCELL
  mstr_symbols p3v3 *
  page92_i104
#ISCELL
  mstr_symbols p3v3 *
  page92_i105
#CELL
  mstr_discrete res *
  page92_i106
#ISCELL
  mstr_symbols pvccio_cpu0 *
  page92_i107
#CELL
  mstr_discrete res *
  page92_i108
#ISCELL
  mstr_symbols pvccio_cpu0 *
  page92_i109
#CELL
  w_hdl 374r2f-1-gp *
  page92_i110
#CELL
  w_hdl 374r2f-1-gp *
  page92_i111
#CELL
  mstr_discrete res *
  page92_i12
#CELL
  mstr_discrete res *
  page92_i13
#CELL
  mstr_discrete res *
  page92_i14
#ISCELL
  mstr_standard offpage *
  page92_i16
#ISCELL
  mstr_standard offpage *
  page92_i18
#CELL
  mstr_discrete res *
  page92_i19
#ISCELL
  mstr_symbols gnd *
  page92_i2
#ISCELL
  mstr_standard offpage *
  page92_i20
#ISCELL
  mstr_standard offpage *
  page92_i22
#CELL
  mstr_discrete res *
  page92_i24
#ISCELL
  mstr_standard offpage *
  page92_i27
#CELL
  mstr_discrete res *
  page92_i29
#ISCELL
  mstr_standard offpage *
  page92_i3
#CELL
  mstr_discrete res *
  page92_i30
#CELL
  mstr_digital gtl2014 *
  page92_i32
#ISCELL
  mstr_symbols gnd *
  page92_i33
#ISCELL
  mstr_standard offpage *
  page92_i36
#CELL
  dev_discrete cap_a *
  page92_i37
#CELL
  mstr_discrete res *
  page92_i38
#ISCELL
  mstr_symbols gnd *
  page92_i41
#ISCELL
  mstr_symbols p3v3 *
  page92_i42
#CELL
  mstr_discrete res *
  page92_i46
#ISCELL
  mstr_symbols gnd *
  page92_i47
#CELL
  mstr_discrete res *
  page92_i48
#ISCELL
  mstr_symbols gnd *
  page92_i49
#ISCELL
  mstr_standard offpage *
  page92_i5
#CELL
  dev_discrete cap_a *
  page92_i52
#ISCELL
  mstr_symbols gnd *
  page92_i53
#CELL
  mstr_discrete res *
  page92_i54
#ISCELL
  mstr_symbols p3v3 *
  page92_i58
#ISCELL
  mstr_standard offpage *
  page92_i59
#ISCELL
  mstr_standard offpage *
  page92_i60
#CELL
  mstr_discrete res *
  page92_i61
#ISCELL
  mstr_standard offpage *
  page92_i62
#ISCELL
  mstr_standard offpage *
  page92_i63
#CELL
  mstr_discrete res *
  page92_i64
#CELL
  mstr_discrete res *
  page92_i65
#ISCELL
  mstr_symbols pvccio_cpu0 *
  page92_i66
#CELL
  mstr_discrete res *
  page92_i67
#CELL
  mstr_discrete res *
  page92_i68
#ISCELL
  mstr_standard offpage *
  page92_i69
#CELL
  mstr_discrete res *
  page92_i70
#CELL
  mstr_discrete res *
  page92_i75
#ISCELL
  mstr_symbols gnd *
  page92_i76
#CELL
  mstr_discrete cap *
  page92_i79
#ISCELL
  mstr_symbols gnd *
  page92_i80
#ISCELL
  mstr_symbols pvccio_cpu0 *
  page92_i82
#CELL
  mstr_discrete cap *
  page92_i84
#ISCELL
  mstr_symbols gnd *
  page92_i85
#ISCELL
  mstr_standard offpage *
  page92_i88
#ISCELL
  mstr_standard offpage *
  page92_i89
#CELL
  mstr_discrete res *
  page92_i9
#ISCELL
  mstr_standard offpage *
  page92_i90
#ISCELL
  mstr_standard offpage *
  page92_i91
#CELL
  mstr_discrete res *
  page92_i92
#CELL
  mstr_discrete res *
  page92_i93
#CELL
  mstr_discrete res *
  page92_i94
#ISCELL
  mstr_symbols pvccio_cpu0 *
  page92_i95
#CELL
  mstr_discrete res *
  page92_i96
#CELL
  mstr_discrete res *
  page92_i97
#CELL
  mstr_discrete res *
  page92_i98
#ISCELL
  mstr_symbols pvccio_cpu0 *
  page92_i99
#ISCELL
  mstr_misc dns *
  *
#ISCELL
  mstr_symbols cad_note *
  *
#ISCELL
  mstr_symbols design_note *
  *
#ISCELL
  mstr_symbols intel_corp_bpage *
  *
#ISCELL
  mstr_standard offpage *
  page93_i100
#ISCELL
  mstr_standard offpage *
  page93_i101
#CELL
  mstr_discrete res *
  page93_i102
#CELL
  mstr_discrete res *
  page93_i103
#ISCELL
  mstr_symbols pvccio_cpu1 *
  page93_i105
#CELL
  mstr_discrete res *
  page93_i106
#CELL
  mstr_discrete res *
  page93_i107
#CELL
  mstr_discrete res *
  page93_i108
#CELL
  mstr_discrete res *
  page93_i109
#CELL
  mstr_discrete res *
  page93_i110
#CELL
  mstr_discrete res *
  page93_i111
#CELL
  mstr_discrete res *
  page93_i112
#CELL
  mstr_discrete res *
  page93_i113
#CELL
  mstr_discrete res *
  page93_i114
#ISCELL
  mstr_standard offpage *
  page93_i115
#ISCELL
  mstr_standard offpage *
  page93_i116
#ISCELL
  mstr_standard offpage *
  page93_i117
#ISCELL
  mstr_standard offpage *
  page93_i118
#CELL
  mstr_discrete res *
  page93_i119
#ISCELL
  mstr_standard offpage *
  page93_i120
#CELL
  mstr_discrete res *
  page93_i121
#CELL
  mstr_discrete res *
  page93_i122
#CELL
  mstr_discrete res *
  page93_i123
#ISCELL
  mstr_standard offpage *
  page93_i124
#ISCELL
  mstr_standard offpage *
  page93_i125
#ISCELL
  mstr_standard offpage *
  page93_i126
#CELL
  mstr_discrete res *
  page93_i127
#ISCELL
  mstr_symbols gnd *
  page93_i128
#ISCELL
  mstr_standard offpage *
  page93_i129
#CELL
  mstr_discrete res *
  page93_i13
#ISCELL
  mstr_standard offpage *
  page93_i130
#CELL
  mstr_discrete res *
  page93_i131
#ISCELL
  mstr_standard offpage *
  page93_i132
#CELL
  mstr_discrete res *
  page93_i133
#ISCELL
  mstr_standard offpage *
  page93_i134
#CELL
  mstr_discrete res *
  page93_i135
#ISCELL
  mstr_standard offpage *
  page93_i136
#CELL
  mstr_discrete res *
  page93_i137
#ISCELL
  mstr_standard offpage *
  page93_i138
#CELL
  mstr_discrete res *
  page93_i143
#CELL
  mstr_discrete res *
  page93_i144
#ISCELL
  mstr_symbols p3v3 *
  page93_i145
#ISCELL
  mstr_symbols pvccio_cpu0 *
  page93_i146
#CELL
  mstr_discrete res *
  page93_i147
#CELL
  w_hdl 374r2f-1-gp *
  page93_i148
#CELL
  mstr_discrete res *
  page93_i15
#CELL
  mstr_discrete res *
  page93_i16
#ISCELL
  mstr_standard offpage *
  page93_i19
#CELL
  mstr_discrete res *
  page93_i23
#ISCELL
  mstr_symbols gnd *
  page93_i29
#CELL
  mstr_digital gtl2014 *
  page93_i30
#CELL
  mstr_discrete res *
  page93_i39
#ISCELL
  mstr_standard offpage *
  page93_i4
#CELL
  mstr_discrete res *
  page93_i40
#CELL
  mstr_discrete res *
  page93_i42
#ISCELL
  mstr_standard offpage *
  page93_i47
#ISCELL
  mstr_standard offpage *
  page93_i48
#ISCELL
  mstr_standard offpage *
  page93_i5
#ISCELL
  mstr_standard offpage *
  page93_i6
#CELL
  mstr_discrete res *
  page93_i62
#CELL
  mstr_discrete res *
  page93_i63
#ISCELL
  mstr_symbols pvccio_cpu0 *
  page93_i64
#CELL
  mstr_discrete res *
  page93_i67
#CELL
  mstr_discrete res *
  page93_i68
#ISCELL
  mstr_symbols p3v3 *
  page93_i70
#CELL
  dev_discrete cap_a *
  page93_i72
#ISCELL
  mstr_symbols gnd *
  page93_i73
#ISCELL
  mstr_standard offpage *
  page93_i76
#ISCELL
  mstr_standard offpage *
  page93_i77
#ISCELL
  mstr_symbols pvccio_cpu0 *
  page93_i78
#CELL
  mstr_discrete res *
  page93_i79
#ISCELL
  mstr_standard offpage *
  page93_i81
#ISCELL
  mstr_standard offpage *
  page93_i83
#CELL
  mstr_discrete res *
  page93_i87
#CELL
  mstr_discrete res *
  page93_i88
#CELL
  mstr_discrete res *
  page93_i89
#CELL
  mstr_discrete res *
  page93_i93
#CELL
  mstr_discrete res *
  page93_i94
#CELL
  dev_discrete cap_a *
  page93_i95
#CELL
  mstr_discrete res *
  page93_i98
#ISCELL
  mstr_symbols gnd *
  page93_i99
#ISCELL
  mstr_symbols intel_corp_bpage *
  *
#CELL
  mstr_discrete res *
  page94_i100
#ISCELL
  mstr_standard offpage *
  page94_i101
#CELL
  mstr_discrete fet_n_dual *
  page94_i102
#ISCELL
  mstr_symbols pvpp_abc *
  page94_i103
#CELL
  mstr_discrete res *
  page94_i104
#ISCELL
  mstr_symbols gnd *
  page94_i105
#ISCELL
  mstr_standard offpage *
  page94_i39
#ISCELL
  mstr_symbols gnd *
  page94_i47
#CELL
  mstr_discrete fet_n_dual *
  page94_i49
#ISCELL
  mstr_symbols p3v3 *
  page94_i50
#CELL
  mstr_discrete res *
  page94_i51
#ISCELL
  mstr_symbols gnd *
  page94_i56
#ISCELL
  mstr_standard offpage *
  page94_i59
#CELL
  mstr_discrete fet_n_dual *
  page94_i60
#ISCELL
  mstr_standard offpage *
  page94_i61
#ISCELL
  mstr_symbols gnd *
  page94_i63
#CELL
  mstr_discrete fet_n_dual *
  page94_i64
#ISCELL
  mstr_symbols p3v3 *
  page94_i65
#CELL
  mstr_discrete res *
  page94_i66
#ISCELL
  mstr_symbols gnd *
  page94_i67
#ISCELL
  mstr_standard offpage *
  page94_i68
#CELL
  mstr_discrete fet_n_dual *
  page94_i69
#ISCELL
  mstr_standard offpage *
  page94_i70
#ISCELL
  mstr_standard offpage *
  page94_i71
#ISCELL
  mstr_symbols gnd *
  page94_i74
#CELL
  mstr_discrete fet_n_dual *
  page94_i75
#ISCELL
  mstr_symbols gnd *
  page94_i76
#CELL
  mstr_discrete fet_n_dual *
  page94_i77
#ISCELL
  mstr_symbols p3v3 *
  page94_i78
#CELL
  mstr_discrete res *
  page94_i79
#ISCELL
  mstr_symbols gnd *
  page94_i80
#ISCELL
  mstr_symbols p3v3 *
  page94_i81
#CELL
  mstr_discrete res *
  page94_i82
#ISCELL
  mstr_symbols gnd *
  page94_i83
#CELL
  mstr_discrete fet_n_dual *
  page94_i84
#ISCELL
  mstr_standard offpage *
  page94_i85
#ISCELL
  mstr_standard offpage *
  page94_i86
#CELL
  mstr_discrete fet_n_dual *
  page94_i89
#ISCELL
  mstr_standard offpage *
  page94_i90
#CELL
  mstr_discrete res *
  page94_i91
#ISCELL
  mstr_symbols p3v3_stby *
  page94_i92
#CELL
  mstr_discrete res *
  page94_i94
#ISCELL
  mstr_symbols gnd *
  page94_i95
#ISCELL
  mstr_symbols gnd *
  page94_i97
#CELL
  mstr_discrete fet_n_dual *
  page94_i98
#ISCELL
  mstr_symbols pvpp_abc *
  page94_i99
#ISCELL
  mstr_symbols cad_note *
  *
#ISCELL
  mstr_symbols intel_corp_bpage *
  *
#ISCELL
  mstr_symbols gnd *
  page95_i1
#ISCELL
  mstr_symbols gnd *
  page95_i105
#CELL
  mstr_discrete res *
  page95_i106
#ISCELL
  mstr_symbols p3v3 *
  page95_i107
#CELL
  mstr_discrete res *
  page95_i108
#ISCELL
  mstr_standard offpage *
  page95_i109
#ISCELL
  mstr_standard offpage *
  page95_i110
#CELL
  mstr_discrete fet_n_dual *
  page95_i111
#CELL
  mstr_discrete fet_n_dual *
  page95_i112
#CELL
  mstr_discrete fet_n_dual *
  page95_i113
#ISCELL
  mstr_symbols p3v3_stby *
  page95_i114
#CELL
  dev_discrete cap_a *
  page95_i115
#ISCELL
  mstr_symbols gnd *
  page95_i116
#CELL
  mstr_ttl ttl1g08 *
  page95_i117
#CELL
  mstr_ttl ttl1g08 *
  page95_i118
#ISCELL
  mstr_standard offpage *
  page95_i12
#ISCELL
  mstr_symbols gnd *
  page95_i120
#ISCELL
  mstr_standard offpage *
  page95_i121
#CELL
  mstr_discrete fet_n *
  page95_i122
#CELL
  mstr_discrete fet_n *
  page95_i123
#ISCELL
  mstr_standard offpage *
  page95_i13
#ISCELL
  mstr_standard offpage *
  page95_i14
#ISCELL
  mstr_standard offpage *
  page95_i18
#ISCELL
  mstr_standard offpage *
  page95_i19
#ISCELL
  mstr_standard offpage *
  page95_i22
#ISCELL
  mstr_symbols gnd *
  page95_i23
#ISCELL
  mstr_symbols gnd *
  page95_i26
#ISCELL
  mstr_symbols gnd *
  page95_i27
#CELL
  mstr_discrete fet_n_dual *
  page95_i28
#ISCELL
  mstr_symbols gnd *
  page95_i29
#ISCELL
  mstr_symbols gnd *
  page95_i30
#CELL
  mstr_discrete fet_n_dual *
  page95_i32
#CELL
  mstr_discrete fet_n_dual *
  page95_i33
#CELL
  mstr_discrete fet_n_dual *
  page95_i51
#CELL
  mstr_discrete fet_n_dual *
  page95_i52
#ISCELL
  mstr_standard offpage *
  page95_i58
#CELL
  mstr_discrete fet_n_dual *
  page95_i59
#ISCELL
  mstr_standard offpage *
  page95_i6
#ISCELL
  mstr_symbols gnd *
  page95_i60
#ISCELL
  mstr_symbols p3v3 *
  page95_i61
#CELL
  mstr_discrete res *
  page95_i62
#ISCELL
  mstr_symbols gnd *
  page95_i63
#ISCELL
  mstr_standard offpage *
  page95_i66
#ISCELL
  mstr_standard offpage *
  page95_i67
#ISCELL
  mstr_standard offpage *
  page95_i68
#CELL
  mstr_discrete fet_n_dual *
  page95_i69
#ISCELL
  mstr_symbols gnd *
  page95_i70
#ISCELL
  mstr_symbols p3v3 *
  page95_i71
#CELL
  mstr_discrete res *
  page95_i72
#ISCELL
  mstr_symbols gnd *
  page95_i73
#ISCELL
  mstr_standard offpage *
  page95_i76
#ISCELL
  mstr_standard offpage *
  page95_i77
#CELL
  dev_discrete cap_a *
  page95_i92
#ISCELL
  mstr_symbols gnd *
  page95_i94
#ISCELL
  mstr_symbols p3v3_stby *
  page95_i98
#ISCELL
  mstr_symbols cad_note *
  *
#ISCELL
  mstr_symbols design_note *
  *
#ISCELL
  mstr_symbols intel_corp_bpage *
  *
#ISCELL
  mstr_symbols pvccio_cpu0 *
  page96_i1
#ISCELL
  mstr_standard offpage *
  page96_i10
#ISCELL
  mstr_standard offpage *
  page96_i11
#ISCELL
  mstr_standard offpage *
  page96_i14
#ISCELL
  mstr_standard offpage *
  page96_i15
#ISCELL
  mstr_standard offpage *
  page96_i16
#ISCELL
  mstr_standard offpage *
  page96_i17
#CELL
  mstr_discrete res *
  page96_i2
#ISCELL
  mstr_symbols pvccio_cpu1 *
  page96_i24
#CELL
  mstr_discrete res *
  page96_i25
#CELL
  mstr_discrete res *
  page96_i26
#ISCELL
  mstr_symbols pvddq_klm *
  page96_i27
#CELL
  mstr_discrete res *
  page96_i28
#ISCELL
  mstr_symbols pvddq_ghj *
  page96_i29
#CELL
  mstr_discrete res *
  page96_i3
#CELL
  mstr_discrete res *
  page96_i30
#CELL
  mstr_discrete res *
  page96_i36
#ISCELL
  mstr_symbols pvddq_def *
  page96_i4
#ISCELL
  mstr_symbols gnd *
  page96_i41
#CELL
  mstr_digital gtl2014 *
  page96_i42
#ISCELL
  mstr_symbols gnd *
  page96_i45
#CELL
  mstr_digital gtl2014 *
  page96_i46
#CELL
  mstr_discrete res *
  page96_i5
#ISCELL
  mstr_standard offpage *
  page96_i51
#ISCELL
  mstr_standard offpage *
  page96_i52
#ISCELL
  mstr_standard offpage *
  page96_i53
#CELL
  mstr_discrete res *
  page96_i55
#ISCELL
  mstr_standard offpage *
  page96_i59
#ISCELL
  mstr_symbols pvddq_abc *
  page96_i6
#ISCELL
  mstr_standard offpage *
  page96_i60
#ISCELL
  mstr_standard offpage *
  page96_i61
#ISCELL
  mstr_symbols p3v3_stby *
  page96_i65
#ISCELL
  mstr_symbols p3v3_stby *
  page96_i68
#CELL
  mstr_discrete res *
  page96_i69
#CELL
  mstr_discrete res *
  page96_i7
#ISCELL
  mstr_symbols gnd *
  page96_i70
#CELL
  mstr_discrete res *
  page96_i71
#ISCELL
  mstr_symbols gnd *
  page96_i72
#CELL
  dev_discrete cap_a *
  page96_i73
#ISCELL
  mstr_symbols gnd *
  page96_i74
#CELL
  dev_discrete cap_a *
  page96_i75
#ISCELL
  mstr_symbols gnd *
  page96_i76
#ISCELL
  mstr_standard offpage *
  page96_i8
#ISCELL
  mstr_standard offpage *
  page96_i9
#ISCELL
  mstr_symbols cad_note *
  *
#ISCELL
  mstr_symbols intel_corp_bpage *
  *
#ISCELL
  mstr_standard offpage *
  page97_i22
#CELL
  mstr_discrete res *
  page97_i33
#ISCELL
  mstr_standard offpage *
  page97_i34
#ISCELL
  mstr_symbols pvccio_cpu0 *
  page97_i41
#CELL
  mstr_discrete res *
  page97_i42
#CELL
  mstr_discrete res *
  page97_i44
#ISCELL
  mstr_symbols pvccio_cpu0 *
  page97_i71
#CELL
  mstr_discrete res *
  page97_i72
#ISCELL
  mstr_standard offpage *
  page97_i74
#CELL
  mstr_discrete res *
  page97_i76
#ISCELL
  mstr_standard offpage *
  page97_i77
#ISCELL
  mstr_symbols pvccio_cpu1 *
  page97_i78
#CELL
  mstr_discrete res *
  page97_i80
#CELL
  mstr_discrete res *
  page97_i81
#ISCELL
  mstr_symbols gnd *
  page97_i82
#ISCELL
  mstr_standard offpage *
  page97_i83
#ISCELL
  mstr_standard offpage *
  page97_i84
#ISCELL
  mstr_symbols pvccio_cpu0 *
  page97_i85
#ISCELL
  mstr_symbols cad_note *
  *
#ISCELL
  mstr_symbols intel_corp_bpage *
  *
#ISCELL
  mstr_symbols pvddq_abc *
  page98_i1
#ISCELL
  mstr_symbols pvddq_def *
  page98_i10
#ISCELL
  mstr_standard offpage *
  page98_i11
#CELL
  mstr_discrete res *
  page98_i12
#ISCELL
  mstr_symbols gnd *
  page98_i13
#CELL
  mstr_discrete res *
  page98_i14
#ISCELL
  mstr_standard offpage *
  page98_i16
#ISCELL
  mstr_standard offpage *
  page98_i3
#CELL
  dev_discrete cap_a *
  page98_i33
#CELL
  mstr_discrete res *
  page98_i36
#ISCELL
  mstr_symbols pvddq_abc *
  page98_i37
#CELL
  mstr_discrete res *
  page98_i38
#ISCELL
  mstr_standard offpage *
  page98_i39
#CELL
  mstr_discrete res *
  page98_i4
#CELL
  mstr_discrete res *
  page98_i40
#ISCELL
  mstr_symbols gnd *
  page98_i41
#CELL
  mstr_discrete res *
  page98_i42
#CELL
  dev_discrete cap_a *
  page98_i43
#ISCELL
  mstr_standard offpage *
  page98_i44
#ISCELL
  mstr_symbols pvddq_abc *
  page98_i45
#CELL
  mstr_discrete res *
  page98_i46
#ISCELL
  mstr_standard offpage *
  page98_i47
#CELL
  mstr_discrete res *
  page98_i48
#ISCELL
  mstr_symbols gnd *
  page98_i49
#CELL
  mstr_discrete res *
  page98_i5
#CELL
  mstr_discrete res *
  page98_i50
#CELL
  dev_discrete cap_a *
  page98_i51
#ISCELL
  mstr_standard offpage *
  page98_i52
#CELL
  mstr_discrete res *
  page98_i54
#ISCELL
  mstr_standard offpage *
  page98_i55
#CELL
  mstr_discrete res *
  page98_i56
#ISCELL
  mstr_symbols gnd *
  page98_i57
#CELL
  mstr_discrete res *
  page98_i58
#CELL
  dev_discrete cap_a *
  page98_i59
#ISCELL
  mstr_symbols gnd *
  page98_i6
#ISCELL
  mstr_standard offpage *
  page98_i60
#CELL
  mstr_discrete res *
  page98_i62
#ISCELL
  mstr_standard offpage *
  page98_i63
#CELL
  mstr_discrete res *
  page98_i64
#ISCELL
  mstr_symbols gnd *
  page98_i65
#CELL
  mstr_discrete res *
  page98_i66
#CELL
  dev_discrete cap_a *
  page98_i67
#ISCELL
  mstr_standard offpage *
  page98_i68
#ISCELL
  mstr_symbols pvddq_def *
  page98_i69
#CELL
  dev_discrete cap_a *
  page98_i7
#ISCELL
  mstr_symbols pvddq_def *
  page98_i70
#ISCELL
  mstr_standard offpage *
  page98_i8
#CELL
  mstr_discrete res *
  page98_i9
#ISCELL
  mstr_symbols intel_corp_bpage *
  *
#ISCELL
  mstr_symbols pvccio_cpu0 *
  page99_i1
#CELL
  mstr_discrete res *
  page99_i10
#ISCELL
  mstr_standard offpage *
  page99_i100
#CELL
  mstr_discrete res *
  page99_i101
#ISCELL
  mstr_symbols pvpp_def *
  page99_i102
#CELL
  mstr_discrete res *
  page99_i103
#CELL
  mstr_discrete res *
  page99_i104
#ISCELL
  mstr_symbols pvpp_ghj *
  page99_i105
#CELL
  mstr_discrete res *
  page99_i106
#CELL
  mstr_discrete res *
  page99_i107
#ISCELL
  mstr_symbols pvpp_klm *
  page99_i108
#CELL
  mstr_discrete res *
  page99_i109
#CELL
  mstr_discrete res *
  page99_i11
#CELL
  mstr_discrete res *
  page99_i110
#CELL
  mstr_discrete res *
  page99_i111
#CELL
  mstr_discrete res *
  page99_i112
#ISCELL
  mstr_symbols pvpp_abc *
  page99_i113
#ISCELL
  mstr_symbols pvpp_abc *
  page99_i114
#CELL
  mstr_discrete res *
  page99_i115
#ISCELL
  mstr_symbols pvpp_abc *
  page99_i12
#CELL
  mstr_discrete res *
  page99_i13
#CELL
  mstr_digital pca9617 *
  page99_i15
#ISCELL
  mstr_symbols pvccio_cpu0 *
  page99_i16
#CELL
  mstr_discrete res *
  page99_i17
#ISCELL
  mstr_symbols pvccio_cpu0 *
  page99_i18
#CELL
  mstr_discrete res *
  page99_i19
#CELL
  dev_discrete cap_a *
  page99_i2
#CELL
  mstr_discrete res *
  page99_i20
#ISCELL
  mstr_symbols pvccio_cpu0 *
  page99_i21
#ISCELL
  mstr_symbols gnd *
  page99_i22
#CELL
  dev_discrete cap_a *
  page99_i23
#ISCELL
  mstr_standard offpage *
  page99_i24
#ISCELL
  mstr_standard offpage *
  page99_i25
#ISCELL
  mstr_symbols pvccio_cpu1 *
  page99_i26
#CELL
  dev_discrete cap_a *
  page99_i27
#ISCELL
  mstr_symbols gnd *
  page99_i28
#ISCELL
  mstr_standard offpage *
  page99_i29
#ISCELL
  mstr_symbols gnd *
  page99_i3
#ISCELL
  mstr_standard offpage *
  page99_i30
#ISCELL
  mstr_symbols pvpp_def *
  page99_i31
#CELL
  dev_discrete cap_a *
  page99_i32
#ISCELL
  mstr_symbols gnd *
  page99_i33
#CELL
  mstr_discrete res *
  page99_i34
#CELL
  mstr_discrete res *
  page99_i35
#ISCELL
  mstr_symbols pvpp_ghj *
  page99_i39
#ISCELL
  mstr_standard offpage *
  page99_i4
#ISCELL
  mstr_symbols gnd *
  page99_i40
#CELL
  dev_discrete cap_a *
  page99_i41
#CELL
  mstr_discrete res *
  page99_i42
#CELL
  dev_discrete cap_a *
  page99_i47
#ISCELL
  mstr_symbols pvccio_cpu1 *
  page99_i48
#ISCELL
  mstr_symbols gnd *
  page99_i49
#ISCELL
  mstr_standard offpage *
  page99_i5
#ISCELL
  mstr_standard offpage *
  page99_i50
#ISCELL
  mstr_standard offpage *
  page99_i51
#ISCELL
  mstr_symbols pvpp_klm *
  page99_i52
#CELL
  dev_discrete cap_a *
  page99_i53
#ISCELL
  mstr_symbols gnd *
  page99_i54
#CELL
  mstr_discrete res *
  page99_i55
#CELL
  mstr_discrete res *
  page99_i56
#ISCELL
  mstr_symbols pvpp_def *
  page99_i60
#CELL
  mstr_digital pca9617 *
  page99_i61
#ISCELL
  mstr_symbols pvpp_ghj *
  page99_i62
#CELL
  mstr_digital pca9617 *
  page99_i63
#ISCELL
  mstr_symbols pvccio_cpu0 *
  page99_i64
#CELL
  mstr_discrete res *
  page99_i65
#ISCELL
  mstr_symbols pvccio_cpu0 *
  page99_i66
#CELL
  mstr_discrete res *
  page99_i67
#ISCELL
  mstr_symbols pvccio_cpu1 *
  page99_i69
#CELL
  dev_discrete cap_a *
  page99_i7
#CELL
  mstr_discrete res *
  page99_i70
#ISCELL
  mstr_symbols pvccio_cpu1 *
  page99_i71
#CELL
  mstr_discrete res *
  page99_i72
#ISCELL
  mstr_symbols pvpp_klm *
  page99_i74
#CELL
  mstr_digital pca9617 *
  page99_i75
#ISCELL
  mstr_symbols pvccio_cpu1 *
  page99_i76
#CELL
  mstr_discrete res *
  page99_i77
#ISCELL
  mstr_symbols pvccio_cpu1 *
  page99_i78
#CELL
  mstr_discrete res *
  page99_i79
#ISCELL
  mstr_symbols gnd *
  page99_i8
#CELL
  mstr_discrete res *
  page99_i83
#ISCELL
  mstr_standard offpage *
  page99_i84
#ISCELL
  mstr_standard offpage *
  page99_i85
#CELL
  mstr_discrete res *
  page99_i88
#ISCELL
  mstr_standard offpage *
  page99_i89
#CELL
  mstr_discrete res *
  page99_i9
#CELL
  mstr_discrete res *
  page99_i92
#ISCELL
  mstr_standard offpage *
  page99_i93
#ISCELL
  mstr_standard offpage *
  page99_i94
#ISCELL
  mstr_standard offpage *
  page99_i95
#CELL
  mstr_discrete res *
  page99_i98
#ISCELL
  mstr_standard offpage *
  page99_i99
#ISCELL
  mstr_symbols cad_note *
  *
#ISCELL
  mstr_symbols intel_corp_bpage *
  *
#ISCELL
  mstr_standard offpage *
  page100_i1
#ISCELL
  mstr_symbols pvddq_klm *
  page100_i10
#CELL
  mstr_discrete res *
  page100_i11
#ISCELL
  mstr_standard offpage *
  page100_i12
#CELL
  mstr_discrete res *
  page100_i13
#ISCELL
  mstr_symbols gnd *
  page100_i14
#CELL
  dev_discrete cap_a *
  page100_i15
#ISCELL
  mstr_standard offpage *
  page100_i16
#ISCELL
  mstr_symbols pvddq_ghj *
  page100_i17
#ISCELL
  mstr_standard offpage *
  page100_i18
#CELL
  mstr_discrete res *
  page100_i19
#CELL
  mstr_discrete res *
  page100_i2
#CELL
  mstr_discrete res *
  page100_i20
#ISCELL
  mstr_symbols pvddq_klm *
  page100_i21
#CELL
  mstr_discrete res *
  page100_i22
#ISCELL
  mstr_standard offpage *
  page100_i23
#CELL
  mstr_discrete res *
  page100_i24
#CELL
  mstr_discrete res *
  page100_i25
#CELL
  dev_discrete cap_a *
  page100_i26
#ISCELL
  mstr_standard offpage *
  page100_i27
#ISCELL
  mstr_symbols gnd *
  page100_i28
#CELL
  mstr_discrete res *
  page100_i29
#ISCELL
  mstr_standard offpage *
  page100_i3
#CELL
  dev_discrete cap_a *
  page100_i30
#ISCELL
  mstr_symbols gnd *
  page100_i31
#ISCELL
  mstr_standard offpage *
  page100_i32
#ISCELL
  mstr_symbols pvddq_ghj *
  page100_i33
#ISCELL
  mstr_standard offpage *
  page100_i34
#CELL
  mstr_discrete res *
  page100_i35
#CELL
  mstr_discrete res *
  page100_i36
#ISCELL
  mstr_symbols pvddq_klm *
  page100_i37
#CELL
  mstr_discrete res *
  page100_i38
#ISCELL
  mstr_standard offpage *
  page100_i39
#CELL
  mstr_discrete res *
  page100_i4
#CELL
  mstr_discrete res *
  page100_i40
#CELL
  mstr_discrete res *
  page100_i41
#CELL
  dev_discrete cap_a *
  page100_i42
#ISCELL
  mstr_standard offpage *
  page100_i43
#ISCELL
  mstr_symbols gnd *
  page100_i44
#CELL
  mstr_discrete res *
  page100_i45
#CELL
  dev_discrete cap_a *
  page100_i46
#ISCELL
  mstr_symbols gnd *
  page100_i47
#ISCELL
  mstr_standard offpage *
  page100_i48
#ISCELL
  mstr_symbols pvddq_ghj *
  page100_i5
#CELL
  mstr_discrete res *
  page100_i6
#CELL
  mstr_discrete res *
  page100_i7
#CELL
  dev_discrete cap_a *
  page100_i8
#ISCELL
  mstr_symbols gnd *
  page100_i9
#ISCELL
  mstr_misc dns *
  *
#ISCELL
  mstr_symbols cad_note *
  *
#ISCELL
  mstr_symbols intel_corp_bpage *
  *
#ISCELL
  mstr_symbols vcc_core *
  page101_i100
#ISCELL
  mstr_symbols vcc_core *
  page101_i101
#ISCELL
  mstr_symbols vcc_core *
  page101_i102
#ISCELL
  mstr_symbols vcc_core *
  page101_i103
#CELL
  dev_discrete cap_a *
  page101_i104
#CELL
  mstr_discrete res *
  page101_i105
#CELL
  dev_discrete cap_a *
  page101_i106
#ISCELL
  mstr_symbols gnd *
  page101_i107
#ISCELL
  mstr_symbols gnd *
  page101_i108
#CELL
  dev_discrete cap_a *
  page101_i109
#CELL
  dev_discrete cap_a *
  page101_i110
#CELL
  dev_discrete cap_a *
  page101_i111
#CELL
  dev_discrete cap_a *
  page101_i112
#CELL
  mstr_discrete cap *
  page101_i113
#CELL
  mstr_discrete ferrite *
  page101_i114
#ISCELL
  mstr_symbols p3v3_stby *
  page101_i115
#CELL
  dev_discrete cap_a *
  page101_i116
#ISCELL
  mstr_symbols vcc_core *
  page101_i117
#ISCELL
  mstr_symbols vcc_core *
  page101_i118
#ISCELL
  mstr_symbols vcc_core *
  page101_i119
#ISCELL
  mstr_symbols vcc_core *
  page101_i120
#ISCELL
  mstr_symbols vcc_core *
  page101_i121
#ISCELL
  mstr_symbols vcc_core *
  page101_i122
#ISCELL
  mstr_symbols vcc_core *
  page101_i123
#CELL
  mstr_discrete res *
  page101_i124
#CELL
  mstr_discrete res *
  page101_i125
#ISCELL
  mstr_standard offpage *
  page101_i13
#CELL
  mstr_discrete res *
  page101_i130
#CELL
  mstr_discrete res *
  page101_i134
#CELL
  mstr_discrete res *
  page101_i135
#ISCELL
  mstr_standard offpage *
  page101_i136
#ISCELL
  mstr_standard offpage *
  page101_i137
#CELL
  mstr_discrete res *
  page101_i138
#CELL
  mstr_discrete cap *
  page101_i139
#ISCELL
  mstr_standard offpage *
  page101_i14
#CELL
  mstr_discrete res *
  page101_i140
#ISCELL
  mstr_symbols gnd *
  page101_i141
#CELL
  mstr_discrete res *
  page101_i142
#CELL
  mstr_discrete res *
  page101_i143
#CELL
  mstr_discrete res *
  page101_i144
#CELL
  mstr_discrete res *
  page101_i145
#CELL
  mstr_discrete cap *
  page101_i146
#CELL
  mstr_discrete cap *
  page101_i147
#CELL
  mstr_discrete res *
  page101_i20
#CELL
  mstr_discrete res *
  page101_i28
#ISCELL
  mstr_symbols gnd *
  page101_i29
#ISCELL
  mstr_symbols gnd *
  page101_i33
#CELL
  mstr_clock ics9fgp204 *
  page101_i34
#CELL
  mstr_discrete res *
  page101_i48
#CELL
  mstr_discrete crystal *
  page101_i52
#ISCELL
  mstr_symbols gnd *
  page101_i54
#ISCELL
  mstr_standard offpage *
  page101_i55
#ISCELL
  mstr_symbols gnd *
  page101_i58
#ISCELL
  mstr_symbols gnd *
  page101_i64
#ISCELL
  mstr_standard offpage *
  page101_i71
#ISCELL
  mstr_standard offpage *
  page101_i72
#ISCELL
  mstr_standard offpage *
  page101_i79
#ISCELL
  mstr_standard offpage *
  page101_i80
#ISCELL
  mstr_standard offpage *
  page101_i81
#ISCELL
  mstr_standard offpage *
  page101_i87
#CELL
  dev_discrete cap_a *
  page101_i89
#CELL
  dev_discrete cap_a *
  page101_i90
#CELL
  mstr_discrete res *
  page101_i94
#CELL
  mstr_discrete res *
  page101_i95
#ISCELL
  mstr_symbols gnd *
  page101_i96
#CELL
  dev_discrete cap_a *
  page101_i97
#ISCELL
  mstr_symbols gnd *
  page101_i98
#CELL
  dev_discrete cap_a *
  page101_i99
#ISCELL
  mstr_misc dns *
  *
#ISCELL
  mstr_symbols design_note *
  *
#ISCELL
  mstr_symbols intel_corp_bpage *
  *
#CELL
  mstr_clock nb3w1200l *
  page102_i1
#CELL
  mstr_discrete cap *
  page102_i10
#CELL
  mstr_discrete fet_n_dual *
  page102_i101
#CELL
  mstr_discrete fet_n_dual *
  page102_i102
#CELL
  mstr_discrete res *
  page102_i103
#ISCELL
  mstr_symbols vcc_core *
  page102_i104
#CELL
  mstr_discrete res *
  page102_i105
#CELL
  mstr_discrete res *
  page102_i106
#ISCELL
  mstr_symbols vcc_core *
  page102_i107
#CELL
  mstr_discrete res *
  page102_i109
#CELL
  dev_discrete cap_a *
  page102_i11
#ISCELL
  mstr_symbols vcc_core *
  page102_i110
#ISCELL
  mstr_standard offpage *
  page102_i111
#CELL
  mstr_discrete fet_n *
  page102_i112
#ISCELL
  mstr_symbols gnd *
  page102_i113
#CELL
  mstr_discrete res *
  page102_i114
#CELL
  mstr_discrete res *
  page102_i115
#CELL
  dev_discrete cap_a *
  page102_i12
#CELL
  dev_discrete cap_a *
  page102_i13
#CELL
  dev_discrete cap_a *
  page102_i14
#CELL
  dev_discrete cap_a *
  page102_i15
#CELL
  dev_discrete cap_a *
  page102_i16
#ISCELL
  mstr_symbols gnd *
  page102_i17
#CELL
  dev_discrete cap_a *
  page102_i18
#CELL
  dev_discrete cap_a *
  page102_i19
#CELL
  mstr_discrete res *
  page102_i21
#ISCELL
  mstr_symbols gnd *
  page102_i22
#ISCELL
  mstr_symbols vcc_core *
  page102_i23
#ISCELL
  mstr_symbols vcc_core *
  page102_i24
#ISCELL
  mstr_symbols vcc_core *
  page102_i25
#CELL
  mstr_discrete res *
  page102_i26
#ISCELL
  mstr_symbols vcc_core *
  page102_i27
#CELL
  dev_discrete cap_a *
  page102_i28
#ISCELL
  mstr_symbols gnd *
  page102_i29
#CELL
  dev_discrete cap_a *
  page102_i30
#ISCELL
  mstr_standard offpage *
  page102_i31
#ISCELL
  mstr_standard offpage *
  page102_i32
#ISCELL
  mstr_standard offpage *
  page102_i33
#ISCELL
  mstr_standard offpage *
  page102_i34
#ISCELL
  mstr_standard offpage *
  page102_i35
#ISCELL
  mstr_standard offpage *
  page102_i36
#CELL
  mstr_discrete res *
  page102_i37
#CELL
  mstr_discrete res *
  page102_i38
#ISCELL
  mstr_standard offpage *
  page102_i4
#ISCELL
  mstr_standard offpage *
  page102_i41
#ISCELL
  mstr_standard offpage *
  page102_i42
#ISCELL
  mstr_symbols vcc_core *
  page102_i43
#ISCELL
  mstr_symbols gnd *
  page102_i44
#CELL
  mstr_discrete res *
  page102_i45
#CELL
  mstr_discrete res *
  page102_i46
#CELL
  mstr_discrete res *
  page102_i47
#ISCELL
  mstr_symbols vcc_core *
  page102_i49
#ISCELL
  mstr_standard offpage *
  page102_i5
#ISCELL
  mstr_symbols gnd *
  page102_i50
#ISCELL
  mstr_standard offpage *
  page102_i51
#ISCELL
  mstr_standard offpage *
  page102_i52
#CELL
  mstr_discrete res *
  page102_i53
#ISCELL
  mstr_standard offpage *
  page102_i54
#ISCELL
  mstr_standard offpage *
  page102_i55
#ISCELL
  mstr_standard offpage *
  page102_i56
#ISCELL
  mstr_standard offpage *
  page102_i57
#ISCELL
  mstr_standard offpage *
  page102_i58
#ISCELL
  mstr_standard offpage *
  page102_i59
#ISCELL
  mstr_symbols gnd *
  page102_i6
#ISCELL
  mstr_standard offpage *
  page102_i60
#ISCELL
  mstr_standard offpage *
  page102_i61
#ISCELL
  mstr_standard offpage *
  page102_i62
#ISCELL
  mstr_standard offpage *
  page102_i63
#ISCELL
  mstr_standard offpage *
  page102_i64
#ISCELL
  mstr_standard offpage *
  page102_i65
#ISCELL
  mstr_standard offpage *
  page102_i66
#ISCELL
  mstr_standard offpage *
  page102_i67
#ISCELL
  mstr_standard offpage *
  page102_i68
#ISCELL
  mstr_standard offpage *
  page102_i69
#ISCELL
  mstr_standard offpage *
  page102_i70
#ISCELL
  mstr_standard offpage *
  page102_i71
#ISCELL
  mstr_standard offpage *
  page102_i72
#ISCELL
  mstr_standard offpage *
  page102_i73
#ISCELL
  mstr_standard offpage *
  page102_i74
#ISCELL
  mstr_standard offpage *
  page102_i75
#ISCELL
  mstr_standard offpage *
  page102_i76
#ISCELL
  mstr_standard offpage *
  page102_i77
#CELL
  dev_discrete cap_a *
  page102_i79
#CELL
  mstr_discrete ferrite *
  page102_i8
#CELL
  mstr_discrete res *
  page102_i80
#CELL
  mstr_discrete res *
  page102_i81
#ISCELL
  mstr_standard offpage *
  page102_i83
#ISCELL
  mstr_standard offpage *
  page102_i84
#ISCELL
  mstr_standard offpage *
  page102_i85
#ISCELL
  mstr_standard offpage *
  page102_i86
#ISCELL
  mstr_standard offpage *
  page102_i89
#ISCELL
  mstr_symbols p3v3 *
  page102_i9
#ISCELL
  mstr_standard offpage *
  page102_i90
#CELL
  mstr_discrete res *
  page102_i93
#CELL
  mstr_discrete res *
  page102_i94
#ISCELL
  mstr_symbols p3v3 *
  page102_i95
#ISCELL
  mstr_standard offpage *
  page102_i96
#ISCELL
  mstr_standard offpage *
  page102_i97
#ISCELL
  mstr_standard offpage *
  page102_i98
#ISCELL
  mstr_standard offpage *
  page102_i99
#ISCELL
  mstr_misc dns *
  *
#ISCELL
  mstr_symbols cad_note *
  *
#ISCELL
  mstr_symbols design_note *
  *
#ISCELL
  mstr_symbols intel_corp_bpage *
  *
#CELL
  mstr_discrete res *
  page103_i1
#ISCELL
  mstr_standard offpage *
  page103_i10
#ISCELL
  mstr_standard offpage *
  page103_i100
#ISCELL
  mstr_standard offpage *
  page103_i102
#CELL
  mstr_discrete res *
  page103_i104
#ISCELL
  mstr_standard offpage *
  page103_i105
#ISCELL
  mstr_standard offpage *
  page103_i108
#CELL
  mstr_discrete res *
  page103_i109
#ISCELL
  mstr_standard offpage *
  page103_i11
#ISCELL
  mstr_standard offpage *
  page103_i110
#ISCELL
  mstr_standard offpage *
  page103_i113
#CELL
  mstr_discrete res *
  page103_i114
#ISCELL
  mstr_standard offpage *
  page103_i115
#ISCELL
  mstr_standard offpage *
  page103_i118
#CELL
  mstr_discrete res *
  page103_i119
#ISCELL
  mstr_standard offpage *
  page103_i120
#CELL
  mstr_discrete res *
  page103_i121
#CELL
  mstr_discrete res *
  page103_i123
#CELL
  mstr_discrete res *
  page103_i125
#ISCELL
  mstr_symbols gnd *
  page103_i126
#CELL
  mstr_discrete res *
  page103_i127
#ISCELL
  mstr_symbols gnd *
  page103_i128
#CELL
  mstr_discrete res *
  page103_i129
#ISCELL
  mstr_symbols gnd *
  page103_i130
#CELL
  mstr_discrete res *
  page103_i131
#ISCELL
  mstr_symbols gnd *
  page103_i132
#CELL
  mstr_discrete res *
  page103_i133
#ISCELL
  mstr_symbols gnd *
  page103_i134
#CELL
  mstr_discrete res *
  page103_i135
#ISCELL
  mstr_symbols gnd *
  page103_i136
#CELL
  mstr_discrete res *
  page103_i137
#ISCELL
  mstr_symbols gnd *
  page103_i138
#CELL
  mstr_discrete res *
  page103_i139
#CELL
  mstr_discrete res *
  page103_i14
#ISCELL
  mstr_symbols gnd *
  page103_i140
#CELL
  mstr_discrete res *
  page103_i141
#ISCELL
  mstr_symbols gnd *
  page103_i142
#CELL
  mstr_discrete res *
  page103_i143
#ISCELL
  mstr_symbols gnd *
  page103_i144
#CELL
  mstr_discrete res *
  page103_i145
#ISCELL
  mstr_symbols gnd *
  page103_i146
#CELL
  mstr_discrete res *
  page103_i147
#ISCELL
  mstr_symbols gnd *
  page103_i148
#CELL
  mstr_discrete res *
  page103_i149
#ISCELL
  mstr_standard offpage *
  page103_i15
#ISCELL
  mstr_symbols gnd *
  page103_i150
#CELL
  mstr_discrete res *
  page103_i151
#ISCELL
  mstr_symbols gnd *
  page103_i152
#CELL
  mstr_discrete res *
  page103_i153
#ISCELL
  mstr_symbols gnd *
  page103_i154
#CELL
  mstr_discrete res *
  page103_i155
#ISCELL
  mstr_symbols gnd *
  page103_i156
#CELL
  mstr_discrete res *
  page103_i157
#ISCELL
  mstr_symbols gnd *
  page103_i158
#CELL
  mstr_discrete res *
  page103_i159
#ISCELL
  mstr_standard offpage *
  page103_i16
#ISCELL
  mstr_symbols gnd *
  page103_i160
#CELL
  mstr_discrete res *
  page103_i161
#ISCELL
  mstr_symbols gnd *
  page103_i162
#CELL
  mstr_discrete res *
  page103_i163
#ISCELL
  mstr_symbols gnd *
  page103_i164
#CELL
  mstr_discrete res *
  page103_i165
#ISCELL
  mstr_symbols gnd *
  page103_i166
#CELL
  mstr_discrete res *
  page103_i167
#ISCELL
  mstr_symbols gnd *
  page103_i168
#ISCELL
  mstr_symbols gnd *
  page103_i169
#ISCELL
  mstr_symbols gnd *
  page103_i170
#CELL
  mstr_discrete res *
  page103_i19
#ISCELL
  mstr_standard offpage *
  page103_i20
#ISCELL
  mstr_standard offpage *
  page103_i21
#CELL
  mstr_discrete res *
  page103_i24
#ISCELL
  mstr_standard offpage *
  page103_i25
#ISCELL
  mstr_standard offpage *
  page103_i26
#CELL
  mstr_discrete res *
  page103_i29
#ISCELL
  mstr_standard offpage *
  page103_i30
#ISCELL
  mstr_standard offpage *
  page103_i31
#CELL
  mstr_discrete res *
  page103_i34
#ISCELL
  mstr_standard offpage *
  page103_i35
#ISCELL
  mstr_standard offpage *
  page103_i36
#CELL
  mstr_discrete res *
  page103_i39
#ISCELL
  mstr_standard offpage *
  page103_i4
#ISCELL
  mstr_standard offpage *
  page103_i40
#ISCELL
  mstr_standard offpage *
  page103_i41
#CELL
  mstr_discrete res *
  page103_i44
#ISCELL
  mstr_standard offpage *
  page103_i45
#ISCELL
  mstr_standard offpage *
  page103_i46
#CELL
  mstr_discrete res *
  page103_i49
#ISCELL
  mstr_standard offpage *
  page103_i5
#ISCELL
  mstr_standard offpage *
  page103_i50
#ISCELL
  mstr_standard offpage *
  page103_i51
#CELL
  mstr_discrete res *
  page103_i54
#ISCELL
  mstr_standard offpage *
  page103_i55
#ISCELL
  mstr_standard offpage *
  page103_i56
#CELL
  mstr_discrete res *
  page103_i59
#ISCELL
  mstr_standard offpage *
  page103_i6
#ISCELL
  mstr_standard offpage *
  page103_i60
#ISCELL
  mstr_standard offpage *
  page103_i61
#CELL
  mstr_discrete res *
  page103_i64
#ISCELL
  mstr_standard offpage *
  page103_i65
#ISCELL
  mstr_standard offpage *
  page103_i66
#CELL
  mstr_discrete res *
  page103_i69
#ISCELL
  mstr_standard offpage *
  page103_i70
#ISCELL
  mstr_standard offpage *
  page103_i71
#CELL
  mstr_discrete res *
  page103_i74
#ISCELL
  mstr_standard offpage *
  page103_i75
#ISCELL
  mstr_standard offpage *
  page103_i77
#CELL
  mstr_discrete res *
  page103_i79
#ISCELL
  mstr_standard offpage *
  page103_i80
#ISCELL
  mstr_standard offpage *
  page103_i82
#CELL
  mstr_discrete res *
  page103_i84
#ISCELL
  mstr_standard offpage *
  page103_i85
#ISCELL
  mstr_standard offpage *
  page103_i87
#CELL
  mstr_discrete res *
  page103_i89
#CELL
  mstr_discrete res *
  page103_i9
#ISCELL
  mstr_standard offpage *
  page103_i90
#ISCELL
  mstr_standard offpage *
  page103_i92
#CELL
  mstr_discrete res *
  page103_i94
#ISCELL
  mstr_standard offpage *
  page103_i95
#ISCELL
  mstr_standard offpage *
  page103_i97
#CELL
  mstr_discrete res *
  page103_i99
#ISCELL
  mstr_misc dns *
  *
#ISCELL
  mstr_symbols cad_note *
  *
#ISCELL
  mstr_symbols intel_corp_bpage *
  *
#ISCELL
  mstr_standard offpage *
  page104_i100
#ISCELL
  mstr_standard offpage *
  page104_i101
#ISCELL
  mstr_standard offpage *
  page104_i102
#CELL
  mstr_discrete res *
  page104_i103
#CELL
  mstr_discrete res *
  page104_i104
#ISCELL
  mstr_symbols p3v3 *
  page104_i24
#CELL
  dev_discrete cap_a *
  page104_i25
#ISCELL
  mstr_symbols gnd *
  page104_i26
#ISCELL
  mstr_symbols gnd *
  page104_i27
#ISCELL
  mstr_standard offpage *
  page104_i29
#ISCELL
  mstr_symbols gnd *
  page104_i31
#ISCELL
  mstr_symbols p3v3 *
  page104_i32
#ISCELL
  mstr_symbols gnd *
  page104_i33
#CELL
  dev_discrete cap_a *
  page104_i34
#ISCELL
  mstr_standard offpage *
  page104_i36
#CELL
  mstr_discrete res *
  page104_i37
#ISCELL
  mstr_standard offpage *
  page104_i38
#CELL
  mstr_discrete res *
  page104_i41
#ISCELL
  mstr_standard offpage *
  page104_i42
#ISCELL
  mstr_standard offpage *
  page104_i44
#ISCELL
  mstr_standard offpage *
  page104_i46
#ISCELL
  mstr_standard offpage *
  page104_i48
#CELL
  mstr_discrete res *
  page104_i51
#CELL
  mstr_discrete res *
  page104_i53
#ISCELL
  mstr_standard offpage *
  page104_i54
#ISCELL
  mstr_standard offpage *
  page104_i55
#ISCELL
  mstr_standard offpage *
  page104_i56
#ISCELL
  mstr_standard offpage *
  page104_i57
#ISCELL
  mstr_standard offpage *
  page104_i58
#ISCELL
  mstr_standard offpage *
  page104_i59
#ISCELL
  mstr_standard offpage *
  page104_i60
#CELL
  mstr_discrete res *
  page104_i67
#CELL
  mstr_discrete res *
  page104_i68
#CELL
  mstr_discrete res *
  page104_i69
#CELL
  mstr_discrete res *
  page104_i70
#CELL
  mstr_discrete osc_c *
  page104_i71
#CELL
  mstr_discrete osc_c *
  page104_i72
#ISCELL
  mstr_standard offpage *
  page104_i74
#ISCELL
  mstr_standard offpage *
  page104_i76
#ISCELL
  mstr_standard offpage *
  page104_i77
#CELL
  mstr_discrete res *
  page104_i78
#CELL
  mstr_discrete res *
  page104_i79
#ISCELL
  mstr_standard offpage *
  page104_i80
#ISCELL
  mstr_standard offpage *
  page104_i81
#ISCELL
  mstr_standard offpage *
  page104_i83
#CELL
  mstr_discrete res *
  page104_i84
#ISCELL
  mstr_standard offpage *
  page104_i86
#ISCELL
  mstr_standard offpage *
  page104_i87
#CELL
  mstr_discrete res *
  page104_i88
#ISCELL
  mstr_standard offpage *
  page104_i89
#ISCELL
  mstr_standard offpage *
  page104_i90
#ISCELL
  mstr_standard offpage *
  page104_i91
#ISCELL
  mstr_standard offpage *
  page104_i92
#CELL
  mstr_discrete res *
  page104_i93
#CELL
  mstr_discrete res *
  page104_i94
#CELL
  mstr_discrete res *
  page104_i96
#CELL
  mstr_discrete res *
  page104_i97
#ISCELL
  mstr_standard offpage *
  page104_i99
#ISCELL
  mstr_symbols cad_note *
  *
#ISCELL
  mstr_symbols intel_corp_bpage *
  *
#CELL
  mstr_discrete cap *
  page105_i1
#ISCELL
  mstr_standard tap *
  page105_i10
#ISCELL
  mstr_standard tap *
  page105_i11
#CELL
  mstr_discrete cap *
  page105_i12
#CELL
  mstr_discrete cap *
  page105_i13
#ISCELL
  mstr_standard tap *
  page105_i14
#ISCELL
  mstr_standard tap *
  page105_i15
#ISCELL
  mstr_standard tap *
  page105_i151
#ISCELL
  mstr_standard tap *
  page105_i152
#CELL
  mstr_discrete cap *
  page105_i153
#ISCELL
  mstr_standard tap *
  page105_i154
#ISCELL
  mstr_standard tap *
  page105_i155
#ISCELL
  mstr_standard tap *
  page105_i156
#ISCELL
  mstr_standard tap *
  page105_i157
#ISCELL
  mstr_standard tap *
  page105_i158
#ISCELL
  mstr_standard tap *
  page105_i159
#ISCELL
  mstr_standard tap *
  page105_i16
#CELL
  mstr_discrete cap *
  page105_i160
#ISCELL
  mstr_standard tap *
  page105_i161
#ISCELL
  mstr_standard tap *
  page105_i162
#CELL
  mstr_discrete cap *
  page105_i163
#ISCELL
  mstr_standard tap *
  page105_i164
#ISCELL
  mstr_standard tap *
  page105_i165
#CELL
  mstr_discrete cap *
  page105_i166
#ISCELL
  mstr_standard tap *
  page105_i167
#ISCELL
  mstr_standard tap *
  page105_i168
#CELL
  mstr_discrete cap *
  page105_i169
#ISCELL
  mstr_standard tap *
  page105_i17
#ISCELL
  mstr_standard tap *
  page105_i170
#ISCELL
  mstr_standard offpage *
  page105_i171
#ISCELL
  mstr_standard tap *
  page105_i172
#CELL
  mstr_discrete cap *
  page105_i173
#ISCELL
  mstr_standard tap *
  page105_i174
#CELL
  mstr_discrete cap *
  page105_i175
#ISCELL
  mstr_standard tap *
  page105_i176
#ISCELL
  mstr_standard tap *
  page105_i177
#ISCELL
  mstr_standard tap *
  page105_i178
#ISCELL
  mstr_standard tap *
  page105_i179
#ISCELL
  mstr_standard tap *
  page105_i18
#CELL
  mstr_discrete cap *
  page105_i180
#CELL
  mstr_discrete cap *
  page105_i181
#ISCELL
  mstr_standard tap *
  page105_i182
#ISCELL
  mstr_standard tap *
  page105_i183
#ISCELL
  mstr_standard tap *
  page105_i184
#CELL
  mstr_discrete cap *
  page105_i185
#ISCELL
  mstr_standard tap *
  page105_i186
#CELL
  mstr_discrete cap *
  page105_i187
#ISCELL
  mstr_standard tap *
  page105_i188
#CELL
  mstr_discrete cap *
  page105_i189
#ISCELL
  mstr_standard tap *
  page105_i19
#ISCELL
  mstr_standard tap *
  page105_i190
#ISCELL
  mstr_standard tap *
  page105_i191
#ISCELL
  mstr_standard tap *
  page105_i192
#CELL
  mstr_discrete cap *
  page105_i193
#ISCELL
  mstr_standard tap *
  page105_i194
#ISCELL
  mstr_standard tap *
  page105_i195
#CELL
  mstr_discrete cap *
  page105_i196
#ISCELL
  mstr_standard tap *
  page105_i197
#CELL
  mstr_discrete cap *
  page105_i198
#ISCELL
  mstr_standard offpage *
  page105_i199
#CELL
  mstr_discrete cap *
  page105_i20
#ISCELL
  mstr_standard tap *
  page105_i200
#CELL
  mstr_discrete cap *
  page105_i201
#ISCELL
  mstr_standard tap *
  page105_i202
#ISCELL
  mstr_standard offpage *
  page105_i203
#ISCELL
  mstr_standard offpage *
  page105_i204
#CELL
  mstr_discrete cap *
  page105_i205
#CELL
  mstr_discrete cap *
  page105_i206
#ISCELL
  mstr_standard offpage *
  page105_i207
#ISCELL
  mstr_standard offpage *
  page105_i208
#ISCELL
  mstr_standard tap *
  page105_i209
#CELL
  mstr_discrete cap *
  page105_i21
#ISCELL
  mstr_standard tap *
  page105_i210
#ISCELL
  mstr_standard tap *
  page105_i211
#CELL
  mstr_discrete cap *
  page105_i212
#ISCELL
  mstr_standard tap *
  page105_i213
#ISCELL
  mstr_standard tap *
  page105_i214
#ISCELL
  mstr_standard tap *
  page105_i215
#ISCELL
  mstr_standard tap *
  page105_i216
#CELL
  mstr_discrete cap *
  page105_i217
#CELL
  mstr_discrete cap *
  page105_i218
#ISCELL
  mstr_standard tap *
  page105_i219
#CELL
  mstr_discrete cap *
  page105_i22
#ISCELL
  mstr_standard tap *
  page105_i220
#ISCELL
  mstr_standard tap *
  page105_i221
#ISCELL
  mstr_standard tap *
  page105_i222
#CELL
  mstr_discrete cap *
  page105_i223
#ISCELL
  mstr_standard tap *
  page105_i224
#CELL
  mstr_discrete cap *
  page105_i225
#ISCELL
  mstr_standard tap *
  page105_i226
#ISCELL
  mstr_standard tap *
  page105_i227
#ISCELL
  mstr_standard tap *
  page105_i228
#CELL
  mstr_discrete cap *
  page105_i229
#ISCELL
  mstr_standard tap *
  page105_i23
#ISCELL
  mstr_standard tap *
  page105_i230
#ISCELL
  mstr_standard tap *
  page105_i231
#CELL
  mstr_discrete cap *
  page105_i232
#ISCELL
  mstr_standard tap *
  page105_i233
#CELL
  mstr_discrete cap *
  page105_i234
#ISCELL
  mstr_standard tap *
  page105_i235
#ISCELL
  mstr_standard tap *
  page105_i236
#ISCELL
  mstr_standard offpage *
  page105_i237
#ISCELL
  mstr_standard tap *
  page105_i238
#CELL
  mstr_discrete cap *
  page105_i239
#ISCELL
  mstr_standard tap *
  page105_i24
#ISCELL
  mstr_standard tap *
  page105_i240
#ISCELL
  mstr_standard tap *
  page105_i241
#ISCELL
  mstr_standard tap *
  page105_i242
#ISCELL
  mstr_standard tap *
  page105_i243
#CELL
  mstr_discrete cap *
  page105_i244
#ISCELL
  mstr_standard tap *
  page105_i245
#CELL
  mstr_discrete cap *
  page105_i246
#CELL
  mstr_discrete cap *
  page105_i247
#ISCELL
  mstr_standard tap *
  page105_i248
#ISCELL
  mstr_standard offpage *
  page105_i249
#ISCELL
  mstr_standard tap *
  page105_i25
#ISCELL
  mstr_standard tap *
  page105_i250
#ISCELL
  mstr_standard tap *
  page105_i251
#ISCELL
  mstr_standard tap *
  page105_i252
#CELL
  mstr_discrete cap *
  page105_i253
#ISCELL
  mstr_standard tap *
  page105_i254
#CELL
  mstr_discrete cap *
  page105_i255
#ISCELL
  mstr_standard tap *
  page105_i256
#CELL
  mstr_discrete cap *
  page105_i257
#CELL
  mstr_discrete cap *
  page105_i258
#ISCELL
  mstr_standard tap *
  page105_i26
#CELL
  mstr_discrete cap *
  page105_i27
#CELL
  mstr_discrete cap *
  page105_i28
#ISCELL
  mstr_standard tap *
  page105_i29
#ISCELL
  mstr_standard offpage *
  page105_i3
#ISCELL
  mstr_standard tap *
  page105_i30
#CELL
  mstr_discrete cap *
  page105_i31
#CELL
  mstr_discrete cap *
  page105_i32
#ISCELL
  mstr_standard tap *
  page105_i33
#ISCELL
  mstr_standard tap *
  page105_i35
#ISCELL
  mstr_standard tap *
  page105_i36
#CELL
  mstr_discrete cap *
  page105_i37
#ISCELL
  mstr_standard tap *
  page105_i38
#ISCELL
  mstr_standard tap *
  page105_i39
#ISCELL
  mstr_standard tap *
  page105_i4
#ISCELL
  mstr_standard tap *
  page105_i40
#ISCELL
  mstr_standard tap *
  page105_i41
#ISCELL
  mstr_standard tap *
  page105_i42
#ISCELL
  mstr_standard tap *
  page105_i43
#CELL
  mstr_discrete cap *
  page105_i44
#CELL
  mstr_discrete cap *
  page105_i45
#ISCELL
  mstr_standard tap *
  page105_i47
#ISCELL
  mstr_standard tap *
  page105_i48
#ISCELL
  mstr_standard tap *
  page105_i49
#ISCELL
  mstr_standard tap *
  page105_i5
#ISCELL
  mstr_standard tap *
  page105_i50
#CELL
  mstr_discrete cap *
  page105_i51
#CELL
  mstr_discrete cap *
  page105_i52
#ISCELL
  mstr_standard tap *
  page105_i53
#ISCELL
  mstr_standard tap *
  page105_i54
#CELL
  mstr_discrete cap *
  page105_i55
#CELL
  mstr_discrete cap *
  page105_i56
#ISCELL
  mstr_standard tap *
  page105_i57
#CELL
  mstr_discrete cap *
  page105_i58
#ISCELL
  mstr_standard tap *
  page105_i59
#CELL
  mstr_discrete cap *
  page105_i6
#ISCELL
  mstr_standard tap *
  page105_i60
#CELL
  mstr_discrete cap *
  page105_i61
#CELL
  mstr_discrete cap *
  page105_i62
#ISCELL
  mstr_standard tap *
  page105_i63
#ISCELL
  mstr_standard tap *
  page105_i64
#ISCELL
  mstr_standard tap *
  page105_i65
#ISCELL
  mstr_standard tap *
  page105_i66
#ISCELL
  mstr_standard tap *
  page105_i67
#ISCELL
  mstr_standard tap *
  page105_i68
#CELL
  mstr_discrete cap *
  page105_i69
#CELL
  mstr_discrete cap *
  page105_i7
#CELL
  mstr_discrete cap *
  page105_i70
#CELL
  mstr_discrete cap *
  page105_i71
#ISCELL
  mstr_standard tap *
  page105_i72
#ISCELL
  mstr_standard tap *
  page105_i73
#ISCELL
  mstr_standard tap *
  page105_i74
#CELL
  mstr_discrete cap *
  page105_i75
#CELL
  mstr_discrete cap *
  page105_i76
#ISCELL
  mstr_standard offpage *
  page105_i77
#ISCELL
  mstr_standard tap *
  page105_i78
#ISCELL
  mstr_standard tap *
  page105_i79
#CELL
  mstr_discrete cap *
  page105_i8
#ISCELL
  mstr_standard tap *
  page105_i80
#ISCELL
  mstr_standard tap *
  page105_i81
#ISCELL
  mstr_standard tap *
  page105_i82
#ISCELL
  mstr_standard tap *
  page105_i83
#ISCELL
  mstr_standard tap *
  page105_i84
#ISCELL
  mstr_standard tap *
  page105_i85
#ISCELL
  mstr_standard tap *
  page105_i86
#ISCELL
  mstr_standard tap *
  page105_i87
#ISCELL
  mstr_standard tap *
  page105_i88
#ISCELL
  mstr_standard tap *
  page105_i89
#ISCELL
  mstr_standard tap *
  page105_i9
#ISCELL
  mstr_standard tap *
  page105_i90
#ISCELL
  mstr_standard tap *
  page105_i91
#ISCELL
  mstr_standard tap *
  page105_i92
#CELL
  mstr_discrete cap *
  page105_i93
#ISCELL
  mstr_standard tap *
  page105_i94
#ISCELL
  mstr_standard offpage *
  page105_i95
#CELL
  mstr_discrete cap *
  page105_i96
#ISCELL
  mstr_standard tap *
  page105_i97
#ISCELL
  mstr_standard tap *
  page105_i98
#ISCELL
  mstr_standard offpage *
  page105_i99
#ISCELL
  mstr_symbols cad_note *
  *
#ISCELL
  mstr_symbols intel_corp_bpage *
  *
#CELL
  mstr_discrete cap *
  page106_i10
#CELL
  mstr_discrete cap *
  page106_i100
#ISCELL
  mstr_standard tap *
  page106_i101
#CELL
  mstr_discrete cap *
  page106_i102
#ISCELL
  mstr_standard tap *
  page106_i103
#ISCELL
  mstr_standard tap *
  page106_i104
#CELL
  mstr_discrete cap *
  page106_i105
#ISCELL
  mstr_standard tap *
  page106_i106
#ISCELL
  mstr_standard offpage *
  page106_i107
#ISCELL
  mstr_standard tap *
  page106_i108
#CELL
  mstr_discrete cap *
  page106_i109
#ISCELL
  mstr_standard tap *
  page106_i11
#ISCELL
  mstr_standard tap *
  page106_i110
#CELL
  mstr_discrete cap *
  page106_i111
#ISCELL
  mstr_standard tap *
  page106_i112
#ISCELL
  mstr_standard tap *
  page106_i113
#CELL
  mstr_discrete cap *
  page106_i114
#ISCELL
  mstr_standard tap *
  page106_i115
#ISCELL
  mstr_standard tap *
  page106_i116
#CELL
  mstr_discrete cap *
  page106_i117
#ISCELL
  mstr_standard tap *
  page106_i118
#ISCELL
  mstr_standard tap *
  page106_i119
#ISCELL
  mstr_standard offpage *
  page106_i120
#ISCELL
  mstr_standard tap *
  page106_i121
#CELL
  mstr_discrete cap *
  page106_i122
#CELL
  mstr_discrete cap *
  page106_i123
#ISCELL
  mstr_standard tap *
  page106_i124
#ISCELL
  mstr_standard tap *
  page106_i125
#ISCELL
  mstr_standard tap *
  page106_i126
#ISCELL
  mstr_standard tap *
  page106_i127
#CELL
  mstr_discrete cap *
  page106_i128
#ISCELL
  mstr_standard tap *
  page106_i129
#CELL
  mstr_discrete cap *
  page106_i130
#ISCELL
  mstr_standard tap *
  page106_i131
#ISCELL
  mstr_standard tap *
  page106_i133
#CELL
  mstr_discrete cap *
  page106_i134
#ISCELL
  mstr_standard tap *
  page106_i135
#ISCELL
  mstr_standard tap *
  page106_i136
#CELL
  mstr_discrete cap *
  page106_i137
#ISCELL
  mstr_standard tap *
  page106_i138
#ISCELL
  mstr_standard tap *
  page106_i140
#CELL
  mstr_discrete cap *
  page106_i141
#CELL
  mstr_discrete cap *
  page106_i142
#ISCELL
  mstr_standard tap *
  page106_i143
#ISCELL
  mstr_standard tap *
  page106_i144
#ISCELL
  mstr_standard tap *
  page106_i145
#ISCELL
  mstr_standard tap *
  page106_i146
#CELL
  mstr_discrete cap *
  page106_i147
#ISCELL
  mstr_standard tap *
  page106_i148
#ISCELL
  mstr_standard offpage *
  page106_i151
#ISCELL
  mstr_standard offpage *
  page106_i152
#ISCELL
  mstr_standard tap *
  page106_i25
#CELL
  mstr_discrete cap *
  page106_i26
#ISCELL
  mstr_standard tap *
  page106_i27
#ISCELL
  mstr_standard tap *
  page106_i28
#CELL
  mstr_discrete cap *
  page106_i29
#ISCELL
  mstr_standard tap *
  page106_i30
#ISCELL
  mstr_standard tap *
  page106_i36
#CELL
  mstr_discrete cap *
  page106_i37
#ISCELL
  mstr_standard tap *
  page106_i38
#ISCELL
  mstr_standard tap *
  page106_i39
#CELL
  mstr_discrete cap *
  page106_i40
#ISCELL
  mstr_standard tap *
  page106_i41
#ISCELL
  mstr_standard tap *
  page106_i54
#CELL
  mstr_discrete cap *
  page106_i55
#ISCELL
  mstr_standard tap *
  page106_i56
#ISCELL
  mstr_standard tap *
  page106_i58
#CELL
  mstr_discrete cap *
  page106_i59
#ISCELL
  mstr_standard tap *
  page106_i60
#ISCELL
  mstr_standard tap *
  page106_i69
#CELL
  mstr_discrete cap *
  page106_i70
#ISCELL
  mstr_standard tap *
  page106_i72
#ISCELL
  mstr_standard tap *
  page106_i73
#ISCELL
  mstr_standard tap *
  page106_i74
#ISCELL
  mstr_standard tap *
  page106_i75
#CELL
  mstr_discrete cap *
  page106_i76
#ISCELL
  mstr_standard tap *
  page106_i77
#CELL
  mstr_discrete cap *
  page106_i78
#ISCELL
  mstr_standard tap *
  page106_i79
#ISCELL
  mstr_standard tap *
  page106_i80
#ISCELL
  mstr_standard tap *
  page106_i81
#CELL
  mstr_discrete cap *
  page106_i82
#ISCELL
  mstr_standard tap *
  page106_i83
#ISCELL
  mstr_standard tap *
  page106_i84
#CELL
  mstr_discrete cap *
  page106_i85
#CELL
  mstr_discrete cap *
  page106_i86
#ISCELL
  mstr_standard tap *
  page106_i87
#ISCELL
  mstr_standard tap *
  page106_i88
#ISCELL
  mstr_standard tap *
  page106_i89
#ISCELL
  mstr_standard tap *
  page106_i9
#CELL
  mstr_discrete cap *
  page106_i90
#ISCELL
  mstr_standard tap *
  page106_i91
#CELL
  mstr_discrete cap *
  page106_i92
#ISCELL
  mstr_standard tap *
  page106_i93
#ISCELL
  mstr_standard tap *
  page106_i94
#CELL
  mstr_discrete cap *
  page106_i95
#ISCELL
  mstr_standard tap *
  page106_i96
#ISCELL
  mstr_standard tap *
  page106_i97
#ISCELL
  mstr_standard tap *
  page106_i98
#ISCELL
  mstr_standard tap *
  page106_i99
#ISCELL
  mstr_symbols bom_note *
  *
#ISCELL
  mstr_symbols cad_note *
  *
#ISCELL
  mstr_symbols intel_corp_bpage *
  *
#ISCELL
  mstr_standard tap *
  page107_i198
#ISCELL
  mstr_standard tap *
  page107_i199
#ISCELL
  mstr_standard tap *
  page107_i200
#ISCELL
  mstr_standard tap *
  page107_i201
#ISCELL
  mstr_standard tap *
  page107_i202
#ISCELL
  mstr_standard tap *
  page107_i203
#ISCELL
  mstr_standard tap *
  page107_i204
#ISCELL
  mstr_standard tap *
  page107_i205
#ISCELL
  mstr_standard offpage *
  page107_i206
#CELL
  mstr_discrete cap *
  page107_i207
#CELL
  mstr_discrete cap *
  page107_i208
#ISCELL
  mstr_standard offpage *
  page107_i209
#ISCELL
  mstr_standard tap *
  page107_i210
#ISCELL
  mstr_standard tap *
  page107_i211
#CELL
  mstr_discrete cap *
  page107_i212
#ISCELL
  mstr_standard tap *
  page107_i213
#ISCELL
  mstr_standard tap *
  page107_i214
#CELL
  mstr_discrete cap *
  page107_i215
#CELL
  mstr_discrete cap *
  page107_i216
#ISCELL
  mstr_standard tap *
  page107_i217
#ISCELL
  mstr_standard tap *
  page107_i218
#CELL
  mstr_discrete cap *
  page107_i219
#ISCELL
  mstr_standard tap *
  page107_i220
#ISCELL
  mstr_standard tap *
  page107_i221
#ISCELL
  mstr_standard tap *
  page107_i222
#CELL
  mstr_discrete cap *
  page107_i223
#ISCELL
  mstr_standard tap *
  page107_i224
#ISCELL
  mstr_standard offpage *
  page107_i225
#CELL
  mstr_discrete cap *
  page107_i226
#ISCELL
  mstr_standard tap *
  page107_i227
#ISCELL
  mstr_standard tap *
  page107_i228
#CELL
  mstr_discrete cap *
  page107_i229
#ISCELL
  mstr_standard tap *
  page107_i230
#ISCELL
  mstr_standard tap *
  page107_i231
#CELL
  mstr_discrete cap *
  page107_i232
#ISCELL
  mstr_standard tap *
  page107_i233
#CELL
  mstr_discrete cap *
  page107_i234
#CELL
  mstr_discrete cap *
  page107_i235
#ISCELL
  mstr_standard tap *
  page107_i236
#ISCELL
  mstr_standard tap *
  page107_i237
#ISCELL
  mstr_standard tap *
  page107_i238
#ISCELL
  mstr_standard tap *
  page107_i239
#CELL
  mstr_discrete cap *
  page107_i240
#CELL
  mstr_discrete cap *
  page107_i241
#ISCELL
  mstr_standard tap *
  page107_i242
#ISCELL
  mstr_standard tap *
  page107_i243
#ISCELL
  mstr_standard offpage *
  page107_i244
#CELL
  mstr_discrete cap *
  page107_i245
#ISCELL
  mstr_standard tap *
  page107_i246
#ISCELL
  mstr_standard tap *
  page107_i247
#CELL
  mstr_discrete cap *
  page107_i248
#ISCELL
  mstr_standard tap *
  page107_i249
#ISCELL
  mstr_standard tap *
  page107_i250
#ISCELL
  mstr_standard tap *
  page107_i251
#ISCELL
  mstr_standard tap *
  page107_i252
#ISCELL
  mstr_standard tap *
  page107_i253
#ISCELL
  mstr_standard tap *
  page107_i254
#ISCELL
  mstr_standard offpage *
  page107_i255
#ISCELL
  mstr_standard offpage *
  page107_i256
#CELL
  mstr_discrete cap *
  page107_i257
#ISCELL
  mstr_standard tap *
  page107_i258
#ISCELL
  mstr_standard tap *
  page107_i259
#CELL
  mstr_discrete cap *
  page107_i260
#ISCELL
  mstr_standard tap *
  page107_i261
#ISCELL
  mstr_standard tap *
  page107_i262
#ISCELL
  mstr_standard tap *
  page107_i263
#CELL
  mstr_discrete cap *
  page107_i264
#CELL
  mstr_discrete cap *
  page107_i265
#ISCELL
  mstr_standard tap *
  page107_i266
#CELL
  mstr_discrete cap *
  page107_i267
#ISCELL
  mstr_standard tap *
  page107_i268
#ISCELL
  mstr_standard tap *
  page107_i269
#ISCELL
  mstr_standard tap *
  page107_i270
#ISCELL
  mstr_standard tap *
  page107_i271
#CELL
  mstr_discrete cap *
  page107_i272
#ISCELL
  mstr_standard tap *
  page107_i273
#CELL
  mstr_discrete cap *
  page107_i274
#ISCELL
  mstr_standard tap *
  page107_i275
#ISCELL
  mstr_standard tap *
  page107_i276
#CELL
  mstr_discrete cap *
  page107_i277
#CELL
  mstr_discrete cap *
  page107_i278
#CELL
  mstr_discrete cap *
  page107_i279
#ISCELL
  mstr_standard tap *
  page107_i280
#ISCELL
  mstr_standard tap *
  page107_i281
#ISCELL
  mstr_standard tap *
  page107_i282
#ISCELL
  mstr_standard tap *
  page107_i283
#ISCELL
  mstr_standard tap *
  page107_i284
#ISCELL
  mstr_standard offpage *
  page107_i285
#CELL
  mstr_discrete cap *
  page107_i286
#CELL
  mstr_discrete cap *
  page107_i287
#ISCELL
  mstr_standard tap *
  page107_i288
#ISCELL
  mstr_standard tap *
  page107_i289
#ISCELL
  mstr_standard tap *
  page107_i290
#ISCELL
  mstr_standard tap *
  page107_i291
#ISCELL
  mstr_standard tap *
  page107_i292
#ISCELL
  mstr_standard tap *
  page107_i293
#CELL
  mstr_discrete cap *
  page107_i294
#ISCELL
  mstr_standard offpage *
  page107_i295
#CELL
  mstr_discrete cap *
  page107_i296
#CELL
  mstr_discrete cap *
  page107_i297
#ISCELL
  mstr_standard tap *
  page107_i298
#ISCELL
  mstr_standard tap *
  page107_i299
#CELL
  mstr_discrete cap *
  page107_i300
#ISCELL
  mstr_standard tap *
  page107_i301
#ISCELL
  mstr_standard tap *
  page107_i355
#ISCELL
  mstr_standard tap *
  page107_i356
#ISCELL
  mstr_standard tap *
  page107_i357
#ISCELL
  mstr_standard tap *
  page107_i359
#ISCELL
  mstr_standard tap *
  page107_i360
#ISCELL
  mstr_standard tap *
  page107_i361
#ISCELL
  mstr_standard tap *
  page107_i363
#ISCELL
  mstr_standard tap *
  page107_i365
#ISCELL
  mstr_standard offpage *
  page107_i366
#ISCELL
  mstr_standard tap *
  page107_i367
#ISCELL
  mstr_standard offpage *
  page107_i368
#ISCELL
  mstr_standard offpage *
  page107_i369
#ISCELL
  mstr_standard tap *
  page107_i371
#ISCELL
  mstr_standard tap *
  page107_i372
#ISCELL
  mstr_standard tap *
  page107_i373
#ISCELL
  mstr_standard tap *
  page107_i375
#ISCELL
  mstr_standard tap *
  page107_i376
#ISCELL
  mstr_standard tap *
  page107_i379
#ISCELL
  mstr_standard tap *
  page107_i380
#ISCELL
  mstr_standard tap *
  page107_i382
#ISCELL
  mstr_standard tap *
  page107_i383
#ISCELL
  mstr_standard tap *
  page107_i384
#ISCELL
  mstr_standard tap *
  page107_i386
#ISCELL
  mstr_standard tap *
  page107_i388
#ISCELL
  mstr_standard tap *
  page107_i389
#ISCELL
  mstr_standard tap *
  page107_i391
#ISCELL
  mstr_standard tap *
  page107_i392
#ISCELL
  mstr_standard tap *
  page107_i393
#ISCELL
  mstr_standard tap *
  page107_i395
#ISCELL
  mstr_standard tap *
  page107_i396
#ISCELL
  mstr_standard tap *
  page107_i397
#ISCELL
  mstr_standard tap *
  page107_i399
#ISCELL
  mstr_standard offpage *
  page107_i400
#ISCELL
  mstr_standard tap *
  page107_i402
#ISCELL
  mstr_standard tap *
  page107_i403
#ISCELL
  mstr_standard tap *
  page107_i405
#ISCELL
  mstr_standard tap *
  page107_i406
#ISCELL
  mstr_standard tap *
  page107_i407
#ISCELL
  mstr_standard tap *
  page107_i408
#ISCELL
  mstr_standard tap *
  page107_i409
#ISCELL
  mstr_standard tap *
  page107_i410
#ISCELL
  mstr_standard tap *
  page107_i411
#ISCELL
  mstr_standard tap *
  page107_i412
#ISCELL
  mstr_standard tap *
  page107_i413
#ISCELL
  mstr_standard tap *
  page107_i414
#ISCELL
  mstr_standard offpage *
  page107_i416
#ISCELL
  mstr_standard tap *
  page107_i418
#ISCELL
  mstr_standard tap *
  page107_i419
#ISCELL
  mstr_standard tap *
  page107_i420
#ISCELL
  mstr_standard tap *
  page107_i421
#ISCELL
  mstr_standard tap *
  page107_i425
#ISCELL
  mstr_standard tap *
  page107_i426
#ISCELL
  mstr_standard tap *
  page107_i428
#ISCELL
  mstr_standard tap *
  page107_i429
#ISCELL
  mstr_standard tap *
  page107_i430
#ISCELL
  mstr_standard tap *
  page107_i432
#ISCELL
  mstr_standard offpage *
  page107_i433
#ISCELL
  mstr_standard tap *
  page107_i434
#ISCELL
  mstr_standard tap *
  page107_i436
#ISCELL
  mstr_standard tap *
  page107_i440
#ISCELL
  mstr_standard tap *
  page107_i441
#ISCELL
  mstr_standard tap *
  page107_i442
#ISCELL
  mstr_standard tap *
  page107_i443
#ISCELL
  mstr_standard tap *
  page107_i445
#ISCELL
  mstr_standard tap *
  page107_i446
#ISCELL
  mstr_standard tap *
  page107_i449
#ISCELL
  mstr_standard tap *
  page107_i450
#ISCELL
  mstr_standard tap *
  page107_i451
#ISCELL
  mstr_standard tap *
  page107_i453
#ISCELL
  mstr_standard tap *
  page107_i454
#ISCELL
  mstr_standard offpage *
  page107_i456
#ISCELL
  mstr_standard offpage *
  page107_i457
#CELL
  mstr_discrete cap *
  page107_i474
#CELL
  mstr_discrete cap *
  page107_i475
#CELL
  mstr_discrete cap *
  page107_i476
#CELL
  mstr_discrete cap *
  page107_i477
#CELL
  mstr_discrete cap *
  page107_i478
#CELL
  mstr_discrete cap *
  page107_i479
#CELL
  mstr_discrete cap *
  page107_i480
#CELL
  mstr_discrete cap *
  page107_i481
#CELL
  mstr_discrete cap *
  page107_i482
#CELL
  mstr_discrete cap *
  page107_i483
#CELL
  mstr_discrete cap *
  page107_i484
#CELL
  mstr_discrete cap *
  page107_i485
#CELL
  mstr_discrete cap *
  page107_i486
#CELL
  mstr_discrete cap *
  page107_i487
#CELL
  mstr_discrete cap *
  page107_i488
#CELL
  mstr_discrete cap *
  page107_i489
#CELL
  mstr_discrete res *
  page107_i490
#CELL
  mstr_discrete res *
  page107_i491
#CELL
  mstr_discrete res *
  page107_i492
#CELL
  mstr_discrete res *
  page107_i493
#CELL
  mstr_discrete res *
  page107_i494
#CELL
  mstr_discrete res *
  page107_i495
#CELL
  mstr_discrete res *
  page107_i496
#CELL
  mstr_discrete res *
  page107_i497
#CELL
  mstr_discrete res *
  page107_i498
#CELL
  mstr_discrete res *
  page107_i499
#CELL
  mstr_discrete res *
  page107_i500
#CELL
  mstr_discrete res *
  page107_i501
#CELL
  mstr_discrete res *
  page107_i502
#CELL
  mstr_discrete res *
  page107_i503
#CELL
  mstr_discrete res *
  page107_i504
#CELL
  mstr_discrete res *
  page107_i505
#ISCELL
  mstr_misc dns *
  *
#ISCELL
  mstr_symbols cad_note *
  *
#ISCELL
  mstr_symbols intel_corp_bpage *
  *
#CELL
  dev_discrete cap_a *
  page108_i1
#ISCELL
  mstr_symbols p12v *
  page108_i165
#ISCELL
  mstr_symbols p12v *
  page108_i167
#ISCELL
  mstr_symbols gnd *
  page108_i168
#ISCELL
  mstr_symbols p3v3 *
  page108_i172
#CELL
  mstr_discrete res *
  page108_i173
#ISCELL
  mstr_standard offpage *
  page108_i174
#ISCELL
  mstr_standard offpage *
  page108_i175
#ISCELL
  mstr_standard offpage *
  page108_i176
#CELL
  dev_discrete cap_a *
  page108_i2
#ISCELL
  mstr_symbols gnd *
  page108_i236
#ISCELL
  mstr_symbols p3v3 *
  page108_i238
#ISCELL
  mstr_standard offpage *
  page108_i243
#ISCELL
  mstr_symbols gnd *
  page108_i250
#ISCELL
  mstr_symbols p3v3 *
  page108_i251
#ISCELL
  mstr_symbols gnd *
  page108_i252
#CELL
  mstr_sconn sconn200_h68296001 *
  page108_i258
#ISCELL
  mstr_standard offpage *
  page108_i259
#ISCELL
  mstr_standard offpage *
  page108_i260
#ISCELL
  mstr_standard offpage *
  page108_i261
#ISCELL
  mstr_symbols p3v3_stby *
  page108_i262
#ISCELL
  mstr_standard offpage *
  page108_i264
#ISCELL
  mstr_standard offpage *
  page108_i265
#ISCELL
  mstr_standard offpage *
  page108_i266
#ISCELL
  mstr_standard offpage *
  page108_i267
#ISCELL
  mstr_standard offpage *
  page108_i269
#ISCELL
  mstr_standard offpage *
  page108_i270
#ISCELL
  mstr_standard tap *
  page108_i271
#ISCELL
  mstr_standard tap *
  page108_i272
#ISCELL
  mstr_standard tap *
  page108_i273
#ISCELL
  mstr_standard tap *
  page108_i274
#ISCELL
  mstr_standard tap *
  page108_i275
#ISCELL
  mstr_standard tap *
  page108_i276
#ISCELL
  mstr_standard tap *
  page108_i277
#ISCELL
  mstr_standard tap *
  page108_i278
#ISCELL
  mstr_standard tap *
  page108_i279
#ISCELL
  mstr_standard tap *
  page108_i280
#ISCELL
  mstr_standard tap *
  page108_i281
#ISCELL
  mstr_standard tap *
  page108_i282
#ISCELL
  mstr_standard tap *
  page108_i283
#ISCELL
  mstr_standard tap *
  page108_i284
#ISCELL
  mstr_standard tap *
  page108_i285
#ISCELL
  mstr_standard tap *
  page108_i286
#ISCELL
  mstr_standard offpage *
  page108_i287
#ISCELL
  mstr_standard offpage *
  page108_i288
#ISCELL
  mstr_standard offpage *
  page108_i289
#ISCELL
  mstr_standard offpage *
  page108_i290
#ISCELL
  mstr_standard offpage *
  page108_i291
#ISCELL
  mstr_standard offpage *
  page108_i292
#ISCELL
  mstr_standard offpage *
  page108_i293
#ISCELL
  mstr_standard offpage *
  page108_i294
#ISCELL
  mstr_standard tap *
  page108_i295
#ISCELL
  mstr_standard tap *
  page108_i296
#ISCELL
  mstr_standard tap *
  page108_i297
#ISCELL
  mstr_standard tap *
  page108_i298
#ISCELL
  mstr_standard tap *
  page108_i299
#ISCELL
  mstr_standard tap *
  page108_i300
#ISCELL
  mstr_standard tap *
  page108_i301
#ISCELL
  mstr_standard tap *
  page108_i302
#ISCELL
  mstr_standard tap *
  page108_i303
#ISCELL
  mstr_standard tap *
  page108_i304
#ISCELL
  mstr_standard tap *
  page108_i305
#ISCELL
  mstr_standard tap *
  page108_i306
#ISCELL
  mstr_standard offpage *
  page108_i310
#ISCELL
  mstr_standard offpage *
  page108_i314
#CELL
  dev_discrete cap_a *
  page108_i315
#ISCELL
  mstr_symbols gnd *
  page108_i316
#CELL
  dev_discrete cap_a *
  page108_i318
#ISCELL
  mstr_symbols p3v3_stby *
  page108_i319
#ISCELL
  mstr_standard offpage *
  page108_i323
#ISCELL
  mstr_standard offpage *
  page108_i324
#ISCELL
  mstr_standard offpage *
  page108_i325
#ISCELL
  mstr_standard offpage *
  page108_i329
#CELL
  mstr_discrete res *
  page108_i330
#ISCELL
  mstr_standard offpage *
  page108_i333
#ISCELL
  mstr_standard offpage *
  page108_i338
#CELL
  mstr_discrete res *
  page108_i339
#CELL
  mstr_discrete res *
  page108_i341
#ISCELL
  mstr_standard offpage *
  page108_i342
#CELL
  mstr_discrete res *
  page108_i343
#ISCELL
  mstr_symbols p3v3 *
  page108_i344
#ISCELL
  mstr_standard tap *
  page108_i345
#ISCELL
  mstr_standard tap *
  page108_i346
#ISCELL
  mstr_standard tap *
  page108_i347
#ISCELL
  mstr_standard offpage *
  page108_i348
#ISCELL
  mstr_standard offpage *
  page108_i349
#CELL
  mstr_discrete res *
  page108_i350
#CELL
  mstr_discrete res *
  page108_i351
#ISCELL
  mstr_standard offpage *
  page108_i352
#ISCELL
  mstr_standard offpage *
  page108_i353
#ISCELL
  mstr_symbols p12v *
  page108_i4
#CELL
  dev_discrete cap_a *
  page108_i5
#CELL
  dev_discrete cap_a *
  page108_i7
#ISCELL
  mstr_symbols intel_corp_bpage *
  *
#ISCELL
  mstr_standard offpage *
  page109_i1
#ISCELL
  mstr_standard tap *
  page109_i10
#ISCELL
  mstr_standard tap *
  page109_i11
#ISCELL
  mstr_standard tap *
  page109_i12
#ISCELL
  mstr_standard tap *
  page109_i13
#ISCELL
  mstr_standard tap *
  page109_i14
#ISCELL
  mstr_standard tap *
  page109_i15
#ISCELL
  mstr_standard tap *
  page109_i16
#ISCELL
  mstr_standard tap *
  page109_i17
#ISCELL
  mstr_standard tap *
  page109_i18
#ISCELL
  mstr_standard tap *
  page109_i19
#ISCELL
  mstr_standard offpage *
  page109_i2
#ISCELL
  mstr_standard tap *
  page109_i20
#ISCELL
  mstr_standard tap *
  page109_i21
#ISCELL
  mstr_standard tap *
  page109_i22
#ISCELL
  mstr_standard tap *
  page109_i23
#ISCELL
  mstr_symbols gnd *
  page109_i25
#ISCELL
  mstr_symbols gnd *
  page109_i26
#ISCELL
  mstr_standard tap *
  page109_i27
#ISCELL
  mstr_standard tap *
  page109_i28
#ISCELL
  mstr_standard tap *
  page109_i29
#ISCELL
  mstr_standard offpage *
  page109_i3
#ISCELL
  mstr_standard tap *
  page109_i30
#ISCELL
  mstr_standard tap *
  page109_i31
#ISCELL
  mstr_standard tap *
  page109_i32
#ISCELL
  mstr_standard tap *
  page109_i33
#ISCELL
  mstr_standard tap *
  page109_i34
#ISCELL
  mstr_standard tap *
  page109_i36
#ISCELL
  mstr_standard tap *
  page109_i37
#ISCELL
  mstr_standard tap *
  page109_i38
#ISCELL
  mstr_standard tap *
  page109_i39
#ISCELL
  mstr_standard offpage *
  page109_i4
#ISCELL
  mstr_standard tap *
  page109_i41
#ISCELL
  mstr_standard tap *
  page109_i42
#ISCELL
  mstr_standard tap *
  page109_i43
#ISCELL
  mstr_standard tap *
  page109_i44
#ISCELL
  mstr_standard offpage *
  page109_i45
#ISCELL
  mstr_standard offpage *
  page109_i46
#ISCELL
  mstr_standard tap *
  page109_i48
#ISCELL
  mstr_standard offpage *
  page109_i5
#ISCELL
  mstr_standard tap *
  page109_i50
#ISCELL
  mstr_standard tap *
  page109_i51
#ISCELL
  mstr_standard tap *
  page109_i52
#ISCELL
  mstr_standard tap *
  page109_i54
#ISCELL
  mstr_standard tap *
  page109_i55
#ISCELL
  mstr_standard tap *
  page109_i57
#ISCELL
  mstr_standard tap *
  page109_i58
#ISCELL
  mstr_standard tap *
  page109_i6
#ISCELL
  mstr_standard tap *
  page109_i61
#ISCELL
  mstr_standard tap *
  page109_i62
#ISCELL
  mstr_standard tap *
  page109_i63
#ISCELL
  mstr_standard tap *
  page109_i64
#ISCELL
  mstr_standard tap *
  page109_i65
#ISCELL
  mstr_standard tap *
  page109_i66
#ISCELL
  mstr_standard tap *
  page109_i67
#ISCELL
  mstr_standard tap *
  page109_i69
#ISCELL
  mstr_standard tap *
  page109_i7
#ISCELL
  mstr_standard tap *
  page109_i70
#ISCELL
  mstr_standard tap *
  page109_i71
#ISCELL
  mstr_standard tap *
  page109_i72
#ISCELL
  mstr_standard offpage *
  page109_i73
#ISCELL
  mstr_standard offpage *
  page109_i74
#ISCELL
  mstr_standard offpage *
  page109_i75
#ISCELL
  mstr_standard tap *
  page109_i76
#ISCELL
  mstr_standard tap *
  page109_i77
#CELL
  mstr_sconn sconn200_h68296001 *
  page109_i78
#ISCELL
  mstr_standard tap *
  page109_i8
#ISCELL
  mstr_standard tap *
  page109_i80
#ISCELL
  mstr_standard tap *
  page109_i81
#ISCELL
  mstr_standard tap *
  page109_i82
#ISCELL
  mstr_standard tap *
  page109_i83
#ISCELL
  mstr_standard tap *
  page109_i84
#ISCELL
  mstr_standard tap *
  page109_i85
#ISCELL
  mstr_standard tap *
  page109_i86
#ISCELL
  mstr_standard tap *
  page109_i87
#ISCELL
  mstr_standard tap *
  page109_i88
#ISCELL
  mstr_standard tap *
  page109_i89
#ISCELL
  mstr_standard tap *
  page109_i9
#ISCELL
  mstr_symbols intel_corp_bpage *
  *
#ISCELL
  mstr_misc dns *
  *
#ISCELL
  mstr_symbols cad_note *
  *
#ISCELL
  mstr_symbols intel_corp_bpage *
  *
#CELL
  dev_discrete cap_a *
  page111_i10
#CELL
  mstr_discrete res *
  page111_i11
#CELL
  dev_discrete cap_a *
  page111_i12
#CELL
  mstr_discrete res *
  page111_i13
#CELL
  dev_discrete cap_a *
  page111_i14
#ISCELL
  mstr_standard offpage *
  page111_i15
#ISCELL
  mstr_standard offpage *
  page111_i16
#ISCELL
  mstr_standard offpage *
  page111_i17
#ISCELL
  mstr_standard offpage *
  page111_i18
#ISCELL
  mstr_standard offpage *
  page111_i19
#ISCELL
  mstr_standard offpage *
  page111_i2
#ISCELL
  mstr_standard offpage *
  page111_i20
#ISCELL
  mstr_standard offpage *
  page111_i21
#ISCELL
  mstr_standard offpage *
  page111_i22
#ISCELL
  mstr_standard offpage *
  page111_i23
#ISCELL
  mstr_symbols gnd *
  page111_i24
#CELL
  dev_discrete cap_a *
  page111_i25
#CELL
  mstr_sconn sconn60_c21100002 *
  page111_i26
#ISCELL
  mstr_standard offpage *
  page111_i27
#ISCELL
  mstr_standard offpage *
  page111_i28
#CELL
  dev_discrete cap_a *
  page111_i30
#ISCELL
  mstr_standard offpage *
  page111_i31
#ISCELL
  mstr_standard offpage *
  page111_i32
#CELL
  mstr_discrete res *
  page111_i37
#ISCELL
  mstr_standard offpage *
  page111_i38
#ISCELL
  mstr_symbols gnd *
  page111_i39
#ISCELL
  mstr_standard offpage *
  page111_i4
#ISCELL
  mstr_standard offpage *
  page111_i46
#ISCELL
  mstr_standard offpage *
  page111_i47
#ISCELL
  mstr_standard offpage *
  page111_i48
#ISCELL
  mstr_standard offpage *
  page111_i49
#ISCELL
  mstr_standard offpage *
  page111_i50
#ISCELL
  mstr_standard offpage *
  page111_i51
#ISCELL
  mstr_standard offpage *
  page111_i52
#ISCELL
  mstr_symbols pvccio_cpu0 *
  page111_i54
#CELL
  mstr_discrete res *
  page111_i55
#CELL
  mstr_discrete res *
  page111_i56
#CELL
  mstr_discrete res *
  page111_i57
#ISCELL
  mstr_symbols gnd *
  page111_i58
#CELL
  dev_discrete cap_a *
  page111_i59
#CELL
  mstr_discrete res *
  page111_i6
#CELL
  mstr_discrete res *
  page111_i60
#ISCELL
  mstr_standard offpage *
  page111_i61
#ISCELL
  mstr_standard offpage *
  page111_i62
#ISCELL
  mstr_standard offpage *
  page111_i63
#ISCELL
  mstr_standard offpage *
  page111_i64
#ISCELL
  mstr_symbols p3v3_stby *
  page111_i65
#ISCELL
  mstr_symbols p3v3_stby *
  page111_i67
#CELL
  mstr_discrete res *
  page111_i68
#ISCELL
  mstr_symbols p1v05_pch_stby *
  page111_i69
#ISCELL
  mstr_symbols gnd *
  page111_i7
#ISCELL
  mstr_symbols p1v05_pch_stby *
  page111_i70
#ISCELL
  mstr_symbols p1v05_pch_stby *
  page111_i71
#CELL
  mstr_discrete res *
  page111_i74
#ISCELL
  mstr_standard offpage *
  page111_i75
#ISCELL
  mstr_symbols gnd *
  page111_i8
#CELL
  mstr_discrete res *
  page111_i83
#CELL
  mstr_ttl ttl1g07_a *
  page111_i85
#ISCELL
  mstr_symbols p3v3_stby *
  page111_i86
#CELL
  dev_discrete cap_a *
  page111_i87
#ISCELL
  mstr_symbols gnd *
  page111_i88
#CELL
  mstr_discrete res *
  page111_i89
#ISCELL
  mstr_symbols gnd *
  page111_i9
#ISCELL
  mstr_standard offpage *
  page111_i90
#ISCELL
  mstr_standard offpage *
  page111_i91
#ISCELL
  mstr_standard offpage *
  page111_i92
#CELL
  mstr_discrete npn_dual *
  page111_i93
#CELL
  mstr_discrete npn_dual *
  page111_i94
#CELL
  mstr_discrete res *
  page111_i95
#ISCELL
  mstr_symbols p3v3 *
  page111_i96
#CELL
  mstr_discrete res *
  page111_i97
#ISCELL
  mstr_symbols cad_note *
  *
#ISCELL
  mstr_symbols intel_corp_bpage *
  *
#ISCELL
  mstr_standard offpage *
  page112_i100
#ISCELL
  mstr_standard offpage *
  page112_i101
#ISCELL
  mstr_standard offpage *
  page112_i102
#ISCELL
  mstr_standard offpage *
  page112_i103
#ISCELL
  mstr_standard offpage *
  page112_i104
#ISCELL
  mstr_standard offpage *
  page112_i105
#ISCELL
  mstr_standard offpage *
  page112_i106
#ISCELL
  mstr_standard offpage *
  page112_i107
#CELL
  mstr_ttl ttl3126 *
  page112_i108
#CELL
  mstr_ttl ttl3126 *
  page112_i109
#ISCELL
  mstr_standard offpage *
  page112_i110
#ISCELL
  mstr_standard offpage *
  page112_i111
#ISCELL
  mstr_standard offpage *
  page112_i112
#ISCELL
  mstr_standard offpage *
  page112_i113
#ISCELL
  mstr_standard offpage *
  page112_i114
#ISCELL
  mstr_standard offpage *
  page112_i115
#CELL
  mstr_discrete res *
  page112_i120
#CELL
  mstr_discrete res *
  page112_i121
#ISCELL
  mstr_symbols pvccio_cpu0 *
  page112_i122
#ISCELL
  mstr_symbols pvccio_cpu0 *
  page112_i123
#ISCELL
  mstr_symbols p1v05_pch_stby *
  page112_i126
#CELL
  mstr_ttl 74cbtlv1g125 *
  page112_i127
#ISCELL
  mstr_standard offpage *
  page112_i128
#ISCELL
  mstr_standard offpage *
  page112_i129
#ISCELL
  mstr_standard offpage *
  page112_i130
#CELL
  dev_discrete cap_a *
  page112_i131
#ISCELL
  mstr_symbols gnd *
  page112_i133
#ISCELL
  mstr_symbols pvccio_cpu0 *
  page112_i134
#ISCELL
  mstr_symbols pvccio_cpu1 *
  page112_i135
#CELL
  mstr_discrete cap *
  page112_i136
#ISCELL
  mstr_symbols gnd *
  page112_i138
#CELL
  mstr_discrete cap *
  page112_i140
#ISCELL
  mstr_symbols gnd *
  page112_i141
#ISCELL
  mstr_symbols p3v3_stby *
  page112_i143
#ISCELL
  mstr_symbols p3v3_stby *
  page112_i144
#ISCELL
  mstr_standard offpage *
  page112_i145
#ISCELL
  mstr_standard offpage *
  page112_i146
#ISCELL
  mstr_symbols pvccio_cpu0 *
  page112_i147
#ISCELL
  mstr_symbols p3v3_stby *
  page112_i148
#ISCELL
  mstr_symbols p3v3_stby *
  page112_i149
#ISCELL
  mstr_standard offpage *
  page112_i36
#ISCELL
  mstr_symbols gnd *
  page112_i39
#CELL
  mstr_analog nc7sb3157 *
  page112_i40
#ISCELL
  mstr_standard offpage *
  page112_i41
#CELL
  dev_discrete cap_a *
  page112_i42
#CELL
  dev_discrete cap_a *
  page112_i47
#ISCELL
  mstr_symbols gnd *
  page112_i48
#CELL
  mstr_discrete res *
  page112_i49
#CELL
  mstr_discrete res *
  page112_i50
#CELL
  mstr_discrete res *
  page112_i51
#ISCELL
  mstr_symbols pvccio_cpu0 *
  page112_i52
#CELL
  mstr_discrete res *
  page112_i53
#CELL
  mstr_discrete res *
  page112_i54
#CELL
  mstr_discrete res *
  page112_i55
#CELL
  mstr_discrete res *
  page112_i56
#CELL
  mstr_discrete res *
  page112_i57
#CELL
  mstr_discrete res *
  page112_i58
#CELL
  mstr_discrete res *
  page112_i59
#CELL
  mstr_discrete res *
  page112_i60
#CELL
  mstr_discrete res *
  page112_i61
#CELL
  mstr_discrete res *
  page112_i62
#ISCELL
  mstr_standard offpage *
  page112_i63
#ISCELL
  mstr_standard offpage *
  page112_i64
#ISCELL
  mstr_standard offpage *
  page112_i65
#ISCELL
  mstr_standard offpage *
  page112_i66
#ISCELL
  mstr_standard offpage *
  page112_i67
#ISCELL
  mstr_standard offpage *
  page112_i68
#ISCELL
  mstr_standard offpage *
  page112_i69
#ISCELL
  mstr_standard offpage *
  page112_i70
#ISCELL
  mstr_standard offpage *
  page112_i71
#ISCELL
  mstr_standard offpage *
  page112_i72
#ISCELL
  mstr_standard offpage *
  page112_i73
#ISCELL
  mstr_symbols gnd *
  page112_i74
#CELL
  mstr_discrete res *
  page112_i76
#CELL
  mstr_discrete res *
  page112_i77
#CELL
  mstr_discrete res *
  page112_i78
#CELL
  mstr_discrete res *
  page112_i79
#CELL
  mstr_discrete res *
  page112_i80
#ISCELL
  mstr_standard offpage *
  page112_i81
#ISCELL
  mstr_standard offpage *
  page112_i82
#ISCELL
  mstr_standard offpage *
  page112_i83
#ISCELL
  mstr_standard offpage *
  page112_i84
#CELL
  mstr_discrete res *
  page112_i85
#ISCELL
  mstr_standard offpage *
  page112_i86
#ISCELL
  mstr_standard offpage *
  page112_i87
#ISCELL
  mstr_standard offpage *
  page112_i88
#ISCELL
  mstr_standard offpage *
  page112_i89
#ISCELL
  mstr_standard offpage *
  page112_i90
#ISCELL
  mstr_standard offpage *
  page112_i91
#ISCELL
  mstr_standard offpage *
  page112_i92
#ISCELL
  mstr_standard offpage *
  page112_i93
#CELL
  mstr_discrete res *
  page112_i94
#CELL
  mstr_discrete res *
  page112_i95
#ISCELL
  mstr_symbols gnd *
  page112_i96
#ISCELL
  mstr_standard offpage *
  page112_i97
#ISCELL
  mstr_standard offpage *
  page112_i98
#ISCELL
  mstr_standard offpage *
  page112_i99
#ISCELL
  mstr_misc dns *
  *
#ISCELL
  mstr_symbols bom_note *
  *
#ISCELL
  mstr_symbols cad_note *
  *
#ISCELL
  mstr_symbols design_note *
  *
#ISCELL
  mstr_symbols intel_corp_bpage *
  *
#CELL
  mstr_analog nc7sb3157 *
  page113_i107
#ISCELL
  mstr_symbols gnd *
  page113_i109
#ISCELL
  mstr_symbols gnd *
  page113_i110
#ISCELL
  mstr_standard offpage *
  page113_i111
#ISCELL
  mstr_standard offpage *
  page113_i112
#ISCELL
  mstr_standard offpage *
  page113_i113
#CELL
  dev_discrete cap_a *
  page113_i116
#CELL
  dev_discrete cap_a *
  page113_i117
#ISCELL
  mstr_symbols gnd *
  page113_i118
#CELL
  dev_discrete cap_a *
  page113_i119
#ISCELL
  mstr_symbols gnd *
  page113_i121
#ISCELL
  mstr_standard offpage *
  page113_i124
#ISCELL
  mstr_standard offpage *
  page113_i126
#CELL
  mstr_ttl 74cbtlv1g125 *
  page113_i127
#ISCELL
  mstr_standard offpage *
  page113_i128
#ISCELL
  mstr_standard offpage *
  page113_i143
#ISCELL
  mstr_symbols gnd *
  page113_i146
#CELL
  dev_discrete cap_a *
  page113_i147
#ISCELL
  mstr_standard offpage *
  page113_i153
#ISCELL
  mstr_standard offpage *
  page113_i154
#ISCELL
  mstr_standard offpage *
  page113_i155
#ISCELL
  mstr_symbols p3v3_stby *
  page113_i160
#ISCELL
  mstr_symbols p3v3_stby *
  page113_i161
#ISCELL
  mstr_standard offpage *
  page113_i162
#ISCELL
  mstr_standard offpage *
  page113_i163
#CELL
  mstr_discrete res *
  page113_i168
#ISCELL
  mstr_standard offpage *
  page113_i169
#ISCELL
  mstr_symbols vcc_core *
  page113_i171
#ISCELL
  mstr_standard offpage *
  page113_i172
#CELL
  mstr_sconn sconn10_c12536004 *
  page113_i175
#ISCELL
  mstr_standard offpage *
  page113_i176
#CELL
  mstr_discrete res *
  page113_i179
#CELL
  mstr_discrete res *
  page113_i180
#ISCELL
  mstr_symbols gnd *
  page113_i182
#CELL
  mstr_ttl 74cbtlv1g125 *
  page113_i185
#ISCELL
  mstr_symbols gnd *
  page113_i186
#CELL
  mstr_ttl 74cbtlv1g125 *
  page113_i190
#ISCELL
  mstr_standard offpage *
  page113_i192
#ISCELL
  mstr_standard offpage *
  page113_i193
#CELL
  mstr_discrete res *
  page113_i195
#CELL
  mstr_ttl 74cbtlv1g125 *
  page113_i196
#ISCELL
  mstr_standard offpage *
  page113_i197
#CELL
  mstr_discrete res *
  page113_i199
#ISCELL
  mstr_symbols gnd *
  page113_i200
#ISCELL
  mstr_symbols vcc_core *
  page113_i201
#CELL
  mstr_discrete res *
  page113_i202
#CELL
  mstr_discrete res *
  page113_i203
#CELL
  mstr_discrete res *
  page113_i204
#CELL
  mstr_discrete res *
  page113_i205
#CELL
  mstr_ttl 74cbtlv1g125 *
  page113_i206
#ISCELL
  mstr_standard offpage *
  page113_i212
#ISCELL
  mstr_standard offpage *
  page113_i213
#ISCELL
  mstr_standard offpage *
  page113_i214
#ISCELL
  mstr_standard offpage *
  page113_i215
#ISCELL
  mstr_symbols vcc_core *
  page113_i236
#ISCELL
  mstr_standard offpage *
  page113_i238
#CELL
  mstr_discrete res *
  page113_i239
#CELL
  mstr_discrete res *
  page113_i240
#ISCELL
  mstr_symbols vcc_core *
  page113_i241
#ISCELL
  mstr_standard offpage *
  page113_i242
#ISCELL
  mstr_standard offpage *
  page113_i243
#ISCELL
  mstr_standard offpage *
  page113_i244
#ISCELL
  mstr_symbols vcc_core *
  page113_i245
#CELL
  dev_discrete cap_a *
  page113_i246
#ISCELL
  mstr_symbols gnd *
  page113_i247
#CELL
  dev_discrete cap_a *
  page113_i248
#ISCELL
  mstr_symbols gnd *
  page113_i249
#CELL
  dev_discrete cap_a *
  page113_i250
#ISCELL
  mstr_symbols gnd *
  page113_i251
#CELL
  mstr_analog nc7sb3157 *
  page113_i255
#ISCELL
  mstr_standard offpage *
  page113_i256
#ISCELL
  mstr_standard offpage *
  page113_i257
#ISCELL
  mstr_standard offpage *
  page113_i258
#ISCELL
  mstr_symbols p3v3_stby *
  page113_i259
#ISCELL
  mstr_symbols gnd *
  page113_i261
#ISCELL
  mstr_symbols gnd *
  page113_i263
#ISCELL
  mstr_standard offpage *
  page113_i264
#CELL
  dev_discrete cap_a *
  page113_i265
#CELL
  dev_discrete cap_a *
  page113_i266
#CELL
  dev_discrete cap_a *
  page113_i267
#ISCELL
  mstr_symbols gnd *
  page113_i268
#ISCELL
  mstr_symbols p3v3_stby *
  page113_i269
#CELL
  mstr_discrete res *
  page113_i270
#CELL
  mstr_discrete res *
  page113_i271
#CELL
  mstr_discrete res *
  page113_i272
#CELL
  mstr_discrete res *
  page113_i273
#ISCELL
  mstr_misc dns *
  *
#ISCELL
  mstr_symbols cad_note *
  *
#ISCELL
  mstr_symbols design_note *
  *
#ISCELL
  mstr_symbols intel_corp_bpage *
  *
#ISCELL
  mstr_standard offpage *
  page114_i103
#ISCELL
  mstr_standard offpage *
  page114_i104
#CELL
  mstr_discrete res *
  page114_i110
#CELL
  mstr_discrete res *
  page114_i124
#ISCELL
  mstr_symbols gnd *
  page114_i125
#ISCELL
  mstr_standard offpage *
  page114_i128
#ISCELL
  mstr_standard offpage *
  page114_i129
#ISCELL
  mstr_standard offpage *
  page114_i130
#ISCELL
  mstr_standard offpage *
  page114_i133
#ISCELL
  mstr_standard offpage *
  page114_i138
#ISCELL
  mstr_standard offpage *
  page114_i143
#CELL
  mstr_discrete res *
  page114_i149
#ISCELL
  mstr_symbols gnd *
  page114_i150
#ISCELL
  mstr_standard offpage *
  page114_i166
#ISCELL
  mstr_standard offpage *
  page114_i167
#ISCELL
  mstr_standard offpage *
  page114_i168
#ISCELL
  mstr_standard offpage *
  page114_i169
#ISCELL
  mstr_standard offpage *
  page114_i170
#ISCELL
  mstr_standard offpage *
  page114_i171
#ISCELL
  mstr_standard offpage *
  page114_i172
#ISCELL
  mstr_standard offpage *
  page114_i173
#ISCELL
  mstr_standard offpage *
  page114_i174
#ISCELL
  mstr_standard offpage *
  page114_i175
#ISCELL
  mstr_standard offpage *
  page114_i180
#ISCELL
  mstr_standard offpage *
  page114_i181
#ISCELL
  mstr_standard offpage *
  page114_i182
#ISCELL
  mstr_standard offpage *
  page114_i183
#ISCELL
  mstr_standard offpage *
  page114_i184
#ISCELL
  mstr_standard offpage *
  page114_i185
#ISCELL
  mstr_standard offpage *
  page114_i186
#CELL
  mstr_discrete res *
  page114_i191
#CELL
  mstr_discrete res *
  page114_i192
#CELL
  mstr_discrete cap *
  page114_i193
#ISCELL
  mstr_symbols gnd *
  page114_i194
#CELL
  mstr_discrete cap *
  page114_i195
#CELL
  mstr_discrete cap *
  page114_i196
#ISCELL
  mstr_standard offpage *
  page114_i35
#ISCELL
  mstr_standard offpage *
  page114_i36
#CELL
  mstr_u_proc lbg_core_qat_ext_d *
  page114_i40
#ISCELL
  mstr_standard offpage *
  page114_i43
#ISCELL
  mstr_standard offpage *
  page114_i45
#CELL
  mstr_discrete cap *
  page114_i47
#CELL
  mstr_discrete res *
  page114_i48
#CELL
  mstr_discrete crystal *
  page114_i49
#CELL
  mstr_discrete cap *
  page114_i50
#ISCELL
  mstr_standard offpage *
  page114_i51
#ISCELL
  mstr_symbols gnd *
  page114_i53
#CELL
  mstr_discrete res *
  page114_i54
#CELL
  mstr_discrete crystal *
  page114_i55
#ISCELL
  mstr_symbols gnd *
  page114_i57
#ISCELL
  mstr_standard offpage *
  page114_i58
#ISCELL
  mstr_standard offpage *
  page114_i59
#ISCELL
  mstr_standard offpage *
  page114_i60
#ISCELL
  mstr_standard offpage *
  page114_i62
#ISCELL
  mstr_standard offpage *
  page114_i63
#ISCELL
  mstr_standard offpage *
  page114_i64
#ISCELL
  mstr_standard offpage *
  page114_i89
#ISCELL
  mstr_standard offpage *
  page114_i90
#ISCELL
  mstr_standard offpage *
  page114_i93
#ISCELL
  mstr_standard offpage *
  page114_i94
#ISCELL
  mstr_standard offpage *
  page114_i95
#ISCELL
  mstr_standard offpage *
  page114_i96
#ISCELL
  mstr_symbols cad_note *
  *
#ISCELL
  mstr_symbols intel_corp_bpage *
  *
#ISCELL
  mstr_standard offpage *
  page115_i106
#ISCELL
  mstr_standard offpage *
  page115_i107
#CELL
  mstr_discrete res *
  page115_i114
#ISCELL
  mstr_symbols gnd *
  page115_i115
#CELL
  mstr_discrete res *
  page115_i118
#CELL
  mstr_discrete res *
  page115_i119
#CELL
  mstr_discrete res *
  page115_i120
#CELL
  mstr_discrete res *
  page115_i121
#CELL
  mstr_discrete res *
  page115_i122
#CELL
  mstr_discrete res *
  page115_i123
#ISCELL
  mstr_standard offpage *
  page115_i124
#ISCELL
  mstr_standard offpage *
  page115_i125
#ISCELL
  mstr_standard offpage *
  page115_i126
#ISCELL
  mstr_standard offpage *
  page115_i127
#ISCELL
  mstr_standard offpage *
  page115_i128
#ISCELL
  mstr_standard offpage *
  page115_i129
#ISCELL
  mstr_standard offpage *
  page115_i130
#ISCELL
  mstr_standard offpage *
  page115_i131
#ISCELL
  mstr_standard offpage *
  page115_i132
#ISCELL
  mstr_standard offpage *
  page115_i133
#CELL
  mstr_u_proc lbg_core_qat_ext_d *
  page115_i74
#CELL
  mstr_discrete res *
  page115_i90
#ISCELL
  mstr_symbols gnd *
  page115_i91
#ISCELL
  mstr_misc dns *
  *
#ISCELL
  mstr_symbols cad_note *
  *
#ISCELL
  mstr_symbols design_note *
  *
#ISCELL
  mstr_symbols intel_corp_bpage *
  *
#ISCELL
  mstr_standard offpage *
  page116_i101
#ISCELL
  mstr_standard offpage *
  page116_i102
#ISCELL
  mstr_standard offpage *
  page116_i103
#ISCELL
  mstr_standard offpage *
  page116_i104
#ISCELL
  mstr_standard offpage *
  page116_i105
#ISCELL
  mstr_standard offpage *
  page116_i106
#ISCELL
  mstr_standard offpage *
  page116_i107
#CELL
  mstr_discrete res *
  page116_i108
#ISCELL
  mstr_standard tap *
  page116_i122
#ISCELL
  mstr_standard tap *
  page116_i123
#ISCELL
  mstr_standard tap *
  page116_i125
#ISCELL
  mstr_standard tap *
  page116_i128
#ISCELL
  mstr_standard tap *
  page116_i129
#ISCELL
  mstr_standard tap *
  page116_i130
#ISCELL
  mstr_standard tap *
  page116_i131
#ISCELL
  mstr_standard tap *
  page116_i132
#ISCELL
  mstr_standard tap *
  page116_i133
#ISCELL
  mstr_standard tap *
  page116_i134
#ISCELL
  mstr_standard tap *
  page116_i135
#ISCELL
  mstr_standard tap *
  page116_i136
#ISCELL
  mstr_standard tap *
  page116_i137
#ISCELL
  mstr_standard tap *
  page116_i138
#ISCELL
  mstr_standard tap *
  page116_i139
#ISCELL
  mstr_standard tap *
  page116_i140
#ISCELL
  mstr_standard tap *
  page116_i141
#ISCELL
  mstr_standard tap *
  page116_i142
#ISCELL
  mstr_standard tap *
  page116_i143
#ISCELL
  mstr_standard tap *
  page116_i144
#ISCELL
  mstr_standard tap *
  page116_i145
#ISCELL
  mstr_standard tap *
  page116_i146
#ISCELL
  mstr_standard tap *
  page116_i147
#ISCELL
  mstr_standard tap *
  page116_i148
#ISCELL
  mstr_standard tap *
  page116_i149
#ISCELL
  mstr_standard tap *
  page116_i150
#ISCELL
  mstr_standard tap *
  page116_i151
#ISCELL
  mstr_standard tap *
  page116_i152
#ISCELL
  mstr_standard tap *
  page116_i153
#ISCELL
  mstr_standard tap *
  page116_i154
#ISCELL
  mstr_standard tap *
  page116_i155
#ISCELL
  mstr_standard tap *
  page116_i156
#CELL
  mstr_discrete res *
  page116_i181
#ISCELL
  mstr_standard offpage *
  page116_i204
#ISCELL
  mstr_standard offpage *
  page116_i205
#ISCELL
  mstr_standard offpage *
  page116_i206
#ISCELL
  mstr_standard offpage *
  page116_i207
#ISCELL
  mstr_standard offpage *
  page116_i208
#ISCELL
  mstr_standard offpage *
  page116_i209
#ISCELL
  mstr_standard offpage *
  page116_i21
#ISCELL
  mstr_standard offpage *
  page116_i210
#ISCELL
  mstr_standard offpage *
  page116_i211
#ISCELL
  mstr_standard offpage *
  page116_i212
#ISCELL
  mstr_standard offpage *
  page116_i213
#ISCELL
  mstr_standard offpage *
  page116_i214
#ISCELL
  mstr_standard offpage *
  page116_i215
#ISCELL
  mstr_standard offpage *
  page116_i216
#ISCELL
  mstr_standard offpage *
  page116_i217
#ISCELL
  mstr_standard offpage *
  page116_i218
#ISCELL
  mstr_standard offpage *
  page116_i219
#CELL
  mstr_u_proc lbg_core_qat_ext_d *
  page116_i220
#ISCELL
  mstr_standard offpage *
  page116_i221
#ISCELL
  mstr_standard offpage *
  page116_i222
#ISCELL
  mstr_standard offpage *
  page116_i223
#ISCELL
  mstr_standard offpage *
  page116_i224
#CELL
  mstr_discrete res *
  page116_i229
#CELL
  mstr_discrete res *
  page116_i230
#ISCELL
  mstr_symbols gnd *
  page116_i231
#ISCELL
  mstr_standard offpage *
  page116_i232
#ISCELL
  mstr_standard offpage *
  page116_i233
#CELL
  mstr_discrete res *
  page116_i234
#CELL
  mstr_discrete res *
  page116_i235
#ISCELL
  mstr_symbols gnd *
  page116_i236
#ISCELL
  mstr_symbols gnd *
  page116_i237
#CELL
  dev_discrete cap_a *
  page116_i238
#CELL
  dev_discrete cap_a *
  page116_i239
#ISCELL
  mstr_standard offpage *
  page116_i26
#ISCELL
  mstr_standard offpage *
  page116_i27
#ISCELL
  mstr_standard offpage *
  page116_i28
#ISCELL
  mstr_standard offpage *
  page116_i29
#ISCELL
  mstr_standard offpage *
  page116_i30
#ISCELL
  mstr_standard offpage *
  page116_i31
#ISCELL
  mstr_standard offpage *
  page116_i32
#ISCELL
  mstr_standard offpage *
  page116_i97
#ISCELL
  mstr_symbols design_note *
  *
#ISCELL
  mstr_symbols intel_corp_bpage *
  *
#ISCELL
  mstr_standard tap *
  page117_i101
#ISCELL
  mstr_standard tap *
  page117_i102
#ISCELL
  mstr_standard tap *
  page117_i103
#ISCELL
  mstr_standard tap *
  page117_i104
#ISCELL
  mstr_standard tap *
  page117_i105
#ISCELL
  mstr_standard tap *
  page117_i106
#ISCELL
  mstr_standard tap *
  page117_i107
#ISCELL
  mstr_standard tap *
  page117_i109
#ISCELL
  mstr_standard tap *
  page117_i110
#ISCELL
  mstr_standard tap *
  page117_i111
#ISCELL
  mstr_standard tap *
  page117_i112
#ISCELL
  mstr_standard tap *
  page117_i113
#ISCELL
  mstr_standard tap *
  page117_i114
#ISCELL
  mstr_standard tap *
  page117_i115
#ISCELL
  mstr_standard tap *
  page117_i116
#ISCELL
  mstr_standard tap *
  page117_i117
#ISCELL
  mstr_standard tap *
  page117_i118
#ISCELL
  mstr_standard tap *
  page117_i119
#ISCELL
  mstr_standard tap *
  page117_i120
#ISCELL
  mstr_standard tap *
  page117_i121
#ISCELL
  mstr_standard tap *
  page117_i122
#ISCELL
  mstr_standard tap *
  page117_i123
#ISCELL
  mstr_standard tap *
  page117_i124
#ISCELL
  mstr_standard tap *
  page117_i125
#ISCELL
  mstr_standard tap *
  page117_i126
#ISCELL
  mstr_standard tap *
  page117_i127
#ISCELL
  mstr_standard tap *
  page117_i128
#ISCELL
  mstr_standard offpage *
  page117_i129
#ISCELL
  mstr_standard offpage *
  page117_i130
#ISCELL
  mstr_standard offpage *
  page117_i131
#ISCELL
  mstr_standard offpage *
  page117_i132
#ISCELL
  mstr_standard tap *
  page117_i133
#ISCELL
  mstr_standard tap *
  page117_i134
#ISCELL
  mstr_standard offpage *
  page117_i18
#ISCELL
  mstr_standard offpage *
  page117_i19
#ISCELL
  mstr_standard tap *
  page117_i21
#ISCELL
  mstr_standard tap *
  page117_i22
#ISCELL
  mstr_standard tap *
  page117_i23
#ISCELL
  mstr_standard tap *
  page117_i24
#ISCELL
  mstr_standard tap *
  page117_i25
#ISCELL
  mstr_standard tap *
  page117_i26
#ISCELL
  mstr_standard tap *
  page117_i27
#ISCELL
  mstr_standard tap *
  page117_i28
#ISCELL
  mstr_standard tap *
  page117_i29
#ISCELL
  mstr_standard tap *
  page117_i30
#ISCELL
  mstr_standard tap *
  page117_i31
#ISCELL
  mstr_standard tap *
  page117_i32
#ISCELL
  mstr_standard tap *
  page117_i33
#ISCELL
  mstr_standard tap *
  page117_i34
#ISCELL
  mstr_standard tap *
  page117_i35
#ISCELL
  mstr_standard tap *
  page117_i36
#ISCELL
  mstr_standard offpage *
  page117_i38
#ISCELL
  mstr_standard offpage *
  page117_i39
#ISCELL
  mstr_standard offpage *
  page117_i40
#ISCELL
  mstr_standard offpage *
  page117_i41
#ISCELL
  mstr_standard tap *
  page117_i42
#ISCELL
  mstr_standard tap *
  page117_i43
#ISCELL
  mstr_standard tap *
  page117_i44
#ISCELL
  mstr_standard tap *
  page117_i45
#ISCELL
  mstr_standard tap *
  page117_i46
#ISCELL
  mstr_standard tap *
  page117_i47
#ISCELL
  mstr_standard tap *
  page117_i48
#ISCELL
  mstr_standard tap *
  page117_i50
#ISCELL
  mstr_standard tap *
  page117_i58
#ISCELL
  mstr_standard tap *
  page117_i59
#ISCELL
  mstr_standard tap *
  page117_i60
#ISCELL
  mstr_standard tap *
  page117_i61
#ISCELL
  mstr_standard tap *
  page117_i62
#ISCELL
  mstr_standard tap *
  page117_i63
#ISCELL
  mstr_standard tap *
  page117_i64
#ISCELL
  mstr_standard tap *
  page117_i65
#ISCELL
  mstr_standard tap *
  page117_i74
#ISCELL
  mstr_standard tap *
  page117_i75
#ISCELL
  mstr_standard tap *
  page117_i76
#ISCELL
  mstr_standard tap *
  page117_i77
#ISCELL
  mstr_standard tap *
  page117_i78
#ISCELL
  mstr_standard tap *
  page117_i79
#ISCELL
  mstr_standard tap *
  page117_i80
#ISCELL
  mstr_standard tap *
  page117_i81
#ISCELL
  mstr_standard tap *
  page117_i82
#ISCELL
  mstr_standard tap *
  page117_i83
#ISCELL
  mstr_standard tap *
  page117_i84
#ISCELL
  mstr_standard tap *
  page117_i85
#ISCELL
  mstr_standard tap *
  page117_i86
#ISCELL
  mstr_standard tap *
  page117_i87
#CELL
  mstr_u_proc lbg_core_qat_ext_d *
  page117_i9
#ISCELL
  mstr_standard tap *
  page117_i90
#ISCELL
  mstr_standard tap *
  page117_i91
#ISCELL
  mstr_standard offpage *
  page117_i95
#ISCELL
  mstr_standard offpage *
  page117_i96
#ISCELL
  mstr_standard tap *
  page117_i97
#ISCELL
  mstr_standard tap *
  page117_i98
#ISCELL
  mstr_standard tap *
  page117_i99
#ISCELL
  mstr_misc dns *
  *
#ISCELL
  mstr_symbols cad_note *
  *
#ISCELL
  mstr_symbols intel_corp_bpage *
  *
#ISCELL
  mstr_standard offpage *
  page118_i115
#ISCELL
  mstr_symbols p1v05_pch_stby_kr_pll *
  page118_i117
#ISCELL
  mstr_symbols p1v05_pch_stby_kr_pll *
  page118_i118
#ISCELL
  mstr_standard offpage *
  page118_i119
#CELL
  mstr_discrete res *
  page118_i120
#ISCELL
  mstr_standard offpage *
  page118_i122
#ISCELL
  mstr_standard offpage *
  page118_i123
#ISCELL
  mstr_standard offpage *
  page118_i124
#CELL
  mstr_discrete res *
  page118_i125
#ISCELL
  mstr_standard offpage *
  page118_i126
#CELL
  mstr_discrete res *
  page118_i128
#ISCELL
  mstr_symbols p3v3_stby *
  page118_i129
#ISCELL
  mstr_standard offpage *
  page118_i130
#CELL
  mstr_discrete res *
  page118_i131
#ISCELL
  mstr_standard offpage *
  page118_i132
#ISCELL
  mstr_standard offpage *
  page118_i133
#ISCELL
  mstr_symbols p3v3_stby *
  page118_i135
#CELL
  dev_discrete cap_a *
  page118_i136
#ISCELL
  mstr_symbols gnd *
  page118_i137
#ISCELL
  mstr_standard offpage *
  page118_i138
#ISCELL
  mstr_standard offpage *
  page118_i140
#ISCELL
  mstr_standard offpage *
  page118_i141
#CELL
  mstr_ttl 74cbtlv1g125 *
  page118_i142
#CELL
  mstr_discrete res *
  page118_i144
#ISCELL
  mstr_symbols p3v3_stby *
  page118_i145
#ISCELL
  mstr_standard offpage *
  page118_i152
#ISCELL
  mstr_standard offpage *
  page118_i153
#ISCELL
  mstr_standard offpage *
  page118_i160
#ISCELL
  mstr_standard offpage *
  page118_i161
#ISCELL
  mstr_standard offpage *
  page118_i164
#ISCELL
  mstr_standard offpage *
  page118_i165
#ISCELL
  mstr_standard offpage *
  page118_i166
#CELL
  mstr_discrete res *
  page118_i167
#CELL
  mstr_discrete res *
  page118_i168
#ISCELL
  mstr_standard offpage *
  page118_i169
#ISCELL
  mstr_standard offpage *
  page118_i170
#ISCELL
  mstr_standard offpage *
  page118_i171
#ISCELL
  mstr_standard offpage *
  page118_i172
#ISCELL
  mstr_standard offpage *
  page118_i173
#CELL
  mstr_discrete res *
  page118_i176
#CELL
  mstr_discrete res *
  page118_i177
#CELL
  mstr_discrete cap *
  page118_i178
#CELL
  mstr_discrete cap *
  page118_i179
#CELL
  mstr_discrete res *
  page118_i180
#ISCELL
  mstr_symbols p3v3_stby *
  page118_i181
#CELL
  mstr_discrete res *
  page118_i183
#ISCELL
  mstr_standard offpage *
  page118_i19
#ISCELL
  mstr_standard offpage *
  page118_i25
#ISCELL
  mstr_standard offpage *
  page118_i26
#ISCELL
  mstr_standard offpage *
  page118_i34
#ISCELL
  mstr_standard offpage *
  page118_i35
#ISCELL
  mstr_standard offpage *
  page118_i36
#ISCELL
  mstr_standard offpage *
  page118_i37
#ISCELL
  mstr_standard offpage *
  page118_i38
#ISCELL
  mstr_standard offpage *
  page118_i40
#ISCELL
  mstr_standard offpage *
  page118_i41
#ISCELL
  mstr_standard offpage *
  page118_i42
#ISCELL
  mstr_standard offpage *
  page118_i44
#ISCELL
  mstr_standard offpage *
  page118_i46
#ISCELL
  mstr_standard offpage *
  page118_i47
#ISCELL
  mstr_standard offpage *
  page118_i48
#ISCELL
  mstr_standard offpage *
  page118_i49
#ISCELL
  mstr_standard offpage *
  page118_i50
#ISCELL
  mstr_standard offpage *
  page118_i53
#ISCELL
  mstr_standard offpage *
  page118_i54
#ISCELL
  mstr_standard offpage *
  page118_i55
#ISCELL
  mstr_standard offpage *
  page118_i56
#CELL
  mstr_discrete res *
  page118_i66
#CELL
  mstr_discrete res *
  page118_i67
#ISCELL
  mstr_standard offpage *
  page118_i68
#ISCELL
  mstr_symbols gnd *
  page118_i69
#CELL
  mstr_discrete res *
  page118_i71
#ISCELL
  mstr_symbols p3v3_stby *
  page118_i72
#CELL
  mstr_u_proc lbg_core_qat_ext_d *
  page118_i73
#CELL
  mstr_discrete crystal *
  page118_i76
#ISCELL
  mstr_symbols gnd *
  page118_i78
#ISCELL
  mstr_symbols gnd *
  page118_i80
#ISCELL
  mstr_standard offpage *
  page118_i86
#ISCELL
  mstr_standard offpage *
  page118_i87
#ISCELL
  mstr_standard offpage *
  page118_i89
#ISCELL
  mstr_standard offpage *
  page118_i91
#CELL
  mstr_discrete res *
  page118_i96
#CELL
  mstr_discrete res *
  page118_i99
#ISCELL
  mstr_symbols cad_note *
  *
#ISCELL
  mstr_symbols design_note *
  *
#ISCELL
  mstr_symbols intel_corp_bpage *
  *
#ISCELL
  mstr_standard offpage *
  page119_i10
#ISCELL
  mstr_standard offpage *
  page119_i101
#CELL
  mstr_u_proc lbg_core_qat_ext_d *
  page119_i115
#ISCELL
  mstr_standard offpage *
  page119_i119
#ISCELL
  mstr_standard tap *
  page119_i120
#ISCELL
  mstr_standard tap *
  page119_i121
#ISCELL
  mstr_standard tap *
  page119_i122
#ISCELL
  mstr_standard tap *
  page119_i123
#ISCELL
  mstr_standard offpage *
  page119_i124
#ISCELL
  mstr_standard offpage *
  page119_i125
#ISCELL
  mstr_standard offpage *
  page119_i127
#ISCELL
  mstr_standard offpage *
  page119_i128
#ISCELL
  mstr_standard offpage *
  page119_i129
#ISCELL
  mstr_standard offpage *
  page119_i13
#ISCELL
  mstr_standard offpage *
  page119_i130
#ISCELL
  mstr_standard offpage *
  page119_i131
#ISCELL
  mstr_standard offpage *
  page119_i132
#ISCELL
  mstr_standard offpage *
  page119_i136
#ISCELL
  mstr_standard offpage *
  page119_i137
#ISCELL
  mstr_standard offpage *
  page119_i139
#ISCELL
  mstr_standard offpage *
  page119_i14
#ISCELL
  mstr_standard offpage *
  page119_i140
#ISCELL
  mstr_standard offpage *
  page119_i141
#ISCELL
  mstr_standard offpage *
  page119_i142
#ISCELL
  mstr_standard offpage *
  page119_i143
#ISCELL
  mstr_standard offpage *
  page119_i144
#ISCELL
  mstr_standard offpage *
  page119_i145
#ISCELL
  mstr_standard offpage *
  page119_i146
#ISCELL
  mstr_standard offpage *
  page119_i148
#ISCELL
  mstr_standard offpage *
  page119_i150
#ISCELL
  mstr_standard offpage *
  page119_i151
#ISCELL
  mstr_standard offpage *
  page119_i154
#ISCELL
  mstr_standard offpage *
  page119_i155
#ISCELL
  mstr_standard offpage *
  page119_i156
#ISCELL
  mstr_standard offpage *
  page119_i158
#ISCELL
  mstr_standard offpage *
  page119_i159
#ISCELL
  mstr_standard offpage *
  page119_i161
#ISCELL
  mstr_standard offpage *
  page119_i164
#ISCELL
  mstr_standard offpage *
  page119_i166
#ISCELL
  mstr_standard offpage *
  page119_i170
#ISCELL
  mstr_standard offpage *
  page119_i171
#CELL
  mstr_discrete res *
  page119_i172
#CELL
  mstr_discrete res *
  page119_i173
#CELL
  mstr_discrete res *
  page119_i174
#CELL
  mstr_discrete fet_n_dual *
  page119_i175
#ISCELL
  mstr_standard offpage *
  page119_i176
#ISCELL
  mstr_symbols p3v3_stby *
  page119_i177
#CELL
  mstr_discrete res *
  page119_i178
#CELL
  mstr_discrete led *
  page119_i179
#CELL
  mstr_discrete fet_n_dual *
  page119_i180
#ISCELL
  mstr_symbols gnd *
  page119_i181
#ISCELL
  mstr_symbols p3v3_stby *
  page119_i182
#CELL
  mstr_discrete res *
  page119_i183
#ISCELL
  mstr_symbols gnd *
  page119_i184
#ISCELL
  mstr_symbols p3v3_stby *
  page119_i185
#CELL
  mstr_discrete res *
  page119_i186
#ISCELL
  mstr_standard offpage *
  page119_i187
#ISCELL
  mstr_standard offpage *
  page119_i188
#CELL
  mstr_discrete res *
  page119_i189
#ISCELL
  mstr_standard offpage *
  page119_i190
#ISCELL
  mstr_standard offpage *
  page119_i196
#ISCELL
  mstr_standard offpage *
  page119_i197
#ISCELL
  mstr_standard offpage *
  page119_i198
#ISCELL
  mstr_standard offpage *
  page119_i2
#ISCELL
  mstr_standard offpage *
  page119_i202
#ISCELL
  mstr_standard offpage *
  page119_i203
#ISCELL
  mstr_standard offpage *
  page119_i205
#ISCELL
  mstr_standard offpage *
  page119_i208
#ISCELL
  mstr_standard offpage *
  page119_i209
#ISCELL
  mstr_standard offpage *
  page119_i21
#ISCELL
  mstr_standard offpage *
  page119_i211
#ISCELL
  mstr_standard offpage *
  page119_i212
#CELL
  mstr_discrete res *
  page119_i213
#ISCELL
  mstr_symbols p3v3_stby *
  page119_i214
#ISCELL
  mstr_standard offpage *
  page119_i216
#ISCELL
  mstr_standard offpage *
  page119_i217
#ISCELL
  mstr_standard offpage *
  page119_i218
#ISCELL
  mstr_standard offpage *
  page119_i219
#ISCELL
  mstr_standard offpage *
  page119_i22
#ISCELL
  mstr_standard offpage *
  page119_i220
#ISCELL
  mstr_standard offpage *
  page119_i221
#ISCELL
  mstr_standard offpage *
  page119_i222
#CELL
  mstr_discrete res *
  page119_i223
#CELL
  mstr_discrete res *
  page119_i224
#CELL
  mstr_discrete res *
  page119_i226
#CELL
  mstr_discrete res *
  page119_i227
#CELL
  mstr_discrete res *
  page119_i228
#CELL
  mstr_discrete res *
  page119_i229
#ISCELL
  mstr_standard offpage *
  page119_i23
#CELL
  mstr_discrete res *
  page119_i230
#ISCELL
  mstr_symbols p3v3_stby *
  page119_i231
#ISCELL
  mstr_standard offpage *
  page119_i26
#ISCELL
  mstr_standard offpage *
  page119_i29
#ISCELL
  mstr_standard offpage *
  page119_i31
#ISCELL
  mstr_standard offpage *
  page119_i32
#ISCELL
  mstr_standard offpage *
  page119_i33
#ISCELL
  mstr_standard offpage *
  page119_i34
#ISCELL
  mstr_standard offpage *
  page119_i35
#ISCELL
  mstr_standard offpage *
  page119_i37
#ISCELL
  mstr_standard offpage *
  page119_i39
#ISCELL
  mstr_standard offpage *
  page119_i40
#ISCELL
  mstr_standard offpage *
  page119_i42
#ISCELL
  mstr_standard offpage *
  page119_i46
#ISCELL
  mstr_standard offpage *
  page119_i47
#ISCELL
  mstr_standard offpage *
  page119_i48
#ISCELL
  mstr_standard offpage *
  page119_i49
#ISCELL
  mstr_standard offpage *
  page119_i50
#ISCELL
  mstr_standard offpage *
  page119_i51
#ISCELL
  mstr_standard offpage *
  page119_i52
#ISCELL
  mstr_standard offpage *
  page119_i53
#ISCELL
  mstr_standard offpage *
  page119_i54
#ISCELL
  mstr_standard offpage *
  page119_i55
#ISCELL
  mstr_standard offpage *
  page119_i63
#ISCELL
  mstr_standard offpage *
  page119_i67
#ISCELL
  mstr_standard offpage *
  page119_i7
#ISCELL
  mstr_standard offpage *
  page119_i8
#ISCELL
  mstr_standard offpage *
  page119_i86
#ISCELL
  mstr_standard offpage *
  page119_i87
#ISCELL
  mstr_standard offpage *
  page119_i88
#ISCELL
  mstr_standard offpage *
  page119_i9
#ISCELL
  mstr_symbols cad_note *
  *
#ISCELL
  mstr_symbols design_note *
  *
#ISCELL
  mstr_symbols intel_corp_bpage *
  *
#ISCELL
  mstr_standard offpage *
  page120_i111
#ISCELL
  mstr_standard offpage *
  page120_i113
#ISCELL
  mstr_standard offpage *
  page120_i115
#ISCELL
  mstr_standard offpage *
  page120_i116
#ISCELL
  mstr_standard offpage *
  page120_i117
#ISCELL
  mstr_standard offpage *
  page120_i118
#ISCELL
  mstr_standard offpage *
  page120_i119
#ISCELL
  mstr_standard offpage *
  page120_i140
#ISCELL
  mstr_standard offpage *
  page120_i141
#ISCELL
  mstr_standard offpage *
  page120_i142
#ISCELL
  mstr_standard offpage *
  page120_i143
#ISCELL
  mstr_standard offpage *
  page120_i145
#ISCELL
  mstr_standard offpage *
  page120_i146
#CELL
  mstr_u_proc lbg_core_qat_ext_d *
  page120_i147
#ISCELL
  mstr_standard offpage *
  page120_i15
#ISCELL
  mstr_standard offpage *
  page120_i150
#ISCELL
  mstr_standard offpage *
  page120_i151
#ISCELL
  mstr_standard offpage *
  page120_i152
#ISCELL
  mstr_standard offpage *
  page120_i154
#ISCELL
  mstr_standard offpage *
  page120_i155
#ISCELL
  mstr_standard offpage *
  page120_i156
#ISCELL
  mstr_standard offpage *
  page120_i157
#ISCELL
  mstr_standard offpage *
  page120_i158
#ISCELL
  mstr_standard offpage *
  page120_i159
#ISCELL
  mstr_standard offpage *
  page120_i16
#ISCELL
  mstr_standard offpage *
  page120_i160
#ISCELL
  mstr_standard offpage *
  page120_i161
#ISCELL
  mstr_standard offpage *
  page120_i162
#ISCELL
  mstr_standard offpage *
  page120_i163
#ISCELL
  mstr_standard offpage *
  page120_i164
#ISCELL
  mstr_standard offpage *
  page120_i165
#ISCELL
  mstr_standard offpage *
  page120_i166
#ISCELL
  mstr_standard offpage *
  page120_i173
#ISCELL
  mstr_standard offpage *
  page120_i182
#ISCELL
  mstr_standard offpage *
  page120_i183
#ISCELL
  mstr_standard offpage *
  page120_i184
#ISCELL
  mstr_standard offpage *
  page120_i185
#ISCELL
  mstr_standard offpage *
  page120_i187
#ISCELL
  mstr_standard offpage *
  page120_i195
#ISCELL
  mstr_standard offpage *
  page120_i196
#ISCELL
  mstr_standard offpage *
  page120_i197
#ISCELL
  mstr_standard offpage *
  page120_i198
#ISCELL
  mstr_standard offpage *
  page120_i199
#ISCELL
  mstr_standard offpage *
  page120_i200
#ISCELL
  mstr_standard offpage *
  page120_i201
#ISCELL
  mstr_standard offpage *
  page120_i202
#ISCELL
  mstr_standard offpage *
  page120_i208
#ISCELL
  mstr_standard offpage *
  page120_i210
#ISCELL
  mstr_standard offpage *
  page120_i211
#ISCELL
  mstr_standard offpage *
  page120_i212
#ISCELL
  mstr_standard offpage *
  page120_i213
#ISCELL
  mstr_standard offpage *
  page120_i215
#ISCELL
  mstr_standard offpage *
  page120_i217
#CELL
  mstr_discrete res *
  page120_i218
#CELL
  mstr_discrete res *
  page120_i219
#ISCELL
  mstr_standard offpage *
  page120_i222
#ISCELL
  mstr_standard offpage *
  page120_i223
#ISCELL
  mstr_standard offpage *
  page120_i224
#ISCELL
  mstr_standard offpage *
  page120_i225
#ISCELL
  mstr_standard offpage *
  page120_i226
#ISCELL
  mstr_standard offpage *
  page120_i227
#ISCELL
  mstr_standard offpage *
  page120_i228
#ISCELL
  mstr_standard offpage *
  page120_i233
#ISCELL
  mstr_standard offpage *
  page120_i234
#ISCELL
  mstr_standard offpage *
  page120_i235
#ISCELL
  mstr_standard offpage *
  page120_i236
#ISCELL
  mstr_standard offpage *
  page120_i237
#ISCELL
  mstr_standard offpage *
  page120_i238
#ISCELL
  mstr_standard offpage *
  page120_i246
#ISCELL
  mstr_standard offpage *
  page120_i247
#ISCELL
  mstr_standard offpage *
  page120_i248
#ISCELL
  mstr_standard offpage *
  page120_i249
#ISCELL
  mstr_standard offpage *
  page120_i250
#ISCELL
  mstr_standard offpage *
  page120_i251
#ISCELL
  mstr_standard offpage *
  page120_i252
#ISCELL
  mstr_standard offpage *
  page120_i259
#ISCELL
  mstr_standard offpage *
  page120_i263
#ISCELL
  mstr_standard offpage *
  page120_i264
#ISCELL
  mstr_standard offpage *
  page120_i265
#ISCELL
  mstr_symbols gnd *
  page120_i266
#ISCELL
  mstr_standard offpage *
  page120_i267
#ISCELL
  mstr_standard offpage *
  page120_i268
#CELL
  mstr_discrete res *
  page120_i269
#CELL
  mstr_discrete res *
  page120_i270
#CELL
  mstr_discrete res *
  page120_i271
#ISCELL
  mstr_standard offpage *
  page120_i272
#CELL
  mstr_discrete res *
  page120_i273
#CELL
  mstr_discrete res *
  page120_i274
#CELL
  mstr_discrete res *
  page120_i275
#CELL
  mstr_discrete res *
  page120_i276
#CELL
  mstr_discrete res *
  page120_i277
#CELL
  mstr_discrete res *
  page120_i278
#ISCELL
  mstr_symbols p3v3_stby *
  page120_i279
#ISCELL
  mstr_standard offpage *
  page120_i4
#ISCELL
  mstr_standard offpage *
  page120_i43
#ISCELL
  mstr_standard offpage *
  page120_i5
#ISCELL
  mstr_standard offpage *
  page120_i53
#ISCELL
  mstr_standard offpage *
  page120_i54
#ISCELL
  mstr_standard offpage *
  page120_i68
#ISCELL
  mstr_standard offpage *
  page120_i69
#ISCELL
  mstr_standard offpage *
  page120_i7
#ISCELL
  mstr_standard offpage *
  page120_i70
#ISCELL
  mstr_standard offpage *
  page120_i71
#ISCELL
  mstr_standard offpage *
  page120_i72
#ISCELL
  mstr_standard offpage *
  page120_i73
#ISCELL
  mstr_standard offpage *
  page120_i74
#ISCELL
  mstr_standard offpage *
  page120_i75
#ISCELL
  mstr_standard offpage *
  page120_i76
#ISCELL
  mstr_standard offpage *
  page120_i77
#ISCELL
  mstr_symbols cad_note *
  *
#ISCELL
  mstr_symbols intel_corp_bpage *
  *
#ISCELL
  mstr_standard offpage *
  page121_i10
#ISCELL
  mstr_standard offpage *
  page121_i100
#CELL
  mstr_discrete res *
  page121_i101
#ISCELL
  mstr_standard offpage *
  page121_i102
#ISCELL
  mstr_standard offpage *
  page121_i103
#ISCELL
  mstr_standard offpage *
  page121_i104
#ISCELL
  mstr_standard offpage *
  page121_i105
#ISCELL
  mstr_standard offpage *
  page121_i106
#ISCELL
  mstr_standard offpage *
  page121_i107
#ISCELL
  mstr_standard offpage *
  page121_i108
#ISCELL
  mstr_standard offpage *
  page121_i109
#ISCELL
  mstr_standard offpage *
  page121_i11
#ISCELL
  mstr_standard offpage *
  page121_i110
#ISCELL
  mstr_standard offpage *
  page121_i111
#ISCELL
  mstr_standard offpage *
  page121_i112
#ISCELL
  mstr_standard offpage *
  page121_i21
#ISCELL
  mstr_standard offpage *
  page121_i24
#ISCELL
  mstr_standard offpage *
  page121_i25
#ISCELL
  mstr_standard offpage *
  page121_i27
#ISCELL
  mstr_standard offpage *
  page121_i28
#ISCELL
  mstr_standard offpage *
  page121_i29
#CELL
  mstr_discrete res *
  page121_i31
#ISCELL
  mstr_standard offpage *
  page121_i32
#CELL
  mstr_discrete res *
  page121_i33
#CELL
  mstr_u_proc lbg_core_qat_ext_d *
  page121_i34
#CELL
  mstr_discrete res *
  page121_i35
#CELL
  mstr_discrete res *
  page121_i37
#ISCELL
  mstr_symbols gnd *
  page121_i39
#ISCELL
  mstr_symbols p3v3_stby *
  page121_i40
#ISCELL
  mstr_standard offpage *
  page121_i41
#ISCELL
  mstr_standard offpage *
  page121_i42
#ISCELL
  mstr_standard offpage *
  page121_i43
#ISCELL
  mstr_standard offpage *
  page121_i49
#ISCELL
  mstr_standard offpage *
  page121_i50
#ISCELL
  mstr_standard offpage *
  page121_i51
#ISCELL
  mstr_standard offpage *
  page121_i52
#ISCELL
  mstr_standard offpage *
  page121_i53
#ISCELL
  mstr_standard offpage *
  page121_i54
#ISCELL
  mstr_standard offpage *
  page121_i6
#ISCELL
  mstr_standard offpage *
  page121_i7
#ISCELL
  mstr_standard offpage *
  page121_i72
#CELL
  mstr_discrete res *
  page121_i73
#ISCELL
  mstr_symbols gnd *
  page121_i74
#ISCELL
  mstr_standard offpage *
  page121_i75
#ISCELL
  mstr_standard offpage *
  page121_i76
#ISCELL
  mstr_standard offpage *
  page121_i77
#ISCELL
  mstr_standard offpage *
  page121_i78
#ISCELL
  mstr_standard offpage *
  page121_i79
#ISCELL
  mstr_standard offpage *
  page121_i8
#ISCELL
  mstr_standard offpage *
  page121_i80
#ISCELL
  mstr_standard offpage *
  page121_i85
#ISCELL
  mstr_standard offpage *
  page121_i86
#ISCELL
  mstr_standard offpage *
  page121_i87
#ISCELL
  mstr_standard offpage *
  page121_i88
#CELL
  mstr_discrete res *
  page121_i89
#CELL
  mstr_discrete res *
  page121_i90
#CELL
  mstr_discrete res *
  page121_i91
#ISCELL
  mstr_standard offpage *
  page121_i92
#ISCELL
  mstr_standard offpage *
  page121_i93
#ISCELL
  mstr_standard offpage *
  page121_i94
#ISCELL
  mstr_standard offpage *
  page121_i95
#ISCELL
  mstr_standard offpage *
  page121_i96
#ISCELL
  mstr_standard offpage *
  page121_i97
#CELL
  mstr_discrete res *
  page121_i98
#ISCELL
  mstr_standard offpage *
  page121_i99
#ISCELL
  mstr_symbols intel_corp_bpage *
  *
#ISCELL
  mstr_symbols p1v8_pch_stby *
  page122_i21
#ISCELL
  mstr_symbols p1v05_pch_stby *
  page122_i24
#ISCELL
  mstr_standard offpage *
  page122_i46
#CELL
  mstr_u_proc lbg_core_qat_ext_d *
  page122_i63
#ISCELL
  mstr_symbols p3v3_stby *
  page122_i65
#ISCELL
  mstr_symbols p1v05_pch_stby_wm26_pll *
  page122_i70
#ISCELL
  mstr_symbols p1v05_pch_stby_wm20_pll *
  page122_i71
#ISCELL
  mstr_symbols p1v05_pch_stby_kr_pll *
  page122_i72
#ISCELL
  mstr_symbols p1v05_pch_stby_isclk_pll *
  page122_i73
#ISCELL
  mstr_symbols p1v05_pch_stby_vcca_xtal *
  page122_i74
#ISCELL
  mstr_symbols p3v3_rtc_stby *
  page122_i75
#ISCELL
  mstr_symbols p1v05_pch_stby *
  page122_i76
#ISCELL
  mstr_symbols p1v05_pch_stby_vcca_pll0 *
  page122_i77
#ISCELL
  mstr_symbols p1v05_pch_stby_vcca_pll1 *
  page122_i78
#ISCELL
  mstr_symbols intel_corp_bpage *
  *
#CELL
  mstr_u_proc lbg_core_qat_ext_d *
  page123_i13
#ISCELL
  mstr_symbols gnd *
  page123_i14
#ISCELL
  mstr_symbols gnd *
  page123_i15
#ISCELL
  mstr_symbols pvnn_pch_stby *
  page123_i20
#CELL
  mstr_u_proc lbg_core_qat_ext_d *
  page123_i21
#ISCELL
  mstr_standard offpage *
  page123_i22
#ISCELL
  mstr_standard offpage *
  page123_i23
#ISCELL
  mstr_symbols pvnn_pch_stby *
  page123_i24
#ISCELL
  mstr_symbols p1v05_pch_stby *
  page123_i25
#ISCELL
  mstr_symbols intel_corp_bpage *
  *
#ISCELL
  mstr_symbols gnd *
  page124_i13
#ISCELL
  mstr_symbols gnd *
  page124_i14
#CELL
  mstr_u_proc lbg_core_qat_ext_d *
  page124_i15
#CELL
  mstr_u_proc lbg_core_qat_ext_d *
  page124_i16
#CELL
  mstr_u_proc lbg_core_qat_ext_d *
  page124_i17
#ISCELL
  mstr_symbols gnd *
  page124_i4
#ISCELL
  mstr_symbols gnd *
  page124_i6
#ISCELL
  mstr_symbols gnd *
  page124_i7
#ISCELL
  mstr_symbols gnd *
  page124_i9
#ISCELL
  mstr_misc dns *
  *
#ISCELL
  mstr_symbols design_note *
  *
#ISCELL
  mstr_symbols intel_corp_bpage *
  *
#CELL
  mstr_discrete res *
  page125_i11
#ISCELL
  mstr_symbols gnd *
  page125_i14
#ISCELL
  mstr_symbols gnd *
  page125_i16
#ISCELL
  mstr_standard offpage *
  page125_i20
#CELL
  mstr_discrete res *
  page125_i21
#ISCELL
  mstr_standard offpage *
  page125_i23
#CELL
  mstr_discrete res *
  page125_i24
#ISCELL
  mstr_symbols gnd *
  page125_i25
#CELL
  mstr_discrete res *
  page125_i40
#CELL
  mstr_discrete res *
  page125_i41
#ISCELL
  mstr_standard offpage *
  page125_i43
#ISCELL
  mstr_symbols p3v3_stby *
  page125_i48
#ISCELL
  mstr_symbols p3v3_stby *
  page125_i49
#CELL
  mstr_discrete res *
  page125_i50
#ISCELL
  mstr_symbols p3v3_stby *
  page125_i51
#ISCELL
  mstr_standard offpage *
  page125_i53
#ISCELL
  mstr_symbols gnd *
  page125_i54
#ISCELL
  mstr_symbols gnd *
  page125_i6
#CELL
  mstr_discrete res *
  page125_i60
#ISCELL
  mstr_symbols p3v3_stby *
  page125_i61
#ISCELL
  mstr_standard offpage *
  page125_i64
#ISCELL
  mstr_standard offpage *
  page125_i65
#ISCELL
  mstr_symbols p3v3_stby *
  page125_i66
#ISCELL
  mstr_symbols gnd *
  page125_i69
#ISCELL
  mstr_standard offpage *
  page125_i7
#CELL
  mstr_discrete res *
  page125_i72
#ISCELL
  mstr_standard offpage *
  page125_i73
#ISCELL
  mstr_symbols p3v3_stby *
  page125_i74
#ISCELL
  mstr_symbols p3v3_stby *
  page125_i75
#ISCELL
  mstr_standard offpage *
  page125_i77
#CELL
  mstr_discrete res *
  page125_i78
#ISCELL
  mstr_symbols p3v3_stby *
  page125_i79
#ISCELL
  mstr_standard offpage *
  page125_i82
#CELL
  mstr_discrete res *
  page125_i83
#ISCELL
  mstr_symbols p3v3_stby *
  page125_i84
#CELL
  mstr_discrete res *
  page125_i85
#CELL
  mstr_discrete res *
  page125_i86
#CELL
  mstr_discrete res *
  page125_i87
#CELL
  mstr_discrete res *
  page125_i88
#CELL
  mstr_discrete res *
  page125_i89
#ISCELL
  mstr_misc dns *
  *
#ISCELL
  mstr_symbols design_note *
  *
#ISCELL
  mstr_symbols intel_corp_bpage *
  *
#ISCELL
  mstr_standard offpage *
  page126_i11
#CELL
  mstr_discrete res *
  page126_i12
#CELL
  mstr_discrete fet_n *
  page126_i13
#ISCELL
  mstr_symbols gnd *
  page126_i14
#ISCELL
  mstr_symbols p3v3_stby *
  page126_i16
#ISCELL
  mstr_standard offpage *
  page126_i17
#CELL
  mstr_discrete res *
  page126_i20
#ISCELL
  mstr_standard offpage *
  page126_i21
#CELL
  mstr_discrete res *
  page126_i22
#CELL
  mstr_discrete res *
  page126_i23
#ISCELL
  mstr_symbols gnd *
  page126_i24
#ISCELL
  mstr_symbols p3v3_stby *
  page126_i25
#ISCELL
  mstr_standard offpage *
  page126_i26
#CELL
  mstr_discrete res *
  page126_i27
#ISCELL
  mstr_symbols gnd *
  page126_i5
#CELL
  mstr_discrete res *
  page126_i6
#ISCELL
  mstr_symbols p3v3_stby *
  page126_i7
#ISCELL
  mstr_standard offpage *
  page126_i8
#ISCELL
  mstr_symbols p3v3_stby *
  page126_i9
#ISCELL
  mstr_symbols intel_corp_bpage *
  *
#ISCELL
  mstr_symbols gnd *
  page127_i14
#ISCELL
  mstr_symbols p1v05_pch_stby *
  page127_i16
#CELL
  mstr_discrete ferrite *
  page127_i17
#CELL
  dev_discrete cap_a *
  page127_i18
#ISCELL
  mstr_symbols gnd *
  page127_i23
#ISCELL
  mstr_symbols p1v05_pch_stby *
  page127_i25
#CELL
  mstr_discrete ferrite *
  page127_i26
#CELL
  dev_discrete cap_a *
  page127_i27
#ISCELL
  mstr_symbols gnd *
  page127_i32
#ISCELL
  mstr_symbols gnd *
  page127_i34
#ISCELL
  mstr_symbols gnd *
  page127_i36
#ISCELL
  mstr_symbols p1v05_pch_stby_vcca_xtal *
  page127_i39
#ISCELL
  mstr_symbols p1v05_pch_stby_wm20_pll *
  page127_i40
#CELL
  mstr_discrete cap *
  page127_i43
#CELL
  dev_discrete cap_a *
  page127_i44
#ISCELL
  mstr_symbols p1v05_pch_stby *
  page127_i45
#CELL
  mstr_discrete ferrite *
  page127_i46
#ISCELL
  mstr_symbols p1v05_pch_stby_wm26_pll *
  page127_i47
#CELL
  mstr_discrete cap *
  page127_i49
#CELL
  dev_discrete cap_a *
  page127_i50
#ISCELL
  mstr_symbols gnd *
  page127_i51
#ISCELL
  mstr_symbols p1v05_pch_stby_isclk_pll *
  page127_i52
#ISCELL
  mstr_symbols p1v05_pch_stby *
  page127_i55
#CELL
  mstr_discrete ferrite *
  page127_i56
#CELL
  dev_discrete cap_a *
  page127_i57
#ISCELL
  mstr_symbols gnd *
  page127_i58
#ISCELL
  mstr_symbols gnd *
  page127_i59
#ISCELL
  mstr_symbols gnd *
  page127_i6
#ISCELL
  mstr_symbols gnd *
  page127_i61
#ISCELL
  mstr_symbols p1v05_pch_stby_kr_pll *
  page127_i62
#CELL
  mstr_discrete cap *
  page127_i64
#CELL
  dev_discrete cap_a *
  page127_i65
#ISCELL
  mstr_symbols gnd *
  page127_i66
#ISCELL
  mstr_symbols p1v05_pch_stby *
  page127_i68
#CELL
  mstr_discrete ferrite *
  page127_i69
#ISCELL
  mstr_symbols p1v05_pch_stby *
  page127_i7
#ISCELL
  mstr_symbols p1v05_pch_stby *
  page127_i70
#CELL
  mstr_discrete inductor *
  page127_i71
#ISCELL
  mstr_symbols p1v05_pch_stby_vcca_pll0 *
  page127_i72
#ISCELL
  mstr_symbols p1v05_pch_stby_vcca_pll1 *
  page127_i73
#CELL
  dev_discrete cap_a *
  page127_i74
#ISCELL
  mstr_symbols gnd *
  page127_i75
#CELL
  dev_discrete cap_a *
  page127_i76
#ISCELL
  mstr_symbols gnd *
  page127_i77
#CELL
  dev_discrete cap_a *
  page127_i78
#ISCELL
  mstr_symbols gnd *
  page127_i79
#CELL
  mstr_discrete ferrite *
  page127_i8
#CELL
  dev_discrete cap_a *
  page127_i80
#CELL
  mstr_discrete cap *
  page127_i81
#CELL
  mstr_discrete cap *
  page127_i82
#CELL
  dev_discrete cap_a *
  page127_i83
#CELL
  dev_discrete cap_a *
  page127_i84
#CELL
  mstr_discrete cap *
  page127_i85
#CELL
  mstr_discrete cap *
  page127_i86
#CELL
  dev_discrete cap_a *
  page127_i87
#CELL
  dev_discrete cap_a *
  page127_i9
#ISCELL
  mstr_symbols intel_corp_bpage *
  *
#ISCELL
  mstr_symbols intel_corp_bpage *
  *
#ISCELL
  mstr_standard offpage *
  page129_i1
#ISCELL
  mstr_standard offpage *
  page129_i10
#ISCELL
  mstr_standard tap *
  page129_i11
#ISCELL
  mstr_standard tap *
  page129_i12
#ISCELL
  mstr_standard tap *
  page129_i13
#ISCELL
  mstr_standard tap *
  page129_i14
#ISCELL
  mstr_standard tap *
  page129_i2
#ISCELL
  mstr_standard tap *
  page129_i23
#ISCELL
  mstr_standard tap *
  page129_i24
#ISCELL
  mstr_standard tap *
  page129_i25
#ISCELL
  mstr_standard tap *
  page129_i26
#ISCELL
  mstr_standard offpage *
  page129_i27
#ISCELL
  mstr_standard offpage *
  page129_i28
#ISCELL
  mstr_standard tap *
  page129_i29
#ISCELL
  mstr_standard tap *
  page129_i3
#ISCELL
  mstr_standard tap *
  page129_i30
#ISCELL
  mstr_standard tap *
  page129_i31
#ISCELL
  mstr_standard tap *
  page129_i32
#CELL
  mstr_discrete cap *
  page129_i35
#ISCELL
  mstr_standard tap *
  page129_i37
#ISCELL
  mstr_standard tap *
  page129_i38
#ISCELL
  mstr_standard tap *
  page129_i39
#ISCELL
  mstr_standard tap *
  page129_i4
#ISCELL
  mstr_standard tap *
  page129_i40
#ISCELL
  mstr_standard offpage *
  page129_i42
#ISCELL
  mstr_standard offpage *
  page129_i43
#ISCELL
  mstr_standard tap *
  page129_i45
#ISCELL
  mstr_standard tap *
  page129_i46
#ISCELL
  mstr_standard tap *
  page129_i47
#ISCELL
  mstr_standard tap *
  page129_i48
#ISCELL
  mstr_standard tap *
  page129_i5
#ISCELL
  mstr_standard tap *
  page129_i57
#ISCELL
  mstr_standard tap *
  page129_i58
#ISCELL
  mstr_standard tap *
  page129_i59
#ISCELL
  mstr_standard tap *
  page129_i60
#ISCELL
  mstr_standard offpage *
  page129_i61
#ISCELL
  mstr_standard tap *
  page129_i62
#ISCELL
  mstr_standard tap *
  page129_i63
#ISCELL
  mstr_standard tap *
  page129_i64
#ISCELL
  mstr_standard tap *
  page129_i65
#ISCELL
  mstr_standard offpage *
  page129_i67
#CELL
  mstr_discrete cap *
  page129_i69
#CELL
  mstr_discrete cap *
  page129_i70
#CELL
  mstr_discrete cap *
  page129_i71
#CELL
  mstr_discrete cap *
  page129_i72
#CELL
  mstr_discrete cap *
  page129_i73
#CELL
  mstr_discrete cap *
  page129_i74
#CELL
  mstr_discrete cap *
  page129_i75
#CELL
  mstr_discrete cap *
  page129_i76
#CELL
  mstr_discrete cap *
  page129_i77
#CELL
  mstr_discrete cap *
  page129_i78
#CELL
  mstr_discrete cap *
  page129_i79
#CELL
  mstr_discrete cap *
  page129_i80
#CELL
  mstr_discrete cap *
  page129_i81
#CELL
  mstr_discrete cap *
  page129_i82
#CELL
  mstr_discrete cap *
  page129_i83
#ISCELL
  mstr_symbols cad_note *
  *
#ISCELL
  mstr_symbols design_note *
  *
#ISCELL
  mstr_symbols intel_corp_bpage *
  *
#CELL
  dev_discrete cap_a *
  page130_i12
#ISCELL
  mstr_symbols gnd *
  page130_i13
#ISCELL
  mstr_symbols gnd *
  page130_i14
#CELL
  mstr_discrete cap *
  page130_i15
#CELL
  dev_discrete cap_a *
  page130_i16
#ISCELL
  mstr_symbols gnd *
  page130_i17
#ISCELL
  mstr_standard offpage *
  page130_i18
#CELL
  mstr_discrete cap *
  page130_i19
#CELL
  mstr_discrete cap *
  page130_i2
#CELL
  mstr_discrete cap *
  page130_i20
#CELL
  mstr_discrete cap *
  page130_i21
#CELL
  mstr_discrete cap *
  page130_i22
#CELL
  mstr_discrete cap *
  page130_i24
#CELL
  mstr_discrete cap *
  page130_i25
#ISCELL
  mstr_symbols gnd *
  page130_i27
#CELL
  mstr_discrete cap *
  page130_i28
#CELL
  dev_discrete cap_a *
  page130_i29
#ISCELL
  mstr_symbols gnd *
  page130_i3
#CELL
  dev_discrete cap_a *
  page130_i30
#ISCELL
  mstr_symbols p1v8_pch_stby *
  page130_i31
#CELL
  dev_discrete cap_a *
  page130_i32
#ISCELL
  mstr_symbols gnd *
  page130_i33
#CELL
  dev_discrete cap_a *
  page130_i34
#ISCELL
  mstr_symbols gnd *
  page130_i35
#CELL
  dev_discrete cap_a *
  page130_i37
#CELL
  dev_discrete cap_a *
  page130_i38
#CELL
  dev_discrete cap_a *
  page130_i39
#CELL
  dev_discrete cap_a *
  page130_i4
#ISCELL
  mstr_symbols gnd *
  page130_i40
#CELL
  dev_discrete cap_a *
  page130_i41
#CELL
  dev_discrete cap_a *
  page130_i42
#CELL
  dev_discrete cap_a *
  page130_i43
#ISCELL
  mstr_symbols p1v8_pch_stby *
  page130_i44
#CELL
  dev_discrete cap_a *
  page130_i45
#ISCELL
  mstr_symbols gnd *
  page130_i46
#CELL
  dev_discrete cap_a *
  page130_i47
#ISCELL
  mstr_symbols gnd *
  page130_i48
#CELL
  dev_discrete cap_a *
  page130_i49
#CELL
  dev_discrete cap_a *
  page130_i50
#ISCELL
  mstr_symbols p1v8_pch_stby *
  page130_i51
#CELL
  dev_discrete cap_a *
  page130_i52
#CELL
  dev_discrete cap_a *
  page130_i53
#ISCELL
  mstr_symbols p3v3_stby *
  page130_i54
#ISCELL
  mstr_symbols p3v3_stby *
  page130_i55
#ISCELL
  mstr_symbols p3v3_stby *
  page130_i58
#ISCELL
  mstr_symbols p3v3_stby *
  page130_i59
#ISCELL
  mstr_symbols gnd *
  page130_i6
#ISCELL
  mstr_symbols p3v3_stby *
  page130_i60
#ISCELL
  mstr_symbols p3v3_stby *
  page130_i61
#ISCELL
  mstr_symbols p3v3_stby *
  page130_i62
#CELL
  dev_discrete cap_a *
  page130_i7
#CELL
  mstr_discrete cap *
  page130_i8
#CELL
  mstr_discrete cap *
  page130_i9
#ISCELL
  mstr_symbols cad_note *
  *
#ISCELL
  mstr_symbols design_note *
  *
#ISCELL
  mstr_symbols intel_corp_bpage *
  *
#CELL
  dev_discrete cap_a *
  page131_i1
#CELL
  dev_discrete cap_a *
  page131_i10
#CELL
  dev_discrete cap_a *
  page131_i11
#CELL
  dev_discrete cap_a *
  page131_i12
#ISCELL
  mstr_symbols gnd *
  page131_i13
#CELL
  dev_discrete cap_a *
  page131_i14
#CELL
  dev_discrete cap_a *
  page131_i15
#CELL
  dev_discrete cap_a *
  page131_i16
#ISCELL
  mstr_symbols p1v05_pch_stby *
  page131_i17
#CELL
  dev_discrete cap_a *
  page131_i18
#ISCELL
  mstr_symbols p1v05_pch_stby *
  page131_i19
#CELL
  dev_discrete cap_a *
  page131_i2
#CELL
  dev_discrete cap_a *
  page131_i20
#ISCELL
  mstr_symbols gnd *
  page131_i21
#CELL
  mstr_discrete cap *
  page131_i22
#ISCELL
  mstr_symbols p1v05_pch_stby *
  page131_i23
#CELL
  mstr_discrete cap *
  page131_i24
#ISCELL
  mstr_symbols gnd *
  page131_i25
#ISCELL
  mstr_symbols p1v05_pch_stby *
  page131_i26
#CELL
  dev_discrete cap_a *
  page131_i27
#CELL
  dev_discrete cap_a *
  page131_i28
#CELL
  dev_discrete cap_a *
  page131_i29
#CELL
  dev_discrete cap_a *
  page131_i3
#ISCELL
  mstr_symbols gnd *
  page131_i30
#CELL
  dev_discrete cap_a *
  page131_i31
#CELL
  dev_discrete cap_a *
  page131_i32
#ISCELL
  mstr_symbols gnd *
  page131_i33
#CELL
  mstr_discrete cap *
  page131_i34
#CELL
  mstr_discrete cap *
  page131_i35
#ISCELL
  mstr_symbols p1v05_pch_stby *
  page131_i36
#CELL
  mstr_discrete cap *
  page131_i37
#ISCELL
  mstr_symbols gnd *
  page131_i38
#CELL
  dev_discrete cap_a *
  page131_i39
#CELL
  dev_discrete cap_a *
  page131_i4
#CELL
  dev_discrete cap_a *
  page131_i40
#CELL
  dev_discrete cap_a *
  page131_i41
#CELL
  dev_discrete cap_a *
  page131_i42
#CELL
  dev_discrete cap_a *
  page131_i43
#CELL
  dev_discrete cap_a *
  page131_i44
#CELL
  dev_discrete cap_a *
  page131_i45
#ISCELL
  mstr_symbols p1v05_pch_stby *
  page131_i46
#CELL
  dev_discrete cap_a *
  page131_i47
#CELL
  dev_discrete cap_a *
  page131_i48
#ISCELL
  mstr_symbols p1v05_pch_stby *
  page131_i49
#ISCELL
  mstr_symbols p1v05_pch_stby *
  page131_i5
#CELL
  dev_discrete cap_a *
  page131_i50
#ISCELL
  mstr_symbols gnd *
  page131_i51
#CELL
  dev_discrete cap_a *
  page131_i52
#CELL
  dev_discrete cap_a *
  page131_i6
#CELL
  dev_discrete cap_a *
  page131_i7
#CELL
  dev_discrete cap_a *
  page131_i8
#ISCELL
  mstr_symbols gnd *
  page131_i9
#ISCELL
  mstr_symbols cad_note *
  *
#ISCELL
  mstr_symbols design_note *
  *
#ISCELL
  mstr_symbols intel_corp_bpage *
  *
#CELL
  dev_discrete cap_a *
  page132_i1
#ISCELL
  mstr_symbols gnd *
  page132_i10
#CELL
  dev_discrete cap_a *
  page132_i11
#CELL
  dev_discrete cap_a *
  page132_i12
#CELL
  dev_discrete cap_a *
  page132_i13
#ISCELL
  mstr_symbols pvnn_pch_stby *
  page132_i14
#ISCELL
  mstr_symbols gnd *
  page132_i15
#CELL
  dev_discrete cap_a *
  page132_i16
#CELL
  dev_discrete cap_a *
  page132_i17
#ISCELL
  mstr_symbols pvnn_pch_stby *
  page132_i18
#CELL
  dev_discrete cap_a *
  page132_i19
#CELL
  dev_discrete cap_a *
  page132_i2
#CELL
  dev_discrete cap_a *
  page132_i20
#ISCELL
  mstr_symbols gnd *
  page132_i21
#ISCELL
  mstr_symbols pvnn_pch_stby *
  page132_i22
#CELL
  mstr_discrete cap *
  page132_i23
#CELL
  mstr_discrete cap *
  page132_i24
#ISCELL
  mstr_symbols gnd *
  page132_i25
#CELL
  dev_discrete cap_a *
  page132_i26
#CELL
  dev_discrete cap_a *
  page132_i27
#CELL
  dev_discrete cap_a *
  page132_i28
#CELL
  dev_discrete cap_a *
  page132_i29
#CELL
  dev_discrete cap_a *
  page132_i3
#CELL
  dev_discrete cap_a *
  page132_i30
#CELL
  dev_discrete cap_a *
  page132_i31
#CELL
  dev_discrete cap_a *
  page132_i32
#ISCELL
  mstr_symbols gnd *
  page132_i33
#CELL
  dev_discrete cap_a *
  page132_i34
#CELL
  dev_discrete cap_a *
  page132_i35
#CELL
  dev_discrete cap_a *
  page132_i36
#ISCELL
  mstr_symbols gnd *
  page132_i37
#CELL
  mstr_discrete cap *
  page132_i38
#ISCELL
  mstr_symbols pvnn_pch_stby *
  page132_i39
#CELL
  dev_discrete cap_a *
  page132_i4
#CELL
  mstr_discrete cap *
  page132_i40
#ISCELL
  mstr_symbols gnd *
  page132_i41
#CELL
  dev_discrete cap_a *
  page132_i42
#CELL
  dev_discrete cap_a *
  page132_i43
#CELL
  dev_discrete cap_a *
  page132_i44
#CELL
  dev_discrete cap_a *
  page132_i45
#CELL
  dev_discrete cap_a *
  page132_i46
#ISCELL
  mstr_symbols pvnn_pch_stby *
  page132_i47
#CELL
  dev_discrete cap_a *
  page132_i48
#CELL
  dev_discrete cap_a *
  page132_i49
#ISCELL
  mstr_symbols pvnn_pch_stby *
  page132_i5
#ISCELL
  mstr_symbols pvnn_pch_stby *
  page132_i50
#CELL
  dev_discrete cap_a *
  page132_i51
#CELL
  dev_discrete cap_a *
  page132_i52
#ISCELL
  mstr_symbols pvnn_pch_stby *
  page132_i53
#CELL
  dev_discrete cap_a *
  page132_i54
#ISCELL
  mstr_symbols gnd *
  page132_i55
#CELL
  dev_discrete cap_a *
  page132_i56
#CELL
  dev_discrete cap_a *
  page132_i6
#CELL
  dev_discrete cap_a *
  page132_i7
#CELL
  dev_discrete cap_a *
  page132_i8
#CELL
  dev_discrete cap_a *
  page132_i9
#ISCELL
  mstr_misc dns *
  *
#ISCELL
  mstr_symbols design_note *
  *
#ISCELL
  mstr_symbols intel_corp_bpage *
  *
#ISCELL
  mstr_symbols gnd *
  page133_i110
#ISCELL
  mstr_standard offpage *
  page133_i112
#ISCELL
  mstr_standard offpage *
  page133_i117
#CELL
  mstr_discrete res *
  page133_i120
#CELL
  mstr_discrete res *
  page133_i122
#CELL
  mstr_discrete res *
  page133_i200
#CELL
  mstr_discrete res *
  page133_i202
#ISCELL
  mstr_standard offpage *
  page133_i204
#ISCELL
  mstr_standard offpage *
  page133_i205
#ISCELL
  mstr_standard offpage *
  page133_i206
#ISCELL
  mstr_standard offpage *
  page133_i208
#CELL
  mstr_discrete res *
  page133_i237
#ISCELL
  mstr_standard offpage *
  page133_i238
#ISCELL
  mstr_standard offpage *
  page133_i242
#CELL
  mstr_discrete res *
  page133_i243
#ISCELL
  mstr_standard offpage *
  page133_i244
#CELL
  mstr_discrete res *
  page133_i245
#ISCELL
  mstr_standard offpage *
  page133_i246
#CELL
  mstr_discrete res *
  page133_i247
#ISCELL
  mstr_standard offpage *
  page133_i248
#ISCELL
  mstr_symbols p3v3_stby *
  page133_i251
#ISCELL
  mstr_standard offpage *
  page133_i254
#ISCELL
  mstr_symbols p3v3_stby *
  page133_i256
#ISCELL
  mstr_standard offpage *
  page133_i257
#CELL
  mstr_discrete res *
  page133_i258
#ISCELL
  mstr_standard offpage *
  page133_i259
#ISCELL
  mstr_symbols p3v3_stby *
  page133_i260
#ISCELL
  mstr_standard offpage *
  page133_i264
#CELL
  mstr_discrete res *
  page133_i267
#ISCELL
  mstr_symbols p3v3_stby *
  page133_i268
#ISCELL
  mstr_standard offpage *
  page133_i279
#CELL
  mstr_discrete res *
  page133_i280
#ISCELL
  mstr_standard offpage *
  page133_i281
#CELL
  mstr_discrete res *
  page133_i282
#ISCELL
  mstr_standard offpage *
  page133_i283
#CELL
  mstr_discrete res *
  page133_i284
#ISCELL
  mstr_standard offpage *
  page133_i285
#CELL
  mstr_discrete res *
  page133_i286
#ISCELL
  mstr_standard offpage *
  page133_i287
#ISCELL
  mstr_standard offpage *
  page133_i289
#ISCELL
  mstr_standard offpage *
  page133_i292
#ISCELL
  mstr_standard offpage *
  page133_i293
#ISCELL
  mstr_standard offpage *
  page133_i294
#CELL
  mstr_discrete res *
  page133_i295
#CELL
  mstr_discrete res *
  page133_i296
#CELL
  mstr_discrete res *
  page133_i297
#ISCELL
  mstr_symbols p3v3_stby *
  page133_i298
#ISCELL
  mstr_standard offpage *
  page133_i299
#ISCELL
  mstr_symbols p3v3_stby *
  page133_i300
#CELL
  mstr_discrete res *
  page133_i301
#ISCELL
  mstr_symbols p3v3_stby *
  page133_i302
#CELL
  mstr_discrete res *
  page133_i303
#CELL
  mstr_discrete res *
  page133_i304
#CELL
  mstr_discrete res *
  page133_i306
#CELL
  mstr_discrete res *
  page133_i307
#CELL
  mstr_discrete res *
  page133_i309
#ISCELL
  mstr_standard offpage *
  page133_i311
#ISCELL
  mstr_standard offpage *
  page133_i312
#ISCELL
  mstr_standard offpage *
  page133_i313
#ISCELL
  mstr_standard offpage *
  page133_i314
#ISCELL
  mstr_standard offpage *
  page133_i319
#ISCELL
  mstr_standard offpage *
  page133_i320
#CELL
  mstr_discrete res *
  page133_i322
#ISCELL
  mstr_standard offpage *
  page133_i325
#CELL
  mstr_discrete res *
  page133_i326
#CELL
  mstr_discrete res *
  page133_i327
#ISCELL
  mstr_standard offpage *
  page133_i328
#CELL
  mstr_discrete res *
  page133_i331
#CELL
  mstr_discrete res *
  page133_i332
#CELL
  mstr_discrete res *
  page133_i333
#ISCELL
  mstr_standard offpage *
  page133_i334
#ISCELL
  mstr_symbols p3v3_stby *
  page133_i335
#ISCELL
  mstr_symbols p1v05_pch_stby *
  page133_i339
#ISCELL
  mstr_standard offpage *
  page133_i340
#CELL
  mstr_discrete res *
  page133_i341
#ISCELL
  mstr_symbols p3v3_stby *
  page133_i342
#CELL
  mstr_discrete res *
  page133_i349
#ISCELL
  mstr_standard offpage *
  page133_i350
#ISCELL
  mstr_standard offpage *
  page133_i351
#CELL
  mstr_discrete res *
  page133_i352
#ISCELL
  mstr_symbols p3v3_stby *
  page133_i353
#ISCELL
  mstr_standard offpage *
  page133_i354
#CELL
  mstr_discrete res *
  page133_i356
#ISCELL
  mstr_standard offpage *
  page133_i358
#ISCELL
  mstr_standard offpage *
  page133_i359
#CELL
  mstr_discrete res *
  page133_i360
#ISCELL
  mstr_standard offpage *
  page133_i361
#CELL
  mstr_discrete res *
  page133_i362
#ISCELL
  mstr_standard offpage *
  page133_i363
#CELL
  mstr_discrete res *
  page133_i365
#CELL
  mstr_discrete res *
  page133_i366
#CELL
  mstr_discrete res *
  page133_i367
#CELL
  mstr_discrete res *
  page133_i368
#CELL
  mstr_discrete res *
  page133_i369
#CELL
  mstr_discrete res *
  page133_i370
#CELL
  mstr_discrete res *
  page133_i371
#ISCELL
  mstr_symbols intel_corp_bpage *
  *
#ISCELL
  mstr_standard offpage *
  page134_i1
#CELL
  mstr_discrete res *
  page134_i11
#ISCELL
  mstr_symbols gnd *
  page134_i12
#ISCELL
  mstr_standard offpage *
  page134_i13
#CELL
  mstr_discrete fet_n *
  page134_i14
#CELL
  mstr_discrete fet_n *
  page134_i15
#ISCELL
  mstr_symbols p3v3_stby *
  page134_i2
#CELL
  mstr_discrete res *
  page134_i3
#ISCELL
  mstr_standard offpage *
  page134_i5
#ISCELL
  mstr_standard offpage *
  page134_i6
#ISCELL
  mstr_standard offpage *
  page134_i7
#ISCELL
  mstr_symbols p1v05_pch_stby *
  page134_i8
#CELL
  mstr_discrete res *
  page134_i9
#ISCELL
  mstr_misc dns *
  *
#ISCELL
  mstr_symbols cad_note *
  *
#ISCELL
  mstr_symbols design_note *
  *
#ISCELL
  mstr_symbols intel_corp_bpage *
  *
#ISCELL
  mstr_symbols p3v3_stby *
  page135_i106
#CELL
  mstr_discrete res *
  page135_i107
#ISCELL
  mstr_standard offpage *
  page135_i108
#ISCELL
  mstr_standard offpage *
  page135_i109
#ISCELL
  mstr_standard offpage *
  page135_i110
#ISCELL
  mstr_symbols p3v3_stby *
  page135_i111
#CELL
  mstr_discrete res *
  page135_i112
#CELL
  mstr_discrete res *
  page135_i113
#ISCELL
  mstr_symbols gnd *
  page135_i114
#ISCELL
  mstr_standard offpage *
  page135_i115
#ISCELL
  mstr_symbols p3v3_stby *
  page135_i116
#CELL
  mstr_discrete res *
  page135_i117
#CELL
  mstr_discrete res *
  page135_i118
#ISCELL
  mstr_symbols p3v3_stby *
  page135_i119
#CELL
  mstr_discrete res *
  page135_i120
#CELL
  mstr_discrete res *
  page135_i121
#ISCELL
  mstr_symbols p3v3_stby *
  page135_i122
#ISCELL
  mstr_symbols gnd *
  page135_i123
#CELL
  mstr_conn conn12_c73564003 *
  page135_i124
#ISCELL
  mstr_symbols gnd *
  page135_i125
#ISCELL
  mstr_standard offpage *
  page135_i126
#ISCELL
  mstr_standard offpage *
  page135_i127
#ISCELL
  mstr_symbols p3v3_stby *
  page135_i128
#CELL
  mstr_discrete res *
  page135_i129
#ISCELL
  mstr_symbols gnd *
  page135_i130
#CELL
  mstr_conn conn4_d42317002 *
  page135_i131
#ISCELL
  mstr_symbols bom_note *
  *
#ISCELL
  mstr_symbols cad_note *
  *
#ISCELL
  mstr_symbols design_note *
  *
#ISCELL
  mstr_symbols intel_corp_bpage *
  *
#CELL
  mstr_discrete res *
  page136_i101
#CELL
  mstr_discrete res *
  page136_i102
#ISCELL
  mstr_symbols gnd *
  page136_i103
#ISCELL
  mstr_symbols p3v3_stby *
  page136_i124
#ISCELL
  mstr_standard offpage *
  page136_i125
#CELL
  mstr_discrete res *
  page136_i126
#ISCELL
  mstr_symbols p3v3_stby *
  page136_i127
#CELL
  dev_discrete cap_a *
  page136_i128
#ISCELL
  mstr_symbols gnd *
  page136_i129
#CELL
  mstr_ttl ttl1g126_a *
  page136_i130
#ISCELL
  mstr_symbols p3v3_stby *
  page136_i131
#ISCELL
  mstr_standard offpage *
  page136_i132
#CELL
  mstr_discrete res *
  page136_i133
#CELL
  mstr_discrete fet_n *
  page136_i134
#ISCELL
  mstr_symbols gnd *
  page136_i135
#ISCELL
  mstr_standard offpage *
  page136_i136
#CELL
  mstr_discrete res *
  page136_i139
#CELL
  mstr_discrete res *
  page136_i140
#ISCELL
  mstr_symbols gnd *
  page136_i141
#CELL
  mstr_discrete res *
  page136_i147
#CELL
  mstr_discrete res *
  page136_i148
#ISCELL
  mstr_symbols gnd *
  page136_i152
#ISCELL
  mstr_symbols p3v3_stby *
  page136_i154
#CELL
  mstr_discrete res *
  page136_i155
#CELL
  mstr_discrete res *
  page136_i156
#ISCELL
  mstr_symbols gnd *
  page136_i157
#ISCELL
  mstr_standard offpage *
  page136_i162
#ISCELL
  mstr_standard offpage *
  page136_i165
#ISCELL
  mstr_standard offpage *
  page136_i170
#CELL
  mstr_conn conn12_c73564003 *
  page136_i174
#ISCELL
  mstr_standard offpage *
  page136_i175
#ISCELL
  mstr_misc dns *
  *
#ISCELL
  mstr_symbols bom_note *
  *
#ISCELL
  mstr_symbols cad_note *
  *
#ISCELL
  mstr_symbols design_note *
  *
#ISCELL
  mstr_symbols intel_corp_bpage *
  *
#CELL
  mstr_discrete res *
  page137_i11
#ISCELL
  mstr_standard offpage *
  page137_i126
#CELL
  mstr_conn conn12_c73564003 *
  page137_i128
#ISCELL
  mstr_standard offpage *
  page137_i129
#CELL
  mstr_discrete res *
  page137_i13
#CELL
  mstr_discrete res *
  page137_i133
#ISCELL
  mstr_standard offpage *
  page137_i134
#ISCELL
  mstr_standard offpage *
  page137_i135
#ISCELL
  mstr_standard offpage *
  page137_i136
#CELL
  dev_discrete cap_a *
  page137_i14
#CELL
  mstr_discrete res *
  page137_i140
#ISCELL
  mstr_symbols gnd *
  page137_i141
#CELL
  mstr_discrete res *
  page137_i142
#ISCELL
  mstr_symbols p3v3_stby *
  page137_i143
#CELL
  mstr_discrete res *
  page137_i144
#ISCELL
  mstr_symbols gnd *
  page137_i145
#ISCELL
  mstr_symbols p3v3_stby *
  page137_i146
#ISCELL
  mstr_standard offpage *
  page137_i148
#CELL
  mstr_discrete res *
  page137_i149
#CELL
  mstr_discrete res *
  page137_i15
#ISCELL
  mstr_symbols gnd *
  page137_i16
#ISCELL
  mstr_standard offpage *
  page137_i17
#CELL
  mstr_discrete res *
  page137_i19
#CELL
  dev_discrete cap_a *
  page137_i20
#ISCELL
  mstr_symbols gnd *
  page137_i21
#CELL
  mstr_discrete res *
  page137_i67
#ISCELL
  mstr_symbols p3v3_stby *
  page137_i68
#CELL
  mstr_discrete res *
  page137_i69
#ISCELL
  mstr_symbols gnd *
  page137_i70
#ISCELL
  mstr_symbols p3v3_rtc_stby *
  page137_i78
#ISCELL
  mstr_symbols p3v3_rtc_stby *
  page137_i79
#ISCELL
  mstr_misc dns *
  *
#ISCELL
  mstr_symbols cad_note *
  *
#ISCELL
  mstr_symbols design_note *
  *
#ISCELL
  mstr_symbols intel_corp_bpage *
  *
#ISCELL
  mstr_standard offpage *
  page138_i104
#ISCELL
  mstr_standard offpage *
  page138_i105
#ISCELL
  mstr_standard offpage *
  page138_i108
#ISCELL
  mstr_standard offpage *
  page138_i111
#ISCELL
  mstr_standard offpage *
  page138_i114
#ISCELL
  mstr_standard offpage *
  page138_i115
#ISCELL
  mstr_standard offpage *
  page138_i126
#ISCELL
  mstr_standard offpage *
  page138_i127
#ISCELL
  mstr_symbols p3v3_stby *
  page138_i138
#ISCELL
  mstr_symbols p3v3_stby *
  page138_i139
#ISCELL
  mstr_symbols p3v3_stby *
  page138_i140
#ISCELL
  mstr_symbols p3v3_stby *
  page138_i141
#ISCELL
  mstr_symbols p3v3_stby *
  page138_i144
#ISCELL
  mstr_symbols p3v3_stby *
  page138_i145
#ISCELL
  mstr_symbols p3v3_stby *
  page138_i150
#ISCELL
  mstr_symbols p3v3_stby *
  page138_i151
#ISCELL
  mstr_standard offpage *
  page138_i154
#ISCELL
  mstr_standard offpage *
  page138_i155
#ISCELL
  mstr_standard offpage *
  page138_i156
#ISCELL
  mstr_standard offpage *
  page138_i157
#CELL
  mstr_discrete res *
  page138_i158
#CELL
  mstr_discrete res *
  page138_i159
#CELL
  mstr_discrete res *
  page138_i163
#CELL
  mstr_discrete res *
  page138_i164
#CELL
  mstr_discrete res *
  page138_i165
#CELL
  mstr_discrete res *
  page138_i166
#CELL
  mstr_discrete res *
  page138_i167
#CELL
  mstr_discrete res *
  page138_i168
#CELL
  mstr_discrete res *
  page138_i169
#CELL
  mstr_discrete res *
  page138_i170
#CELL
  mstr_discrete res *
  page138_i171
#CELL
  mstr_discrete res *
  page138_i175
#ISCELL
  mstr_symbols p3v3_stby *
  page138_i179
#ISCELL
  mstr_symbols p3v3_stby *
  page138_i180
#ISCELL
  mstr_standard offpage *
  page138_i181
#ISCELL
  mstr_standard offpage *
  page138_i182
#CELL
  mstr_discrete res *
  page138_i186
#CELL
  mstr_discrete res *
  page138_i187
#ISCELL
  mstr_standard offpage *
  page138_i188
#ISCELL
  mstr_standard offpage *
  page138_i189
#CELL
  mstr_discrete res *
  page138_i194
#CELL
  mstr_discrete res *
  page138_i195
#ISCELL
  mstr_standard offpage *
  page138_i196
#ISCELL
  mstr_standard offpage *
  page138_i197
#CELL
  mstr_discrete res *
  page138_i198
#CELL
  mstr_discrete res *
  page138_i199
#ISCELL
  mstr_symbols p3v3_stby *
  page138_i200
#ISCELL
  mstr_symbols p3v3_stby *
  page138_i201
#CELL
  mstr_discrete res *
  page138_i202
#ISCELL
  mstr_symbols p3v3_stby *
  page138_i203
#ISCELL
  mstr_symbols p3v3_stby *
  page138_i204
#CELL
  mstr_discrete res *
  page138_i205
#ISCELL
  mstr_standard offpage *
  page138_i45
#ISCELL
  mstr_standard offpage *
  page138_i46
#ISCELL
  mstr_standard offpage *
  page138_i49
#ISCELL
  mstr_standard offpage *
  page138_i50
#ISCELL
  mstr_standard offpage *
  page138_i51
#ISCELL
  mstr_standard offpage *
  page138_i52
#ISCELL
  mstr_standard offpage *
  page138_i53
#ISCELL
  mstr_standard offpage *
  page138_i54
#ISCELL
  mstr_standard offpage *
  page138_i59
#ISCELL
  mstr_standard offpage *
  page138_i60
#CELL
  mstr_discrete res *
  page138_i83
#CELL
  mstr_discrete res *
  page138_i84
#CELL
  mstr_discrete res *
  page138_i87
#CELL
  mstr_discrete res *
  page138_i88
#CELL
  mstr_discrete res *
  page138_i89
#CELL
  mstr_discrete res *
  page138_i90
#CELL
  mstr_discrete res *
  page138_i97
#CELL
  mstr_discrete res *
  page138_i98
#ISCELL
  mstr_misc dns *
  *
#ISCELL
  mstr_symbols cad_note *
  *
#ISCELL
  mstr_symbols design_note *
  *
#ISCELL
  mstr_symbols intel_corp_bpage *
  *
#ISCELL
  mstr_standard offpage *
  page139_i101
#ISCELL
  mstr_standard offpage *
  page139_i102
#ISCELL
  mstr_standard offpage *
  page139_i103
#ISCELL
  mstr_standard offpage *
  page139_i104
#ISCELL
  mstr_standard offpage *
  page139_i105
#ISCELL
  mstr_standard offpage *
  page139_i106
#ISCELL
  mstr_standard offpage *
  page139_i107
#ISCELL
  mstr_standard offpage *
  page139_i108
#CELL
  mstr_discrete crystal *
  page139_i109
#CELL
  mstr_discrete res *
  page139_i110
#ISCELL
  mstr_symbols gnd *
  page139_i113
#ISCELL
  mstr_symbols gnd *
  page139_i114
#ISCELL
  mstr_standard offpage *
  page139_i115
#ISCELL
  mstr_standard offpage *
  page139_i116
#ISCELL
  mstr_standard offpage *
  page139_i117
#ISCELL
  mstr_standard offpage *
  page139_i118
#ISCELL
  mstr_standard offpage *
  page139_i127
#CELL
  mstr_discrete res *
  page139_i128
#CELL
  mstr_discrete res *
  page139_i129
#CELL
  mstr_discrete res *
  page139_i130
#ISCELL
  mstr_standard offpage *
  page139_i131
#ISCELL
  mstr_standard offpage *
  page139_i132
#ISCELL
  mstr_standard offpage *
  page139_i133
#CELL
  mstr_discrete cap *
  page139_i134
#CELL
  mstr_discrete cap *
  page139_i135
#CELL
  mstr_discrete cap *
  page139_i136
#ISCELL
  mstr_symbols gnd *
  page139_i137
#ISCELL
  mstr_symbols gnd *
  page139_i138
#ISCELL
  mstr_symbols gnd *
  page139_i139
#CELL
  mstr_discrete cap *
  page139_i142
#CELL
  dev_discrete cap_a *
  page139_i143
#CELL
  dev_discrete cap_a *
  page139_i144
#CELL
  dev_discrete cap_a *
  page139_i145
#CELL
  dev_discrete cap_a *
  page139_i146
#CELL
  dev_discrete cap_a *
  page139_i149
#CELL
  dev_discrete cap_a *
  page139_i150
#CELL
  dev_discrete cap_a *
  page139_i151
#CELL
  dev_discrete cap_a *
  page139_i152
#CELL
  mstr_discrete cap *
  page139_i153
#ISCELL
  mstr_symbols p1v5_lan *
  page139_i154
#CELL
  dev_discrete cap_a *
  page139_i157
#CELL
  dev_discrete cap_a *
  page139_i158
#CELL
  dev_discrete cap_a *
  page139_i159
#CELL
  dev_discrete cap_a *
  page139_i160
#CELL
  mstr_discrete cap *
  page139_i161
#ISCELL
  mstr_symbols p0v9_lan *
  page139_i162
#CELL
  dev_discrete cap_a *
  page139_i163
#ISCELL
  mstr_symbols gnd *
  page139_i164
#ISCELL
  mstr_standard offpage *
  page139_i166
#ISCELL
  mstr_standard offpage *
  page139_i167
#ISCELL
  mstr_standard offpage *
  page139_i172
#CELL
  mstr_discrete res *
  page139_i173
#CELL
  mstr_discrete res *
  page139_i174
#ISCELL
  mstr_standard offpage *
  page139_i175
#ISCELL
  mstr_symbols gnd *
  page139_i176
#CELL
  mstr_discrete res *
  page139_i177
#CELL
  mstr_discrete res *
  page139_i178
#CELL
  mstr_discrete res *
  page139_i179
#ISCELL
  mstr_symbols p3v3_stby *
  page139_i180
#CELL
  mstr_discrete res *
  page139_i181
#ISCELL
  mstr_symbols p3v3_stby *
  page139_i182
#ISCELL
  mstr_standard offpage *
  page139_i183
#ISCELL
  mstr_standard offpage *
  page139_i184
#ISCELL
  mstr_standard offpage *
  page139_i185
#ISCELL
  mstr_symbols p3v3_stby *
  page139_i186
#ISCELL
  mstr_symbols p3v3_stby *
  page139_i188
#ISCELL
  mstr_symbols p3v3_stby *
  page139_i189
#ISCELL
  mstr_standard offpage *
  page139_i191
#ISCELL
  mstr_standard offpage *
  page139_i192
#CELL
  mstr_discrete res *
  page139_i193
#ISCELL
  mstr_symbols p3v3_stby *
  page139_i194
#CELL
  mstr_discrete res *
  page139_i195
#ISCELL
  mstr_standard offpage *
  page139_i197
#ISCELL
  mstr_standard offpage *
  page139_i198
#ISCELL
  mstr_symbols p3v3_stby *
  page139_i199
#CELL
  mstr_discrete res *
  page139_i200
#CELL
  mstr_discrete res *
  page139_i201
#ISCELL
  mstr_standard offpage *
  page139_i202
#ISCELL
  mstr_standard offpage *
  page139_i203
#ISCELL
  mstr_symbols gnd *
  page139_i204
#ISCELL
  mstr_standard offpage *
  page139_i206
#ISCELL
  mstr_symbols gnd *
  page139_i207
#ISCELL
  mstr_standard offpage *
  page139_i209
#ISCELL
  mstr_symbols gnd *
  page139_i211
#CELL
  mstr_discrete res *
  page139_i212
#CELL
  mstr_discrete res *
  page139_i213
#CELL
  mstr_discrete res *
  page139_i214
#ISCELL
  mstr_standard offpage *
  page139_i218
#ISCELL
  mstr_standard offpage *
  page139_i219
#ISCELL
  mstr_standard offpage *
  page139_i220
#ISCELL
  mstr_standard offpage *
  page139_i223
#ISCELL
  mstr_standard offpage *
  page139_i224
#CELL
  mstr_discrete res *
  page139_i225
#ISCELL
  mstr_standard offpage *
  page139_i226
#ISCELL
  mstr_standard offpage *
  page139_i227
#CELL
  mstr_discrete res *
  page139_i228
#CELL
  mstr_discrete res *
  page139_i229
#ISCELL
  mstr_standard offpage *
  page139_i230
#ISCELL
  mstr_standard offpage *
  page139_i231
#ISCELL
  mstr_standard offpage *
  page139_i233
#CELL
  mstr_discrete res *
  page139_i235
#ISCELL
  mstr_standard offpage *
  page139_i236
#CELL
  mstr_discrete res *
  page139_i237
#CELL
  mstr_discrete res *
  page139_i238
#CELL
  mstr_discrete res *
  page139_i239
#CELL
  mstr_discrete res *
  page139_i240
#CELL
  dev_discrete cap_a *
  page139_i241
#ISCELL
  mstr_symbols gnd *
  page139_i243
#CELL
  w_hdl sc22u16v5mx-4-gp *
  page139_i244
#CELL
  w_hdl sc22u16v5mx-4-gp *
  page139_i245
#CELL
  w_hdl sc22u16v5mx-4-gp *
  page139_i246
#ISCELL
  mstr_symbols gnd *
  page139_i247
#CELL
  w_hdl sc22u16v5mx-4-gp *
  page139_i248
#CELL
  mstr_discrete cap *
  page139_i249
#CELL
  mstr_discrete cap *
  page139_i250
#ISCELL
  mstr_standard offpage *
  page139_i251
#CELL
  mstr_discrete res *
  page139_i252
#CELL
  mstr_intel springville *
  page139_i72
#ISCELL
  mstr_symbols p0v9_lan *
  page139_i73
#ISCELL
  mstr_symbols p1v5_lan *
  page139_i74
#CELL
  mstr_discrete cap *
  page139_i76
#ISCELL
  mstr_symbols gnd *
  page139_i77
#ISCELL
  mstr_standard offpage *
  page139_i84
#ISCELL
  mstr_standard offpage *
  page139_i85
#ISCELL
  mstr_standard offpage *
  page139_i86
#CELL
  dev_discrete cap_a *
  page139_i87
#CELL
  dev_discrete cap_a *
  page139_i88
#CELL
  dev_discrete cap_a *
  page139_i89
#CELL
  dev_discrete cap_a *
  page139_i90
#ISCELL
  mstr_standard offpage *
  page139_i91
#ISCELL
  mstr_standard offpage *
  page139_i92
#ISCELL
  mstr_standard offpage *
  page139_i93
#ISCELL
  mstr_standard offpage *
  page139_i94
#ISCELL
  mstr_misc dns *
  *
#ISCELL
  mstr_symbols intel_corp_bpage *
  *
#CELL
  mstr_memory m25pe16 *
  page140_i1
#CELL
  mstr_discrete res *
  page140_i10
#CELL
  mstr_discrete res *
  page140_i11
#CELL
  mstr_discrete res *
  page140_i12
#ISCELL
  mstr_symbols p3v3_stby *
  page140_i13
#CELL
  mstr_discrete res *
  page140_i14
#ISCELL
  mstr_symbols gnd *
  page140_i16
#CELL
  mstr_discrete res *
  page140_i17
#CELL
  dev_discrete cap_a *
  page140_i3
#ISCELL
  mstr_symbols gnd *
  page140_i4
#ISCELL
  mstr_standard offpage *
  page140_i5
#ISCELL
  mstr_standard offpage *
  page140_i6
#ISCELL
  mstr_standard offpage *
  page140_i7
#ISCELL
  mstr_standard offpage *
  page140_i8
#ISCELL
  mstr_symbols gnd *
  page140_i9
#ISCELL
  mstr_misc dns *
  *
#ISCELL
  mstr_symbols intel_corp_bpage *
  *
#CELL
  mstr_discrete cap *
  page141_i100
#CELL
  mstr_discrete cap *
  page141_i101
#CELL
  mstr_discrete cap *
  page141_i102
#ISCELL
  mstr_standard offpage *
  page141_i103
#ISCELL
  mstr_standard offpage *
  page141_i104
#ISCELL
  mstr_standard offpage *
  page141_i105
#ISCELL
  mstr_standard offpage *
  page141_i106
#CELL
  w_hdl skt-rj45-led-xfor-1-gp *
  page141_i129
#CELL
  mstr_discrete res *
  page141_i134
#CELL
  mstr_discrete res *
  page141_i135
#ISCELL
  mstr_standard offpage *
  page141_i136
#ISCELL
  mstr_standard offpage *
  page141_i137
#CELL
  mstr_discrete cap *
  page141_i138
#ISCELL
  mstr_symbols gnd *
  page141_i139
#CELL
  mstr_discrete cap *
  page141_i140
#ISCELL
  mstr_symbols gnd *
  page141_i141
#ISCELL
  mstr_standard offpage *
  page141_i142
#ISCELL
  mstr_standard offpage *
  page141_i143
#ISCELL
  mstr_standard offpage *
  page141_i144
#ISCELL
  mstr_standard offpage *
  page141_i145
#ISCELL
  mstr_symbols gnd *
  page141_i146
#ISCELL
  mstr_standard offpage *
  page141_i147
#ISCELL
  mstr_standard offpage *
  page141_i148
#ISCELL
  mstr_standard offpage *
  page141_i149
#ISCELL
  mstr_standard offpage *
  page141_i150
#ISCELL
  mstr_standard offpage *
  page141_i151
#CELL
  mstr_discrete cap *
  page141_i152
#ISCELL
  mstr_symbols p3v3_stby *
  page141_i153
#ISCELL
  mstr_symbols gnd *
  page141_i155
#CELL
  mstr_discrete res *
  page141_i156
#CELL
  mstr_discrete res *
  page141_i157
#ISCELL
  mstr_standard offpage *
  page141_i158
#CELL
  mstr_discrete cap *
  page141_i159
#ISCELL
  mstr_symbols gnd *
  page141_i160
#ISCELL
  mstr_symbols gnd *
  page141_i161
#ISCELL
  mstr_symbols gnd *
  page141_i162
#ISCELL
  mstr_standard offpage *
  page141_i42
#CELL
  dev_discrete cap_a *
  page141_i46
#CELL
  dev_discrete cap_a *
  page141_i47
#CELL
  mstr_discrete cap *
  page141_i48
#ISCELL
  mstr_standard offpage *
  page141_i49
#ISCELL
  mstr_symbols gnd *
  page141_i50
#CELL
  mstr_discrete res *
  page141_i75
#CELL
  mstr_discrete res *
  page141_i76
#CELL
  mstr_discrete res *
  page141_i77
#CELL
  mstr_discrete res *
  page141_i78
#CELL
  mstr_discrete res *
  page141_i79
#CELL
  mstr_discrete res *
  page141_i80
#CELL
  mstr_discrete res *
  page141_i81
#CELL
  mstr_discrete res *
  page141_i82
#ISCELL
  mstr_standard offpage *
  page141_i83
#ISCELL
  mstr_standard offpage *
  page141_i84
#ISCELL
  mstr_standard offpage *
  page141_i85
#ISCELL
  mstr_standard offpage *
  page141_i86
#ISCELL
  mstr_standard offpage *
  page141_i87
#ISCELL
  mstr_standard offpage *
  page141_i88
#ISCELL
  mstr_standard offpage *
  page141_i89
#ISCELL
  mstr_standard offpage *
  page141_i90
#ISCELL
  mstr_standard offpage *
  page141_i91
#ISCELL
  mstr_standard offpage *
  page141_i92
#ISCELL
  mstr_standard offpage *
  page141_i93
#ISCELL
  mstr_standard offpage *
  page141_i94
#ISCELL
  mstr_standard offpage *
  page141_i95
#ISCELL
  mstr_standard offpage *
  page141_i96
#ISCELL
  mstr_standard offpage *
  page141_i97
#ISCELL
  mstr_standard offpage *
  page141_i98
#CELL
  mstr_discrete cap *
  page141_i99
#ISCELL
  mstr_misc dns *
  *
#ISCELL
  mstr_symbols cad_note *
  *
#ISCELL
  mstr_symbols design_note *
  *
#ISCELL
  mstr_symbols intel_corp_bpage *
  *
#CELL
  mstr_ttl ttl1g126_a *
  page142_i1
#ISCELL
  mstr_standard offpage *
  page142_i11
#ISCELL
  mstr_standard offpage *
  page142_i12
#ISCELL
  mstr_standard offpage *
  page142_i13
#ISCELL
  mstr_standard offpage *
  page142_i17
#CELL
  mstr_discrete res *
  page142_i18
#ISCELL
  mstr_standard offpage *
  page142_i19
#CELL
  mstr_discrete res *
  page142_i2
#CELL
  dev_discrete cap_a *
  page142_i20
#ISCELL
  mstr_symbols p3v3_stby *
  page142_i21
#ISCELL
  mstr_symbols gnd *
  page142_i22
#ISCELL
  mstr_symbols p3v3_stby *
  page142_i24
#CELL
  mstr_discrete res *
  page142_i3
#CELL
  mstr_discrete res *
  page142_i30
#CELL
  mstr_discrete res *
  page142_i31
#CELL
  mstr_discrete res *
  page142_i32
#CELL
  mstr_discrete res *
  page142_i33
#CELL
  w_hdl 2k15r2f-1-gp *
  page142_i34
#CELL
  w_hdl 2k15r2f-1-gp *
  page142_i35
#ISCELL
  mstr_symbols p3v3_stby *
  page142_i4
#ISCELL
  mstr_standard offpage *
  page142_i5
#ISCELL
  mstr_symbols intel_corp_bpage *
  *
#ISCELL
  mstr_standard offpage *
  page143_i10
#ISCELL
  mstr_standard offpage *
  page143_i11
#ISCELL
  mstr_standard offpage *
  page143_i12
#ISCELL
  mstr_standard offpage *
  page143_i13
#ISCELL
  mstr_standard offpage *
  page143_i14
#ISCELL
  mstr_standard offpage *
  page143_i15
#ISCELL
  mstr_standard offpage *
  page143_i16
#ISCELL
  mstr_standard offpage *
  page143_i17
#ISCELL
  mstr_standard offpage *
  page143_i18
#ISCELL
  mstr_standard offpage *
  page143_i19
#ISCELL
  mstr_standard offpage *
  page143_i2
#ISCELL
  mstr_standard offpage *
  page143_i20
#ISCELL
  mstr_standard offpage *
  page143_i21
#ISCELL
  mstr_standard offpage *
  page143_i23
#ISCELL
  mstr_standard offpage *
  page143_i24
#ISCELL
  mstr_standard offpage *
  page143_i25
#ISCELL
  mstr_standard offpage *
  page143_i26
#ISCELL
  mstr_standard offpage *
  page143_i27
#ISCELL
  mstr_standard offpage *
  page143_i28
#ISCELL
  mstr_standard offpage *
  page143_i29
#ISCELL
  mstr_standard offpage *
  page143_i3
#ISCELL
  mstr_standard offpage *
  page143_i30
#ISCELL
  mstr_standard offpage *
  page143_i31
#ISCELL
  mstr_standard offpage *
  page143_i33
#ISCELL
  mstr_standard offpage *
  page143_i34
#ISCELL
  mstr_standard offpage *
  page143_i36
#ISCELL
  mstr_standard offpage *
  page143_i37
#ISCELL
  mstr_standard offpage *
  page143_i38
#ISCELL
  mstr_standard offpage *
  page143_i39
#ISCELL
  mstr_standard offpage *
  page143_i4
#ISCELL
  mstr_standard offpage *
  page143_i40
#ISCELL
  mstr_standard offpage *
  page143_i41
#ISCELL
  mstr_standard offpage *
  page143_i42
#ISCELL
  mstr_standard offpage *
  page143_i43
#ISCELL
  mstr_standard offpage *
  page143_i44
#ISCELL
  mstr_standard offpage *
  page143_i45
#ISCELL
  mstr_standard offpage *
  page143_i46
#ISCELL
  mstr_standard offpage *
  page143_i47
#ISCELL
  mstr_standard offpage *
  page143_i48
#ISCELL
  mstr_standard offpage *
  page143_i49
#ISCELL
  mstr_standard offpage *
  page143_i5
#ISCELL
  mstr_standard offpage *
  page143_i50
#ISCELL
  mstr_standard offpage *
  page143_i51
#ISCELL
  mstr_standard offpage *
  page143_i52
#ISCELL
  mstr_symbols gnd *
  page143_i57
#CELL
  mstr_discrete res *
  page143_i58
#ISCELL
  mstr_standard offpage *
  page143_i6
#CELL
  w_hdl ast2520a1-gp-gp *
  page143_i63
#ISCELL
  mstr_standard offpage *
  page143_i64
#ISCELL
  mstr_symbols gnd *
  page143_i65
#CELL
  dev_discrete cap_a *
  page143_i67
#ISCELL
  mstr_standard offpage *
  page143_i7
#ISCELL
  mstr_standard offpage *
  page143_i8
#ISCELL
  mstr_standard offpage *
  page143_i9
#ISCELL
  mstr_misc dns *
  *
#ISCELL
  mstr_symbols intel_corp_bpage *
  *
#ISCELL
  mstr_standard offpage *
  page144_i100
#ISCELL
  mstr_standard offpage *
  page144_i101
#ISCELL
  mstr_standard offpage *
  page144_i102
#ISCELL
  mstr_standard offpage *
  page144_i103
#ISCELL
  mstr_standard offpage *
  page144_i104
#ISCELL
  mstr_standard offpage *
  page144_i105
#ISCELL
  mstr_standard offpage *
  page144_i106
#ISCELL
  mstr_standard offpage *
  page144_i107
#ISCELL
  mstr_standard offpage *
  page144_i108
#ISCELL
  mstr_standard offpage *
  page144_i109
#ISCELL
  mstr_standard offpage *
  page144_i110
#ISCELL
  mstr_standard offpage *
  page144_i111
#ISCELL
  mstr_standard offpage *
  page144_i112
#ISCELL
  mstr_standard offpage *
  page144_i113
#CELL
  mstr_discrete res *
  page144_i114
#ISCELL
  mstr_standard offpage *
  page144_i116
#CELL
  mstr_discrete res *
  page144_i118
#ISCELL
  mstr_standard offpage *
  page144_i121
#ISCELL
  mstr_standard offpage *
  page144_i125
#ISCELL
  mstr_standard offpage *
  page144_i126
#ISCELL
  mstr_standard offpage *
  page144_i127
#ISCELL
  mstr_standard offpage *
  page144_i128
#ISCELL
  mstr_standard offpage *
  page144_i129
#ISCELL
  mstr_standard offpage *
  page144_i130
#ISCELL
  mstr_standard offpage *
  page144_i133
#ISCELL
  mstr_standard offpage *
  page144_i134
#ISCELL
  mstr_standard offpage *
  page144_i135
#ISCELL
  mstr_standard offpage *
  page144_i136
#ISCELL
  mstr_standard offpage *
  page144_i137
#ISCELL
  mstr_standard offpage *
  page144_i138
#CELL
  mstr_discrete res *
  page144_i139
#CELL
  mstr_discrete res *
  page144_i140
#CELL
  mstr_discrete res *
  page144_i141
#ISCELL
  mstr_symbols gnd *
  page144_i142
#ISCELL
  mstr_symbols gnd *
  page144_i143
#ISCELL
  mstr_symbols gnd *
  page144_i144
#ISCELL
  mstr_standard offpage *
  page144_i146
#ISCELL
  mstr_standard offpage *
  page144_i147
#CELL
  mstr_discrete res *
  page144_i148
#ISCELL
  mstr_standard offpage *
  page144_i149
#CELL
  w_hdl 18kr2f-gp *
  page144_i150
#CELL
  mstr_discrete res *
  page144_i151
#ISCELL
  mstr_standard offpage *
  page144_i152
#ISCELL
  mstr_standard offpage *
  page144_i153
#ISCELL
  mstr_standard offpage *
  page144_i28
#ISCELL
  mstr_standard offpage *
  page144_i29
#ISCELL
  mstr_standard offpage *
  page144_i32
#ISCELL
  mstr_standard offpage *
  page144_i37
#ISCELL
  mstr_standard offpage *
  page144_i44
#ISCELL
  mstr_standard offpage *
  page144_i47
#ISCELL
  mstr_standard offpage *
  page144_i48
#ISCELL
  mstr_standard offpage *
  page144_i49
#ISCELL
  mstr_standard offpage *
  page144_i50
#ISCELL
  mstr_standard offpage *
  page144_i51
#ISCELL
  mstr_standard offpage *
  page144_i52
#ISCELL
  mstr_standard offpage *
  page144_i53
#ISCELL
  mstr_standard offpage *
  page144_i54
#ISCELL
  mstr_standard offpage *
  page144_i55
#ISCELL
  mstr_standard offpage *
  page144_i56
#CELL
  mstr_discrete res *
  page144_i57
#CELL
  mstr_discrete res *
  page144_i58
#CELL
  mstr_discrete res *
  page144_i59
#ISCELL
  mstr_standard offpage *
  page144_i67
#ISCELL
  mstr_standard offpage *
  page144_i70
#ISCELL
  mstr_symbols gnd *
  page144_i72
#ISCELL
  mstr_standard offpage *
  page144_i74
#ISCELL
  mstr_standard offpage *
  page144_i93
#CELL
  w_hdl ast2520a1-gp-gp *
  page144_i95
#ISCELL
  mstr_standard offpage *
  page144_i96
#ISCELL
  mstr_standard offpage *
  page144_i97
#ISCELL
  mstr_misc dns *
  *
#ISCELL
  mstr_symbols cad_note *
  *
#ISCELL
  mstr_symbols intel_corp_bpage *
  *
#CELL
  mstr_discrete res *
  page145_i10
#CELL
  mstr_discrete res *
  page145_i100
#CELL
  mstr_discrete res *
  page145_i101
#ISCELL
  mstr_symbols gnd *
  page145_i102
#ISCELL
  mstr_standard offpage *
  page145_i103
#ISCELL
  mstr_standard offpage *
  page145_i104
#CELL
  mstr_discrete res *
  page145_i11
#CELL
  w_hdl ast2520a1-gp-gp *
  page145_i117
#CELL
  w_hdl 200r2f-l1-gp *
  page145_i118
#CELL
  mstr_discrete res *
  page145_i119
#ISCELL
  mstr_standard offpage *
  page145_i12
#CELL
  mstr_discrete res *
  page145_i120
#ISCELL
  mstr_standard offpage *
  page145_i121
#ISCELL
  mstr_standard offpage *
  page145_i122
#ISCELL
  mstr_standard offpage *
  page145_i123
#ISCELL
  mstr_standard offpage *
  page145_i124
#ISCELL
  mstr_standard offpage *
  page145_i128
#ISCELL
  mstr_symbols gnd *
  page145_i13
#CELL
  mstr_discrete res *
  page145_i136
#ISCELL
  mstr_standard offpage *
  page145_i137
#ISCELL
  mstr_standard offpage *
  page145_i138
#ISCELL
  mstr_standard offpage *
  page145_i139
#CELL
  mstr_discrete res *
  page145_i14
#ISCELL
  mstr_standard offpage *
  page145_i140
#ISCELL
  mstr_standard offpage *
  page145_i143
#ISCELL
  mstr_standard offpage *
  page145_i146
#ISCELL
  mstr_standard offpage *
  page145_i147
#CELL
  dev_discrete cap_a *
  page145_i15
#ISCELL
  mstr_standard offpage *
  page145_i154
#ISCELL
  mstr_standard offpage *
  page145_i155
#CELL
  dev_discrete cap_a *
  page145_i158
#CELL
  dev_discrete cap_a *
  page145_i159
#ISCELL
  mstr_symbols p3v3_stby *
  page145_i16
#CELL
  mstr_discrete res *
  page145_i160
#ISCELL
  mstr_standard offpage *
  page145_i161
#ISCELL
  mstr_standard offpage *
  page145_i162
#CELL
  mstr_discrete res *
  page145_i163
#CELL
  mstr_discrete res *
  page145_i164
#ISCELL
  mstr_standard offpage *
  page145_i165
#ISCELL
  mstr_standard offpage *
  page145_i166
#ISCELL
  mstr_standard offpage *
  page145_i167
#ISCELL
  mstr_standard offpage *
  page145_i168
#ISCELL
  mstr_standard offpage *
  page145_i169
#ISCELL
  mstr_symbols gnd *
  page145_i17
#ISCELL
  mstr_standard offpage *
  page145_i170
#ISCELL
  mstr_standard offpage *
  page145_i172
#CELL
  mstr_discrete res *
  page145_i173
#ISCELL
  mstr_standard offpage *
  page145_i174
#CELL
  mstr_discrete res *
  page145_i175
#CELL
  mstr_discrete res *
  page145_i176
#ISCELL
  mstr_standard offpage *
  page145_i177
#CELL
  mstr_discrete res *
  page145_i20
#ISCELL
  mstr_standard offpage *
  page145_i21
#CELL
  mstr_discrete res *
  page145_i22
#ISCELL
  mstr_symbols gnd *
  page145_i23
#ISCELL
  mstr_standard offpage *
  page145_i24
#ISCELL
  mstr_standard offpage *
  page145_i25
#ISCELL
  mstr_standard offpage *
  page145_i26
#ISCELL
  mstr_standard offpage *
  page145_i27
#ISCELL
  mstr_standard offpage *
  page145_i28
#ISCELL
  mstr_standard offpage *
  page145_i29
#CELL
  mstr_discrete res *
  page145_i30
#CELL
  mstr_discrete res *
  page145_i31
#ISCELL
  mstr_symbols gnd *
  page145_i32
#ISCELL
  mstr_symbols gnd *
  page145_i33
#CELL
  mstr_discrete res *
  page145_i34
#ISCELL
  mstr_symbols gnd *
  page145_i35
#CELL
  mstr_discrete res *
  page145_i36
#ISCELL
  mstr_symbols gnd *
  page145_i37
#CELL
  mstr_discrete res *
  page145_i38
#ISCELL
  mstr_symbols gnd *
  page145_i39
#ISCELL
  mstr_standard offpage *
  page145_i4
#ISCELL
  mstr_standard offpage *
  page145_i41
#ISCELL
  mstr_standard offpage *
  page145_i42
#ISCELL
  mstr_standard offpage *
  page145_i43
#ISCELL
  mstr_symbols gnd *
  page145_i47
#ISCELL
  mstr_standard offpage *
  page145_i48
#ISCELL
  mstr_standard offpage *
  page145_i49
#ISCELL
  mstr_standard offpage *
  page145_i51
#ISCELL
  mstr_standard offpage *
  page145_i52
#ISCELL
  mstr_standard offpage *
  page145_i53
#ISCELL
  mstr_standard offpage *
  page145_i54
#ISCELL
  mstr_standard offpage *
  page145_i55
#ISCELL
  mstr_standard offpage *
  page145_i56
#ISCELL
  mstr_standard offpage *
  page145_i57
#ISCELL
  mstr_standard offpage *
  page145_i58
#ISCELL
  mstr_standard offpage *
  page145_i59
#ISCELL
  mstr_standard offpage *
  page145_i6
#ISCELL
  mstr_standard offpage *
  page145_i7
#ISCELL
  mstr_standard offpage *
  page145_i70
#ISCELL
  mstr_standard offpage *
  page145_i71
#ISCELL
  mstr_standard offpage *
  page145_i72
#ISCELL
  mstr_standard offpage *
  page145_i73
#ISCELL
  mstr_standard offpage *
  page145_i74
#ISCELL
  mstr_standard offpage *
  page145_i75
#CELL
  mstr_discrete osc_c *
  page145_i8
#ISCELL
  mstr_standard offpage *
  page145_i85
#ISCELL
  mstr_standard offpage *
  page145_i86
#ISCELL
  mstr_standard offpage *
  page145_i87
#ISCELL
  mstr_standard offpage *
  page145_i88
#ISCELL
  mstr_standard offpage *
  page145_i89
#ISCELL
  mstr_standard offpage *
  page145_i9
#ISCELL
  mstr_standard offpage *
  page145_i90
#ISCELL
  mstr_standard offpage *
  page145_i91
#ISCELL
  mstr_standard offpage *
  page145_i92
#ISCELL
  mstr_standard offpage *
  page145_i93
#ISCELL
  mstr_standard offpage *
  page145_i94
#ISCELL
  mstr_standard offpage *
  page145_i95
#ISCELL
  mstr_standard offpage *
  page145_i96
#ISCELL
  mstr_standard offpage *
  page145_i99
#ISCELL
  mstr_symbols cad_note *
  *
#ISCELL
  mstr_symbols intel_corp_bpage *
  *
#ISCELL
  mstr_standard offpage *
  page146_i103
#CELL
  w_hdl ast2520a1-gp-gp *
  page146_i104
#CELL
  w_hdl ast2520a1-gp-gp *
  page146_i105
#ISCELL
  mstr_standard offpage *
  page146_i107
#ISCELL
  mstr_standard offpage *
  page146_i108
#ISCELL
  mstr_standard offpage *
  page146_i110
#ISCELL
  mstr_standard offpage *
  page146_i111
#ISCELL
  mstr_standard offpage *
  page146_i114
#ISCELL
  mstr_standard offpage *
  page146_i115
#ISCELL
  mstr_standard offpage *
  page146_i116
#ISCELL
  mstr_standard offpage *
  page146_i117
#ISCELL
  mstr_standard offpage *
  page146_i119
#ISCELL
  mstr_standard offpage *
  page146_i120
#CELL
  mstr_discrete res *
  page146_i123
#ISCELL
  mstr_standard offpage *
  page146_i124
#ISCELL
  mstr_standard offpage *
  page146_i127
#ISCELL
  mstr_standard offpage *
  page146_i128
#ISCELL
  mstr_standard offpage *
  page146_i135
#ISCELL
  mstr_standard offpage *
  page146_i138
#ISCELL
  mstr_standard offpage *
  page146_i139
#ISCELL
  mstr_standard offpage *
  page146_i140
#ISCELL
  mstr_standard offpage *
  page146_i141
#ISCELL
  mstr_standard offpage *
  page146_i142
#ISCELL
  mstr_standard offpage *
  page146_i143
#ISCELL
  mstr_standard offpage *
  page146_i144
#ISCELL
  mstr_standard offpage *
  page146_i145
#ISCELL
  mstr_standard offpage *
  page146_i146
#ISCELL
  mstr_standard offpage *
  page146_i147
#ISCELL
  mstr_standard offpage *
  page146_i149
#ISCELL
  mstr_standard offpage *
  page146_i150
#CELL
  mstr_discrete res *
  page146_i152
#CELL
  mstr_discrete res *
  page146_i153
#ISCELL
  mstr_symbols p3v3 *
  page146_i154
#ISCELL
  mstr_standard offpage *
  page146_i155
#ISCELL
  mstr_standard offpage *
  page146_i156
#ISCELL
  mstr_standard offpage *
  page146_i157
#ISCELL
  mstr_standard offpage *
  page146_i158
#CELL
  mstr_discrete cap *
  page146_i160
#ISCELL
  mstr_standard offpage *
  page146_i161
#ISCELL
  mstr_standard offpage *
  page146_i163
#ISCELL
  mstr_standard offpage *
  page146_i165
#CELL
  mstr_discrete res *
  page146_i166
#ISCELL
  mstr_standard offpage *
  page146_i167
#ISCELL
  mstr_standard offpage *
  page146_i168
#ISCELL
  mstr_standard offpage *
  page146_i169
#ISCELL
  mstr_standard offpage *
  page146_i21
#ISCELL
  mstr_standard offpage *
  page146_i24
#ISCELL
  mstr_standard offpage *
  page146_i25
#CELL
  mstr_discrete res *
  page146_i26
#ISCELL
  mstr_standard offpage *
  page146_i28
#ISCELL
  mstr_standard offpage *
  page146_i29
#CELL
  mstr_discrete res *
  page146_i35
#ISCELL
  mstr_symbols gnd *
  page146_i36
#CELL
  mstr_discrete res *
  page146_i37
#ISCELL
  mstr_standard offpage *
  page146_i42
#ISCELL
  mstr_standard offpage *
  page146_i43
#ISCELL
  mstr_standard offpage *
  page146_i44
#ISCELL
  mstr_standard offpage *
  page146_i45
#ISCELL
  mstr_standard offpage *
  page146_i46
#ISCELL
  mstr_standard offpage *
  page146_i47
#ISCELL
  mstr_standard offpage *
  page146_i48
#ISCELL
  mstr_standard offpage *
  page146_i49
#ISCELL
  mstr_standard offpage *
  page146_i5
#ISCELL
  mstr_standard offpage *
  page146_i54
#ISCELL
  mstr_standard offpage *
  page146_i55
#ISCELL
  mstr_standard offpage *
  page146_i63
#CELL
  mstr_discrete res *
  page146_i65
#ISCELL
  mstr_symbols gnd *
  page146_i66
#CELL
  mstr_discrete res *
  page146_i67
#CELL
  mstr_discrete res *
  page146_i68
#CELL
  mstr_discrete res *
  page146_i70
#CELL
  mstr_discrete res *
  page146_i71
#CELL
  mstr_discrete res *
  page146_i73
#CELL
  mstr_discrete res *
  page146_i74
#CELL
  mstr_discrete res *
  page146_i75
#CELL
  mstr_discrete res *
  page146_i76
#ISCELL
  mstr_symbols gnd *
  page146_i77
#CELL
  mstr_discrete res *
  page146_i78
#ISCELL
  mstr_symbols gnd *
  page146_i79
#ISCELL
  mstr_standard offpage *
  page146_i80
#ISCELL
  mstr_standard offpage *
  page146_i81
#ISCELL
  mstr_standard offpage *
  page146_i83
#CELL
  mstr_discrete res *
  page146_i84
#CELL
  mstr_discrete res *
  page146_i85
#ISCELL
  mstr_standard offpage *
  page146_i86
#ISCELL
  mstr_standard offpage *
  page146_i87
#ISCELL
  mstr_standard offpage *
  page146_i88
#ISCELL
  mstr_standard offpage *
  page146_i89
#ISCELL
  mstr_standard tap *
  page146_i90
#ISCELL
  mstr_standard tap *
  page146_i91
#ISCELL
  mstr_standard tap *
  page146_i92
#ISCELL
  mstr_standard tap *
  page146_i93
#ISCELL
  mstr_standard offpage *
  page146_i94
#ISCELL
  mstr_standard offpage *
  page146_i99
#ISCELL
  mstr_misc dns *
  *
#ISCELL
  mstr_symbols cad_note *
  *
#ISCELL
  mstr_symbols intel_corp_bpage *
  *
#ISCELL
  mstr_standard offpage *
  page147_i10
#CELL
  w_hdl ast2520a1-gp-gp *
  page147_i106
#ISCELL
  mstr_standard offpage *
  page147_i11
#ISCELL
  mstr_standard offpage *
  page147_i111
#ISCELL
  mstr_standard offpage *
  page147_i115
#ISCELL
  mstr_standard offpage *
  page147_i116
#ISCELL
  mstr_standard offpage *
  page147_i12
#ISCELL
  mstr_standard offpage *
  page147_i126
#ISCELL
  mstr_standard offpage *
  page147_i127
#ISCELL
  mstr_standard offpage *
  page147_i128
#CELL
  mstr_discrete res *
  page147_i129
#ISCELL
  mstr_standard offpage *
  page147_i13
#ISCELL
  mstr_standard offpage *
  page147_i131
#ISCELL
  mstr_standard offpage *
  page147_i132
#ISCELL
  mstr_standard offpage *
  page147_i134
#ISCELL
  mstr_standard offpage *
  page147_i135
#ISCELL
  mstr_standard offpage *
  page147_i137
#ISCELL
  mstr_standard offpage *
  page147_i138
#ISCELL
  mstr_standard offpage *
  page147_i139
#ISCELL
  mstr_standard offpage *
  page147_i14
#ISCELL
  mstr_standard offpage *
  page147_i140
#ISCELL
  mstr_standard offpage *
  page147_i143
#ISCELL
  mstr_standard offpage *
  page147_i144
#ISCELL
  mstr_symbols gnd *
  page147_i145
#ISCELL
  mstr_standard offpage *
  page147_i146
#ISCELL
  mstr_standard offpage *
  page147_i147
#ISCELL
  mstr_standard offpage *
  page147_i148
#ISCELL
  mstr_standard offpage *
  page147_i149
#ISCELL
  mstr_standard offpage *
  page147_i15
#ISCELL
  mstr_standard offpage *
  page147_i150
#CELL
  mstr_discrete res *
  page147_i151
#ISCELL
  mstr_standard offpage *
  page147_i152
#ISCELL
  mstr_standard offpage *
  page147_i153
#ISCELL
  mstr_standard offpage *
  page147_i154
#ISCELL
  mstr_standard offpage *
  page147_i155
#CELL
  mstr_discrete res *
  page147_i156
#ISCELL
  mstr_symbols gnd *
  page147_i157
#ISCELL
  mstr_standard offpage *
  page147_i158
#CELL
  mstr_discrete res *
  page147_i159
#ISCELL
  mstr_standard offpage *
  page147_i16
#CELL
  dev_discrete cap_a *
  page147_i160
#CELL
  dev_discrete cap_a *
  page147_i161
#CELL
  dev_discrete cap_a *
  page147_i162
#ISCELL
  mstr_standard offpage *
  page147_i163
#CELL
  mstr_discrete res *
  page147_i164
#ISCELL
  mstr_symbols gnd *
  page147_i165
#ISCELL
  mstr_standard offpage *
  page147_i166
#ISCELL
  mstr_standard offpage *
  page147_i17
#ISCELL
  mstr_standard offpage *
  page147_i171
#ISCELL
  mstr_standard offpage *
  page147_i172
#CELL
  mstr_discrete res *
  page147_i173
#ISCELL
  mstr_standard offpage *
  page147_i174
#ISCELL
  mstr_standard offpage *
  page147_i175
#ISCELL
  mstr_standard offpage *
  page147_i176
#ISCELL
  mstr_standard offpage *
  page147_i177
#ISCELL
  mstr_standard offpage *
  page147_i178
#ISCELL
  mstr_standard offpage *
  page147_i179
#ISCELL
  mstr_standard offpage *
  page147_i18
#ISCELL
  mstr_standard offpage *
  page147_i19
#ISCELL
  mstr_standard offpage *
  page147_i2
#ISCELL
  w_power w_vcc_circle *
  page147_i20
#CELL
  mstr_discrete res *
  page147_i21
#CELL
  mstr_discrete res *
  page147_i22
#CELL
  mstr_discrete res *
  page147_i23
#CELL
  mstr_discrete res *
  page147_i24
#CELL
  mstr_discrete res *
  page147_i25
#ISCELL
  mstr_standard offpage *
  page147_i34
#ISCELL
  mstr_standard offpage *
  page147_i35
#ISCELL
  mstr_symbols gnd *
  page147_i37
#ISCELL
  mstr_symbols gnd *
  page147_i41
#CELL
  mstr_discrete res *
  page147_i42
#CELL
  mstr_discrete res *
  page147_i43
#ISCELL
  mstr_symbols p3v3_stby *
  page147_i44
#ISCELL
  mstr_standard offpage *
  page147_i47
#ISCELL
  mstr_standard offpage *
  page147_i48
#ISCELL
  mstr_standard offpage *
  page147_i49
#ISCELL
  mstr_standard offpage *
  page147_i50
#ISCELL
  mstr_standard offpage *
  page147_i51
#ISCELL
  mstr_standard offpage *
  page147_i54
#ISCELL
  mstr_standard offpage *
  page147_i55
#ISCELL
  mstr_standard offpage *
  page147_i56
#ISCELL
  mstr_standard offpage *
  page147_i57
#ISCELL
  mstr_standard offpage *
  page147_i58
#ISCELL
  mstr_standard offpage *
  page147_i59
#ISCELL
  mstr_standard offpage *
  page147_i6
#ISCELL
  mstr_standard offpage *
  page147_i60
#CELL
  mstr_discrete res *
  page147_i61
#CELL
  mstr_discrete res *
  page147_i62
#ISCELL
  mstr_symbols gnd *
  page147_i63
#ISCELL
  mstr_symbols gnd *
  page147_i64
#CELL
  mstr_discrete res *
  page147_i65
#CELL
  mstr_discrete res *
  page147_i66
#ISCELL
  mstr_symbols gnd *
  page147_i67
#ISCELL
  mstr_symbols gnd *
  page147_i68
#ISCELL
  mstr_standard offpage *
  page147_i7
#CELL
  mstr_discrete res *
  page147_i75
#ISCELL
  mstr_symbols gnd *
  page147_i76
#ISCELL
  mstr_standard offpage *
  page147_i79
#CELL
  mstr_discrete res *
  page147_i8
#ISCELL
  mstr_standard offpage *
  page147_i81
#ISCELL
  mstr_standard offpage *
  page147_i88
#ISCELL
  mstr_standard offpage *
  page147_i89
#ISCELL
  mstr_standard offpage *
  page147_i9
#ISCELL
  mstr_symbols intel_corp_bpage *
  *
#ISCELL
  w_power w_vcc_circle *
  page148_i10
#ISCELL
  mstr_standard offpage *
  page148_i12
#ISCELL
  mstr_standard offpage *
  page148_i13
#ISCELL
  w_power w_vcc_circle *
  page148_i14
#ISCELL
  w_power w_vcc_circle *
  page148_i15
#CELL
  mstr_discrete res *
  page148_i16
#ISCELL
  mstr_symbols p3v3_stby *
  page148_i18
#ISCELL
  w_power w_vcc_circle *
  page148_i19
#ISCELL
  mstr_symbols p3v3_stby *
  page148_i2
#CELL
  dev_discrete cap_a *
  page148_i20
#ISCELL
  mstr_symbols pvccio_cpu0 *
  page148_i21
#ISCELL
  mstr_symbols gnd *
  page148_i22
#ISCELL
  w_power w_vcc_circle *
  page148_i26
#ISCELL
  w_power w_vcc_circle *
  page148_i27
#CELL
  w_hdl ast2520a1-gp-gp *
  page148_i28
#CELL
  mstr_discrete res *
  page148_i29
#ISCELL
  mstr_symbols gnd *
  page148_i3
#ISCELL
  mstr_standard offpage *
  page148_i30
#ISCELL
  mstr_symbols p3v3_stby *
  page148_i4
#ISCELL
  w_power w_vcc_circle *
  page148_i6
#ISCELL
  w_power w_vcc_circle *
  page148_i7
#ISCELL
  w_power w_vcc_circle *
  page148_i8
#ISCELL
  w_power w_vcc_circle *
  page148_i9
#ISCELL
  mstr_symbols intel_corp_bpage *
  *
#CELL
  mstr_discrete cap *
  page149_i1
#CELL
  mstr_discrete cap *
  page149_i100
#CELL
  mstr_discrete cap *
  page149_i101
#CELL
  mstr_discrete cap *
  page149_i102
#CELL
  mstr_discrete cap *
  page149_i103
#CELL
  mstr_discrete cap *
  page149_i104
#CELL
  mstr_discrete cap *
  page149_i105
#CELL
  mstr_discrete cap *
  page149_i106
#CELL
  mstr_discrete cap *
  page149_i107
#CELL
  mstr_discrete cap *
  page149_i108
#CELL
  mstr_discrete cap *
  page149_i109
#CELL
  mstr_discrete cap *
  page149_i110
#CELL
  mstr_discrete cap *
  page149_i112
#CELL
  mstr_discrete cap *
  page149_i113
#CELL
  mstr_discrete cap *
  page149_i114
#CELL
  mstr_discrete cap *
  page149_i115
#CELL
  mstr_discrete cap *
  page149_i116
#CELL
  mstr_discrete cap *
  page149_i117
#CELL
  mstr_discrete cap *
  page149_i118
#CELL
  dev_discrete cap_a *
  page149_i119
#CELL
  dev_discrete cap_a *
  page149_i120
#CELL
  dev_discrete cap_a *
  page149_i121
#CELL
  dev_discrete cap_a *
  page149_i122
#CELL
  dev_discrete cap_a *
  page149_i123
#CELL
  dev_discrete cap_a *
  page149_i124
#CELL
  dev_discrete cap_a *
  page149_i125
#CELL
  dev_discrete cap_a *
  page149_i126
#CELL
  dev_discrete cap_a *
  page149_i128
#CELL
  mstr_discrete cap *
  page149_i129
#CELL
  mstr_discrete cap *
  page149_i130
#ISCELL
  mstr_symbols p3v3_stby *
  page149_i14
#ISCELL
  w_power w_vcc_circle *
  page149_i16
#CELL
  mstr_discrete cap *
  page149_i17
#ISCELL
  mstr_symbols gnd *
  page149_i18
#ISCELL
  w_power w_vcc_circle *
  page149_i2
#CELL
  w_hdl hcb1608kf-800t30-gp *
  page149_i22
#ISCELL
  mstr_symbols p3v3_stby *
  page149_i23
#ISCELL
  mstr_symbols gnd *
  page149_i24
#CELL
  mstr_discrete cap *
  page149_i25
#ISCELL
  w_power w_vcc_circle *
  page149_i26
#ISCELL
  mstr_symbols gnd *
  page149_i27
#ISCELL
  w_power w_vcc_circle *
  page149_i29
#CELL
  mstr_discrete cap *
  page149_i31
#ISCELL
  mstr_symbols gnd *
  page149_i32
#ISCELL
  mstr_symbols gnd *
  page149_i4
#CELL
  mstr_discrete cap *
  page149_i40
#ISCELL
  mstr_symbols gnd *
  page149_i41
#CELL
  w_hdl hcb1608kf-800t30-gp *
  page149_i42
#ISCELL
  w_power w_vcc_circle *
  page149_i43
#ISCELL
  mstr_symbols p3v3_stby *
  page149_i44
#ISCELL
  w_power w_vcc_circle *
  page149_i45
#CELL
  mstr_discrete cap *
  page149_i46
#ISCELL
  mstr_symbols gnd *
  page149_i49
#CELL
  mstr_discrete cap *
  page149_i5
#CELL
  mstr_discrete cap *
  page149_i50
#CELL
  mstr_discrete cap *
  page149_i51
#ISCELL
  mstr_symbols p3v3_stby *
  page149_i54
#ISCELL
  mstr_symbols gnd *
  page149_i55
#ISCELL
  w_power w_vcc_circle *
  page149_i62
#ISCELL
  mstr_symbols p3v3_stby *
  page149_i65
#ISCELL
  w_power w_vcc_circle *
  page149_i66
#ISCELL
  mstr_symbols gnd *
  page149_i68
#ISCELL
  w_power w_vcc_circle *
  page149_i69
#ISCELL
  mstr_symbols gnd *
  page149_i7
#ISCELL
  w_power w_vcc_circle *
  page149_i78
#CELL
  mstr_discrete cap *
  page149_i79
#ISCELL
  mstr_symbols gnd *
  page149_i80
#ISCELL
  mstr_symbols p3v3_stby *
  page149_i84
#CELL
  w_hdl hcb1608kf-800t30-gp *
  page149_i85
#CELL
  w_hdl hcb1608kf-800t30-gp *
  page149_i86
#ISCELL
  mstr_symbols p3v3_stby *
  page149_i87
#CELL
  w_hdl hcb1608kf-800t30-gp *
  page149_i88
#ISCELL
  mstr_symbols p3v3_stby *
  page149_i89
#CELL
  mstr_discrete res *
  page149_i90
#CELL
  mstr_discrete res *
  page149_i91
#CELL
  mstr_discrete cap *
  page149_i92
#CELL
  mstr_discrete cap *
  page149_i93
#CELL
  mstr_discrete cap *
  page149_i95
#CELL
  mstr_discrete cap *
  page149_i96
#CELL
  mstr_discrete cap *
  page149_i97
#CELL
  mstr_discrete cap *
  page149_i98
#CELL
  mstr_discrete cap *
  page149_i99
#ISCELL
  mstr_misc dns *
  *
#ISCELL
  mstr_symbols intel_corp_bpage *
  *
#ISCELL
  mstr_standard offpage *
  page150_i140
#ISCELL
  mstr_standard offpage *
  page150_i141
#ISCELL
  mstr_standard offpage *
  page150_i142
#CELL
  mstr_discrete res *
  page150_i144
#CELL
  mstr_discrete res *
  page150_i145
#CELL
  mstr_discrete res *
  page150_i146
#ISCELL
  mstr_symbols p3v3_stby *
  page150_i147
#ISCELL
  mstr_standard offpage *
  page150_i155
#ISCELL
  mstr_standard offpage *
  page150_i156
#ISCELL
  mstr_standard offpage *
  page150_i157
#ISCELL
  mstr_standard offpage *
  page150_i158
#ISCELL
  mstr_standard offpage *
  page150_i161
#ISCELL
  mstr_standard offpage *
  page150_i166
#CELL
  mstr_discrete res *
  page150_i175
#CELL
  mstr_discrete res *
  page150_i180
#ISCELL
  mstr_symbols gnd *
  page150_i186
#CELL
  mstr_discrete res *
  page150_i189
#CELL
  mstr_discrete res *
  page150_i190
#CELL
  mstr_discrete res *
  page150_i191
#CELL
  mstr_discrete res *
  page150_i196
#ISCELL
  mstr_symbols gnd *
  page150_i198
#CELL
  mstr_discrete res *
  page150_i199
#ISCELL
  mstr_standard offpage *
  page150_i202
#ISCELL
  mstr_standard offpage *
  page150_i203
#ISCELL
  mstr_standard offpage *
  page150_i204
#ISCELL
  mstr_standard offpage *
  page150_i205
#ISCELL
  mstr_standard offpage *
  page150_i206
#ISCELL
  mstr_standard offpage *
  page150_i207
#ISCELL
  mstr_standard offpage *
  page150_i208
#CELL
  mstr_discrete res *
  page150_i209
#CELL
  mstr_discrete res *
  page150_i210
#CELL
  mstr_discrete res *
  page150_i211
#CELL
  mstr_discrete res *
  page150_i214
#CELL
  mstr_discrete res *
  page150_i215
#CELL
  mstr_discrete res *
  page150_i216
#ISCELL
  mstr_symbols gnd *
  page150_i217
#CELL
  mstr_discrete res *
  page150_i218
#CELL
  mstr_discrete res *
  page150_i219
#ISCELL
  mstr_standard offpage *
  page150_i220
#ISCELL
  mstr_standard offpage *
  page150_i221
#ISCELL
  mstr_standard offpage *
  page150_i222
#ISCELL
  mstr_standard offpage *
  page150_i223
#ISCELL
  mstr_standard offpage *
  page150_i224
#ISCELL
  mstr_standard offpage *
  page150_i225
#ISCELL
  mstr_symbols gnd *
  page150_i227
#CELL
  mstr_discrete res *
  page150_i228
#CELL
  mstr_discrete res *
  page150_i229
#CELL
  mstr_discrete res *
  page150_i230
#ISCELL
  mstr_symbols gnd *
  page150_i231
#CELL
  mstr_discrete res *
  page150_i232
#CELL
  mstr_discrete res *
  page150_i233
#CELL
  mstr_discrete res *
  page150_i234
#ISCELL
  mstr_symbols gnd *
  page150_i235
#CELL
  mstr_discrete res *
  page150_i236
#ISCELL
  mstr_symbols gnd *
  page150_i237
#ISCELL
  mstr_symbols p3v3_stby *
  page150_i238
#CELL
  mstr_discrete res *
  page150_i239
#CELL
  mstr_discrete res *
  page150_i240
#CELL
  mstr_discrete res *
  page150_i241
#CELL
  mstr_discrete res *
  page150_i242
#ISCELL
  mstr_misc dns *
  *
#ISCELL
  mstr_symbols cad_note *
  *
#ISCELL
  mstr_symbols intel_corp_bpage *
  *
#ISCELL
  mstr_standard offpage *
  page151_i100
#CELL
  mstr_discrete res *
  page151_i101
#ISCELL
  mstr_standard offpage *
  page151_i103
#ISCELL
  mstr_standard offpage *
  page151_i104
#ISCELL
  mstr_standard offpage *
  page151_i105
#ISCELL
  mstr_standard offpage *
  page151_i106
#ISCELL
  mstr_standard offpage *
  page151_i107
#ISCELL
  mstr_standard offpage *
  page151_i108
#ISCELL
  mstr_standard offpage *
  page151_i109
#ISCELL
  mstr_standard offpage *
  page151_i110
#ISCELL
  mstr_standard offpage *
  page151_i111
#ISCELL
  mstr_symbols gnd *
  page151_i112
#ISCELL
  mstr_standard offpage *
  page151_i113
#ISCELL
  mstr_standard offpage *
  page151_i114
#ISCELL
  mstr_standard offpage *
  page151_i115
#ISCELL
  mstr_standard offpage *
  page151_i116
#ISCELL
  mstr_standard offpage *
  page151_i117
#ISCELL
  mstr_symbols gnd *
  page151_i118
#CELL
  w_hdl sc1u16v3kx-2gp *
  page151_i120
#CELL
  w_hdl sc1u16v3kx-2gp *
  page151_i121
#ISCELL
  w_power w_vcc_circle *
  page151_i122
#CELL
  mstr_discrete cap *
  page151_i123
#ISCELL
  mstr_symbols gnd *
  page151_i124
#CELL
  mstr_discrete cap *
  page151_i125
#ISCELL
  mstr_symbols p3v3_stby *
  page151_i136
#ISCELL
  mstr_symbols gnd *
  page151_i137
#CELL
  mstr_discrete res *
  page151_i138
#CELL
  mstr_discrete cap *
  page151_i139
#CELL
  mstr_discrete cap *
  page151_i140
#CELL
  mstr_discrete cap *
  page151_i141
#CELL
  mstr_discrete cap *
  page151_i142
#CELL
  mstr_discrete cap *
  page151_i143
#CELL
  mstr_discrete led *
  page151_i144
#CELL
  mstr_discrete fet_n_dual *
  page151_i145
#ISCELL
  w_power w_vcc_circle *
  page151_i146
#ISCELL
  mstr_symbols gnd *
  page151_i149
#ISCELL
  mstr_symbols gnd *
  page151_i150
#ISCELL
  mstr_symbols p3v3_stby *
  page151_i172
#CELL
  mstr_discrete res *
  page151_i173
#ISCELL
  mstr_symbols p3v3_stby *
  page151_i174
#CELL
  mstr_discrete res *
  page151_i175
#ISCELL
  mstr_symbols gnd *
  page151_i197
#CELL
  mstr_discrete fet_n_dual *
  page151_i198
#ISCELL
  mstr_symbols gnd *
  page151_i199
#ISCELL
  w_power w_vcc_circle *
  page151_i200
#CELL
  mstr_discrete res *
  page151_i201
#CELL
  mstr_discrete res *
  page151_i202
#ISCELL
  mstr_symbols gnd *
  page151_i204
#ISCELL
  mstr_standard offpage *
  page151_i207
#ISCELL
  mstr_standard offpage *
  page151_i208
#CELL
  mstr_discrete res *
  page151_i209
#CELL
  mstr_discrete res *
  page151_i210
#CELL
  mstr_discrete res *
  page151_i211
#CELL
  dev_discrete cap_a *
  page151_i212
#CELL
  dev_discrete cap_a *
  page151_i213
#CELL
  dev_discrete cap_a *
  page151_i214
#CELL
  dev_discrete cap_a *
  page151_i215
#CELL
  dev_discrete cap_a *
  page151_i216
#CELL
  dev_discrete cap_a *
  page151_i217
#CELL
  mstr_discrete cap *
  page151_i220
#ISCELL
  mstr_symbols gnd *
  page151_i221
#CELL
  mstr_discrete res *
  page151_i222
#CELL
  w_hdl 120r2f-gp *
  page151_i223
#CELL
  w_hdl 120r2f-gp *
  page151_i224
#CELL
  w_hdl 120r2f-gp *
  page151_i225
#CELL
  w_hdl 120r2f-gp *
  page151_i226
#CELL
  w_hdl 120r2f-gp *
  page151_i227
#CELL
  w_hdl 120r2f-gp *
  page151_i228
#CELL
  w_hdl 120r2f-gp *
  page151_i229
#CELL
  w_hdl 120r2f-gp *
  page151_i230
#CELL
  w_hdl 120r2f-gp *
  page151_i231
#CELL
  w_hdl 120r2f-gp *
  page151_i232
#CELL
  w_hdl 120r2f-gp *
  page151_i233
#CELL
  w_hdl 120r2f-gp *
  page151_i234
#CELL
  w_hdl 120r2f-gp *
  page151_i235
#CELL
  w_hdl 120r2f-gp *
  page151_i236
#CELL
  w_hdl 120r2f-gp *
  page151_i237
#CELL
  w_hdl 120r2f-gp *
  page151_i238
#CELL
  w_hdl 120r2f-gp *
  page151_i239
#CELL
  w_hdl 120r2f-gp *
  page151_i240
#CELL
  w_hdl 120r2f-gp *
  page151_i241
#CELL
  w_hdl 120r2f-gp *
  page151_i242
#CELL
  w_hdl 120r2f-gp *
  page151_i243
#CELL
  w_hdl 120r2f-gp *
  page151_i244
#CELL
  w_hdl 120r2f-gp *
  page151_i245
#CELL
  w_hdl 120r2f-gp *
  page151_i246
#CELL
  w_hdl 120r2f-gp *
  page151_i247
#CELL
  w_hdl 120r2f-gp *
  page151_i248
#CELL
  w_hdl 120r2f-gp *
  page151_i249
#CELL
  w_hdl 120r2f-gp *
  page151_i250
#CELL
  w_hdl 120r2f-gp *
  page151_i251
#CELL
  w_hdl 120r2f-gp *
  page151_i252
#CELL
  w_hdl 120r2f-gp *
  page151_i253
#CELL
  w_hdl 120r2f-gp *
  page151_i254
#CELL
  w_hdl 120r2f-gp *
  page151_i255
#CELL
  w_hdl 120r2f-gp *
  page151_i256
#CELL
  w_hdl 120r2f-gp *
  page151_i257
#CELL
  w_hdl 120r2f-gp *
  page151_i258
#CELL
  w_hdl 120r2f-gp *
  page151_i259
#CELL
  w_hdl 120r2f-gp *
  page151_i260
#CELL
  w_hdl 120r2f-gp *
  page151_i261
#CELL
  w_hdl 120r2f-gp *
  page151_i262
#CELL
  w_hdl 120r2f-gp *
  page151_i263
#CELL
  w_hdl 120r2f-gp *
  page151_i264
#CELL
  w_hdl 120r2f-gp *
  page151_i265
#CELL
  w_hdl 120r2f-gp *
  page151_i266
#CELL
  w_hdl 120r2f-gp *
  page151_i267
#CELL
  w_hdl 120r2f-gp *
  page151_i268
#CELL
  w_hdl 120r2f-gp *
  page151_i269
#CELL
  w_hdl 120r2f-gp *
  page151_i270
#CELL
  w_hdl 120r2f-gp *
  page151_i271
#CELL
  w_hdl 120r2f-gp *
  page151_i274
#CELL
  w_hdl 120r2f-gp *
  page151_i275
#CELL
  mstr_discrete res *
  page151_i278
#CELL
  mstr_discrete res *
  page151_i279
#CELL
  w_hdl h5an4g6nafr-tfc-gp *
  page151_i49
#ISCELL
  mstr_standard offpage *
  page151_i50
#ISCELL
  w_power w_vcc_circle *
  page151_i51
#ISCELL
  mstr_standard offpage *
  page151_i52
#ISCELL
  w_power w_vcc_circle *
  page151_i54
#CELL
  mstr_discrete res *
  page151_i55
#CELL
  mstr_ttl ttl1g07_a *
  page151_i56
#ISCELL
  mstr_standard offpage *
  page151_i57
#CELL
  mstr_discrete cap *
  page151_i58
#ISCELL
  mstr_standard offpage *
  page151_i59
#ISCELL
  mstr_standard offpage *
  page151_i60
#ISCELL
  mstr_standard offpage *
  page151_i61
#ISCELL
  mstr_standard offpage *
  page151_i62
#ISCELL
  mstr_standard offpage *
  page151_i63
#ISCELL
  mstr_standard offpage *
  page151_i64
#ISCELL
  mstr_standard offpage *
  page151_i65
#ISCELL
  mstr_standard offpage *
  page151_i66
#ISCELL
  mstr_standard offpage *
  page151_i67
#ISCELL
  mstr_standard offpage *
  page151_i68
#ISCELL
  mstr_standard offpage *
  page151_i69
#ISCELL
  mstr_standard offpage *
  page151_i70
#ISCELL
  mstr_standard offpage *
  page151_i71
#ISCELL
  mstr_standard offpage *
  page151_i72
#ISCELL
  mstr_standard offpage *
  page151_i73
#ISCELL
  mstr_standard offpage *
  page151_i74
#ISCELL
  mstr_standard offpage *
  page151_i75
#ISCELL
  mstr_standard offpage *
  page151_i76
#ISCELL
  mstr_standard offpage *
  page151_i77
#ISCELL
  mstr_standard offpage *
  page151_i78
#ISCELL
  mstr_standard offpage *
  page151_i79
#ISCELL
  mstr_standard offpage *
  page151_i80
#ISCELL
  mstr_standard offpage *
  page151_i81
#ISCELL
  mstr_standard offpage *
  page151_i82
#ISCELL
  mstr_standard offpage *
  page151_i83
#ISCELL
  mstr_standard offpage *
  page151_i84
#ISCELL
  mstr_symbols gnd *
  page151_i85
#ISCELL
  w_power w_vcc_circle *
  page151_i86
#ISCELL
  w_power w_vcc_circle *
  page151_i88
#ISCELL
  mstr_standard offpage *
  page151_i89
#ISCELL
  mstr_symbols gnd *
  page151_i91
#ISCELL
  mstr_standard offpage *
  page151_i92
#ISCELL
  mstr_standard offpage *
  page151_i93
#ISCELL
  mstr_standard offpage *
  page151_i94
#ISCELL
  mstr_standard offpage *
  page151_i95
#ISCELL
  mstr_standard offpage *
  page151_i96
#ISCELL
  mstr_standard offpage *
  page151_i97
#ISCELL
  mstr_standard offpage *
  page151_i98
#ISCELL
  mstr_standard offpage *
  page151_i99
#ISCELL
  mstr_misc dns *
  *
#ISCELL
  mstr_symbols cad_note *
  *
#ISCELL
  mstr_symbols design_note *
  *
#ISCELL
  mstr_symbols intel_corp_bpage *
  *
#CELL
  mstr_digital gtl2014 *
  page152_i1
#ISCELL
  mstr_standard offpage *
  page152_i10
#CELL
  mstr_discrete res *
  page152_i100
#ISCELL
  mstr_standard offpage *
  page152_i101
#CELL
  mstr_discrete res *
  page152_i102
#ISCELL
  mstr_symbols p3v3 *
  page152_i103
#ISCELL
  mstr_symbols pvccio_cpu0 *
  page152_i104
#CELL
  mstr_discrete res *
  page152_i105
#CELL
  w_hdl 374r2f-1-gp *
  page152_i106
#ISCELL
  mstr_standard offpage *
  page152_i11
#ISCELL
  mstr_standard offpage *
  page152_i12
#ISCELL
  mstr_standard offpage *
  page152_i13
#CELL
  mstr_discrete res *
  page152_i14
#CELL
  mstr_discrete res *
  page152_i15
#CELL
  mstr_discrete res *
  page152_i16
#ISCELL
  mstr_symbols gnd *
  page152_i17
#CELL
  mstr_discrete cap *
  page152_i18
#CELL
  mstr_discrete res *
  page152_i2
#ISCELL
  mstr_symbols gnd *
  page152_i20
#ISCELL
  mstr_standard offpage *
  page152_i21
#ISCELL
  mstr_standard offpage *
  page152_i22
#ISCELL
  mstr_standard offpage *
  page152_i23
#ISCELL
  mstr_standard offpage *
  page152_i24
#CELL
  mstr_discrete res *
  page152_i26
#CELL
  dev_discrete cap_a *
  page152_i27
#ISCELL
  mstr_symbols gnd *
  page152_i29
#ISCELL
  mstr_symbols gnd *
  page152_i3
#ISCELL
  mstr_standard offpage *
  page152_i30
#ISCELL
  mstr_standard offpage *
  page152_i4
#CELL
  mstr_discrete res *
  page152_i45
#CELL
  mstr_discrete res *
  page152_i47
#CELL
  mstr_discrete res *
  page152_i49
#ISCELL
  mstr_symbols p3v3 *
  page152_i5
#CELL
  mstr_discrete res *
  page152_i50
#CELL
  mstr_discrete res *
  page152_i51
#ISCELL
  mstr_symbols pvccio_cpu0 *
  page152_i52
#CELL
  mstr_discrete res *
  page152_i53
#CELL
  mstr_discrete res *
  page152_i54
#ISCELL
  mstr_symbols pvccio_cpu1 *
  page152_i55
#CELL
  mstr_discrete res *
  page152_i56
#CELL
  mstr_discrete res *
  page152_i57
#CELL
  mstr_discrete res *
  page152_i58
#CELL
  mstr_discrete res *
  page152_i59
#CELL
  mstr_discrete res *
  page152_i6
#ISCELL
  mstr_symbols pvccio_cpu0 *
  page152_i60
#CELL
  mstr_discrete res *
  page152_i61
#CELL
  mstr_discrete res *
  page152_i62
#ISCELL
  mstr_symbols pvccio_cpu1 *
  page152_i63
#CELL
  mstr_discrete res *
  page152_i64
#CELL
  mstr_discrete res *
  page152_i65
#CELL
  mstr_discrete res *
  page152_i66
#CELL
  mstr_discrete res *
  page152_i67
#CELL
  mstr_discrete res *
  page152_i68
#CELL
  mstr_discrete res *
  page152_i69
#CELL
  mstr_discrete res *
  page152_i70
#CELL
  mstr_discrete res *
  page152_i71
#CELL
  mstr_discrete res *
  page152_i72
#CELL
  mstr_discrete res *
  page152_i73
#CELL
  mstr_discrete res *
  page152_i74
#ISCELL
  mstr_standard offpage *
  page152_i75
#ISCELL
  mstr_standard offpage *
  page152_i76
#ISCELL
  mstr_standard offpage *
  page152_i77
#ISCELL
  mstr_standard offpage *
  page152_i78
#CELL
  mstr_discrete res *
  page152_i79
#ISCELL
  mstr_standard offpage *
  page152_i85
#ISCELL
  mstr_standard offpage *
  page152_i87
#ISCELL
  mstr_standard offpage *
  page152_i89
#ISCELL
  mstr_standard offpage *
  page152_i91
#CELL
  mstr_discrete res *
  page152_i92
#CELL
  mstr_discrete res *
  page152_i93
#CELL
  mstr_discrete res *
  page152_i94
#CELL
  mstr_discrete res *
  page152_i95
#ISCELL
  mstr_standard offpage *
  page152_i96
#ISCELL
  mstr_standard offpage *
  page152_i97
#CELL
  mstr_discrete res *
  page152_i98
#ISCELL
  mstr_standard offpage *
  page152_i99
#ISCELL
  mstr_misc dns *
  *
#ISCELL
  mstr_symbols cad_note *
  *
#ISCELL
  mstr_symbols design_note *
  *
#ISCELL
  mstr_symbols intel_corp_bpage *
  *
#ISCELL
  mstr_standard offpage *
  page153_i101
#ISCELL
  mstr_standard offpage *
  page153_i102
#ISCELL
  mstr_standard offpage *
  page153_i103
#ISCELL
  mstr_standard offpage *
  page153_i105
#ISCELL
  mstr_standard offpage *
  page153_i107
#CELL
  mstr_discrete res *
  page153_i108
#CELL
  mstr_discrete res *
  page153_i109
#ISCELL
  mstr_standard offpage *
  page153_i110
#ISCELL
  mstr_standard offpage *
  page153_i111
#CELL
  dev_discrete cap_a *
  page153_i130
#CELL
  dev_discrete cap_a *
  page153_i131
#ISCELL
  mstr_symbols gnd *
  page153_i133
#CELL
  dev_discrete cap_a *
  page153_i136
#CELL
  dev_discrete cap_a *
  page153_i138
#ISCELL
  mstr_symbols gnd *
  page153_i139
#CELL
  mstr_discrete res *
  page153_i140
#ISCELL
  mstr_symbols p3v3_stby *
  page153_i141
#ISCELL
  mstr_standard offpage *
  page153_i144
#CELL
  mstr_memory w25q256 *
  page153_i146
#CELL
  mstr_discrete res *
  page153_i150
#ISCELL
  mstr_symbols p3v3_stby *
  page153_i151
#CELL
  mstr_discrete res *
  page153_i152
#ISCELL
  mstr_standard offpage *
  page153_i153
#CELL
  mstr_discrete res *
  page153_i155
#CELL
  mstr_discrete res *
  page153_i156
#CELL
  mstr_discrete res *
  page153_i157
#ISCELL
  mstr_standard offpage *
  page153_i158
#ISCELL
  mstr_standard offpage *
  page153_i159
#ISCELL
  mstr_standard offpage *
  page153_i161
#ISCELL
  mstr_standard offpage *
  page153_i162
#ISCELL
  mstr_standard offpage *
  page153_i163
#ISCELL
  mstr_standard offpage *
  page153_i164
#CELL
  mstr_discrete res *
  page153_i166
#CELL
  mstr_discrete res *
  page153_i167
#CELL
  mstr_discrete res *
  page153_i168
#ISCELL
  mstr_symbols p3v3_stby *
  page153_i169
#CELL
  mstr_discrete res *
  page153_i170
#ISCELL
  mstr_standard offpage *
  page153_i171
#ISCELL
  mstr_symbols gnd *
  page153_i172
#ISCELL
  mstr_standard offpage *
  page153_i173
#CELL
  mstr_discrete res *
  page153_i174
#ISCELL
  mstr_symbols p3v3_stby *
  page153_i175
#ISCELL
  mstr_symbols p3v3_stby *
  page153_i176
#ISCELL
  mstr_standard offpage *
  page153_i177
#CELL
  mstr_discrete res *
  page153_i178
#CELL
  mstr_discrete res *
  page153_i179
#ISCELL
  mstr_symbols gnd *
  page153_i180
#CELL
  mstr_discrete res *
  page153_i181
#ISCELL
  mstr_standard offpage *
  page153_i182
#ISCELL
  mstr_standard offpage *
  page153_i183
#CELL
  mstr_discrete res *
  page153_i184
#CELL
  w_hdl w25q256fvfig-gp *
  page153_i185
#ISCELL
  mstr_symbols gnd *
  page153_i186
#CELL
  mstr_discrete res *
  page153_i187
#ISCELL
  mstr_standard offpage *
  page153_i188
#CELL
  mstr_discrete res *
  page153_i90
#ISCELL
  mstr_symbols gnd *
  page153_i91
#CELL
  mstr_discrete res *
  page153_i94
#ISCELL
  mstr_symbols p3v3_stby *
  page153_i95
#CELL
  mstr_discrete res *
  page153_i98
#ISCELL
  mstr_symbols cad_note *
  *
#ISCELL
  mstr_symbols design_note *
  *
#ISCELL
  mstr_symbols intel_corp_bpage *
  *
#CELL
  mstr_ttl ttl1g32_a *
  page154_i100
#CELL
  mstr_discrete res *
  page154_i101
#ISCELL
  mstr_standard offpage *
  page154_i102
#ISCELL
  mstr_standard offpage *
  page154_i103
#CELL
  mstr_discrete res *
  page154_i105
#CELL
  mstr_discrete res *
  page154_i106
#ISCELL
  mstr_standard offpage *
  page154_i107
#ISCELL
  mstr_symbols gnd *
  page154_i109
#ISCELL
  mstr_symbols p3v3_stby *
  page154_i110
#ISCELL
  mstr_symbols p3v3_stby *
  page154_i111
#CELL
  mstr_discrete res *
  page154_i119
#ISCELL
  mstr_symbols p3v3_stby *
  page154_i12
#ISCELL
  mstr_standard offpage *
  page154_i123
#CELL
  mstr_discrete fet_n *
  page154_i126
#CELL
  mstr_discrete res *
  page154_i127
#CELL
  mstr_discrete res *
  page154_i128
#ISCELL
  mstr_symbols gnd *
  page154_i129
#ISCELL
  mstr_symbols gnd *
  page154_i13
#ISCELL
  mstr_standard offpage *
  page154_i130
#ISCELL
  mstr_symbols p3v3_stby *
  page154_i131
#CELL
  dev_discrete cap_a *
  page154_i132
#ISCELL
  mstr_symbols gnd *
  page154_i133
#ISCELL
  mstr_symbols p3v3_stby *
  page154_i134
#CELL
  dev_discrete cap_a *
  page154_i135
#ISCELL
  mstr_symbols gnd *
  page154_i136
#ISCELL
  mstr_symbols p3v3_stby *
  page154_i137
#ISCELL
  mstr_standard offpage *
  page154_i138
#CELL
  dev_discrete cap_a *
  page154_i14
#CELL
  mstr_discrete res *
  page154_i62
#ISCELL
  mstr_standard offpage *
  page154_i70
#ISCELL
  mstr_standard offpage *
  page154_i71
#ISCELL
  mstr_standard offpage *
  page154_i72
#ISCELL
  mstr_standard offpage *
  page154_i73
#CELL
  mstr_digital pi3b3257a *
  page154_i74
#CELL
  mstr_digital pi3b3257a *
  page154_i75
#ISCELL
  mstr_standard offpage *
  page154_i76
#ISCELL
  mstr_standard offpage *
  page154_i77
#ISCELL
  mstr_standard offpage *
  page154_i78
#ISCELL
  mstr_standard offpage *
  page154_i79
#ISCELL
  mstr_standard offpage *
  page154_i81
#ISCELL
  mstr_standard offpage *
  page154_i82
#ISCELL
  mstr_standard offpage *
  page154_i83
#ISCELL
  mstr_standard offpage *
  page154_i84
#ISCELL
  mstr_symbols gnd *
  page154_i85
#ISCELL
  mstr_symbols gnd *
  page154_i86
#ISCELL
  mstr_standard offpage *
  page154_i87
#ISCELL
  mstr_standard offpage *
  page154_i88
#ISCELL
  mstr_standard offpage *
  page154_i89
#ISCELL
  mstr_standard offpage *
  page154_i90
#ISCELL
  mstr_standard offpage *
  page154_i91
#CELL
  mstr_discrete res *
  page154_i92
#CELL
  mstr_discrete res *
  page154_i93
#CELL
  dev_discrete cap_a *
  page154_i94
#ISCELL
  mstr_symbols gnd *
  page154_i95
#ISCELL
  mstr_symbols p3v3_stby *
  page154_i96
#ISCELL
  mstr_symbols gnd *
  page154_i97
#ISCELL
  mstr_symbols gnd *
  page154_i98
#CELL
  mstr_ttl ttl1g32_a *
  page154_i99
#ISCELL
  mstr_symbols cad_note *
  *
#ISCELL
  mstr_symbols intel_corp_bpage *
  *
#CELL
  dev_discrete cap_a *
  page155_i127
#ISCELL
  mstr_symbols gnd *
  page155_i128
#CELL
  mstr_discrete fuse *
  page155_i129
#CELL
  mstr_discrete res *
  page155_i130
#CELL
  mstr_conn conn14_h54902001 *
  page155_i171
#CELL
  mstr_ttl ttl1g07_a *
  page155_i178
#ISCELL
  mstr_symbols gnd *
  page155_i180
#ISCELL
  mstr_standard offpage *
  page155_i182
#ISCELL
  mstr_symbols p3v3_stby *
  page155_i183
#CELL
  dev_discrete cap_a *
  page155_i184
#ISCELL
  mstr_symbols gnd *
  page155_i185
#CELL
  mstr_discrete res *
  page155_i186
#CELL
  mstr_discrete fet_n_dual *
  page155_i187
#CELL
  mstr_discrete fet_n_dual *
  page155_i188
#ISCELL
  mstr_symbols p12v_stby *
  page155_i193
#ISCELL
  mstr_symbols p5v_stby *
  page155_i194
#CELL
  mstr_discrete res *
  page155_i196
#ISCELL
  mstr_symbols p5v_stby *
  page155_i197
#CELL
  mstr_discrete res *
  page155_i198
#ISCELL
  mstr_symbols p3v3_stby *
  page155_i199
#CELL
  mstr_discrete res *
  page155_i201
#CELL
  mstr_discrete diode *
  page155_i202
#ISCELL
  mstr_standard offpage *
  page155_i31
#ISCELL
  mstr_standard offpage *
  page155_i32
#ISCELL
  mstr_standard offpage *
  page155_i33
#ISCELL
  mstr_standard offpage *
  page155_i34
#ISCELL
  mstr_standard offpage *
  page155_i37
#ISCELL
  mstr_standard offpage *
  page155_i38
#ISCELL
  mstr_standard offpage *
  page155_i39
#ISCELL
  mstr_standard offpage *
  page155_i40
#ISCELL
  mstr_symbols gnd *
  page155_i41
#ISCELL
  mstr_standard offpage *
  page155_i42
#ISCELL
  mstr_standard offpage *
  page155_i43
#ISCELL
  mstr_standard offpage *
  page155_i52
#CELL
  mstr_discrete res *
  page155_i53
#ISCELL
  mstr_standard offpage *
  page155_i55
#ISCELL
  mstr_standard offpage *
  page155_i56
#ISCELL
  mstr_standard offpage *
  page155_i57
#ISCELL
  mstr_standard offpage *
  page155_i58
#ISCELL
  mstr_standard offpage *
  page155_i59
#ISCELL
  mstr_standard offpage *
  page155_i60
#ISCELL
  mstr_standard offpage *
  page155_i61
#ISCELL
  mstr_standard offpage *
  page155_i62
#ISCELL
  mstr_standard offpage *
  page155_i63
#ISCELL
  mstr_standard offpage *
  page155_i64
#CELL
  mstr_discrete res *
  page155_i65
#CELL
  mstr_discrete res *
  page155_i66
#CELL
  mstr_discrete res *
  page155_i67
#CELL
  mstr_discrete res *
  page155_i68
#ISCELL
  mstr_standard offpage *
  page155_i69
#ISCELL
  mstr_standard offpage *
  page155_i70
#ISCELL
  mstr_standard offpage *
  page155_i71
#ISCELL
  mstr_standard offpage *
  page155_i72
#CELL
  mstr_discrete res *
  page155_i73
#CELL
  mstr_discrete res *
  page155_i74
#CELL
  mstr_discrete res *
  page155_i75
#CELL
  mstr_discrete res *
  page155_i76
#ISCELL
  mstr_standard offpage *
  page155_i77
#ISCELL
  mstr_standard offpage *
  page155_i78
#ISCELL
  mstr_standard offpage *
  page155_i79
#CELL
  mstr_discrete res *
  page155_i80
#ISCELL
  mstr_symbols p3v3_stby *
  page155_i81
#ISCELL
  mstr_misc dns *
  *
#ISCELL
  mstr_symbols cad_note *
  *
#ISCELL
  mstr_symbols intel_corp_bpage *
  *
#ISCELL
  mstr_standard offpage *
  page156_i202
#ISCELL
  mstr_standard offpage *
  page156_i203
#ISCELL
  mstr_standard offpage *
  page156_i204
#ISCELL
  mstr_standard offpage *
  page156_i205
#CELL
  mstr_discrete res *
  page156_i206
#CELL
  mstr_discrete res *
  page156_i207
#ISCELL
  mstr_symbols p3v3_stby *
  page156_i208
#ISCELL
  mstr_symbols p3v3_stby *
  page156_i209
#CELL
  mstr_discrete res *
  page156_i210
#CELL
  mstr_discrete res *
  page156_i211
#ISCELL
  mstr_standard offpage *
  page156_i212
#ISCELL
  mstr_standard offpage *
  page156_i213
#CELL
  mstr_discrete res *
  page156_i214
#CELL
  mstr_discrete res *
  page156_i215
#ISCELL
  mstr_symbols p3v3_stby *
  page156_i216
#ISCELL
  mstr_symbols gnd *
  page156_i257
#CELL
  mstr_discrete res *
  page156_i265
#ISCELL
  mstr_symbols p3v3_stby *
  page156_i266
#CELL
  mstr_discrete res *
  page156_i267
#ISCELL
  mstr_standard offpage *
  page156_i270
#ISCELL
  mstr_standard offpage *
  page156_i271
#ISCELL
  mstr_symbols p3v3_stby *
  page156_i272
#CELL
  dev_discrete cap_a *
  page156_i273
#ISCELL
  mstr_symbols gnd *
  page156_i274
#CELL
  dev_discrete cap_a *
  page156_i275
#ISCELL
  mstr_symbols gnd *
  page156_i276
#ISCELL
  mstr_symbols p3v3_stby *
  page156_i277
#ISCELL
  mstr_standard offpage *
  page156_i278
#CELL
  mstr_discrete res *
  page156_i279
#ISCELL
  mstr_standard offpage *
  page156_i280
#CELL
  mstr_conn conn3_c95678002 *
  page156_i281
#ISCELL
  mstr_symbols gnd *
  page156_i282
#ISCELL
  mstr_standard offpage *
  page156_i283
#ISCELL
  mstr_standard offpage *
  page156_i284
#CELL
  mstr_conn conn3_c95678002 *
  page156_i285
#ISCELL
  mstr_standard offpage *
  page156_i286
#ISCELL
  mstr_standard offpage *
  page156_i287
#CELL
  mstr_discrete res *
  page156_i288
#CELL
  mstr_discrete res *
  page156_i289
#ISCELL
  mstr_standard offpage *
  page156_i296
#ISCELL
  mstr_standard offpage *
  page156_i297
#ISCELL
  mstr_standard offpage *
  page156_i298
#CELL
  mstr_discrete res *
  page156_i299
#CELL
  mstr_discrete res *
  page156_i300
#CELL
  mstr_discrete res *
  page156_i302
#CELL
  mstr_discrete res *
  page156_i303
#CELL
  mstr_discrete res *
  page156_i304
#ISCELL
  mstr_standard offpage *
  page156_i305
#ISCELL
  mstr_symbols gnd *
  page156_i306
#ISCELL
  mstr_standard offpage *
  page156_i308
#ISCELL
  mstr_standard offpage *
  page156_i309
#ISCELL
  mstr_standard offpage *
  page156_i310
#ISCELL
  mstr_symbols gnd *
  page156_i311
#CELL
  mstr_discrete res *
  page156_i312
#CELL
  mstr_discrete res *
  page156_i313
#ISCELL
  mstr_standard offpage *
  page156_i314
#ISCELL
  mstr_standard offpage *
  page156_i315
#ISCELL
  mstr_standard offpage *
  page156_i316
#ISCELL
  mstr_symbols p3v3_stby *
  page156_i318
#CELL
  mstr_discrete res *
  page156_i320
#CELL
  mstr_discrete res *
  page156_i321
#CELL
  mstr_discrete res *
  page156_i322
#CELL
  mstr_discrete res *
  page156_i323
#CELL
  mstr_discrete res *
  page156_i324
#ISCELL
  mstr_standard offpage *
  page156_i325
#ISCELL
  mstr_standard offpage *
  page156_i326
#ISCELL
  mstr_standard offpage *
  page156_i327
#ISCELL
  mstr_standard offpage *
  page156_i328
#ISCELL
  mstr_standard offpage *
  page156_i329
#ISCELL
  mstr_standard offpage *
  page156_i330
#CELL
  mstr_discrete res *
  page156_i331
#ISCELL
  mstr_symbols p3v3_stby *
  page156_i332
#CELL
  mstr_discrete res *
  page156_i333
#ISCELL
  mstr_symbols gnd *
  page156_i334
#ISCELL
  mstr_standard offpage *
  page156_i335
#CELL
  mstr_discrete res *
  page156_i336
#CELL
  mstr_discrete res *
  page156_i337
#ISCELL
  mstr_symbols gnd *
  page156_i338
#ISCELL
  mstr_symbols p3v3_stby *
  page156_i339
#CELL
  w_hdl sn74lvc2g07dckr-gp *
  page156_i340
#ISCELL
  mstr_symbols gnd *
  page156_i341
#CELL
  w_hdl sn74lvc2g07dckr-gp *
  page156_i342
#ISCELL
  mstr_symbols gnd *
  page156_i343
#ISCELL
  mstr_misc dns *
  *
#ISCELL
  mstr_symbols cad_note *
  *
#ISCELL
  mstr_symbols intel_corp_bpage *
  *
#ISCELL
  mstr_standard offpage *
  page157_i293
#CELL
  mstr_discrete res *
  page157_i296
#ISCELL
  mstr_symbols p3v3_stby *
  page157_i297
#CELL
  mstr_discrete res *
  page157_i298
#ISCELL
  mstr_standard offpage *
  page157_i299
#ISCELL
  mstr_standard offpage *
  page157_i300
#ISCELL
  mstr_standard offpage *
  page157_i301
#CELL
  mstr_discrete res *
  page157_i302
#ISCELL
  mstr_symbols p3v3 *
  page157_i303
#CELL
  mstr_discrete res *
  page157_i316
#ISCELL
  mstr_standard offpage *
  page157_i317
#ISCELL
  mstr_symbols gnd *
  page157_i322
#ISCELL
  mstr_standard offpage *
  page157_i324
#ISCELL
  mstr_standard offpage *
  page157_i325
#CELL
  mstr_discrete res *
  page157_i326
#CELL
  mstr_discrete res *
  page157_i327
#ISCELL
  mstr_symbols p3v3_stby *
  page157_i328
#ISCELL
  mstr_symbols p3v3_stby *
  page157_i329
#CELL
  mstr_discrete npn *
  page157_i330
#ISCELL
  mstr_symbols gnd *
  page157_i333
#CELL
  mstr_discrete res *
  page157_i335
#ISCELL
  mstr_symbols p3v3_stby *
  page157_i339
#CELL
  mstr_discrete fet_n *
  page157_i340
#CELL
  mstr_discrete res *
  page157_i342
#ISCELL
  mstr_standard offpage *
  page157_i343
#CELL
  mstr_discrete res *
  page157_i344
#ISCELL
  mstr_standard offpage *
  page157_i345
#CELL
  mstr_discrete res *
  page157_i346
#ISCELL
  mstr_standard offpage *
  page157_i347
#CELL
  mstr_discrete res *
  page157_i348
#ISCELL
  mstr_standard offpage *
  page157_i349
#CELL
  mstr_misc switch_d90553001 *
  page157_i351
#CELL
  mstr_discrete res *
  page157_i352
#CELL
  dev_discrete cap_a *
  page157_i353
#ISCELL
  mstr_symbols gnd *
  page157_i354
#ISCELL
  mstr_symbols gnd *
  page157_i355
#ISCELL
  mstr_standard offpage *
  page157_i359
#ISCELL
  mstr_standard offpage *
  page157_i360
#CELL
  mstr_discrete res *
  page157_i361
#ISCELL
  mstr_symbols p3v3_stby *
  page157_i362
#ISCELL
  mstr_standard offpage *
  page157_i366
#CELL
  mstr_discrete res *
  page157_i367
#CELL
  mstr_discrete res *
  page157_i368
#ISCELL
  mstr_symbols p3v3_stby *
  page157_i369
#CELL
  dev_discrete cap_a *
  page157_i370
#ISCELL
  mstr_symbols gnd *
  page157_i371
#ISCELL
  mstr_standard offpage *
  page157_i373
#CELL
  mstr_ttl ttl1g07_a *
  page157_i374
#ISCELL
  mstr_standard offpage *
  page157_i375
#CELL
  dev_discrete cap_a *
  page157_i376
#ISCELL
  mstr_symbols gnd *
  page157_i377
#ISCELL
  mstr_symbols p3v3_stby *
  page157_i378
#ISCELL
  mstr_standard offpage *
  page157_i380
#ISCELL
  mstr_standard offpage *
  page157_i381
#CELL
  mstr_discrete res *
  page157_i382
#ISCELL
  mstr_symbols p3v3_stby *
  page157_i384
#CELL
  mstr_discrete res *
  page157_i385
#CELL
  mstr_discrete res *
  page157_i386
#CELL
  mstr_discrete res *
  page157_i388
#ISCELL
  mstr_standard offpage *
  page157_i389
#CELL
  w_hdl tc7pz14fu-gp *
  page157_i390
#CELL
  mstr_discrete res *
  page157_i391
#ISCELL
  mstr_symbols gnd *
  page157_i392
#CELL
  mstr_discrete res *
  page157_i393
#CELL
  mstr_ttl ttl1g07_a *
  page157_i394
#ISCELL
  mstr_symbols p3v3_stby *
  page157_i395
#CELL
  mstr_discrete res *
  page157_i396
#ISCELL
  mstr_standard offpage *
  page157_i397
#CELL
  mstr_discrete res *
  page157_i97
#ISCELL
  mstr_misc dns *
  *
#ISCELL
  mstr_symbols cad_note *
  *
#ISCELL
  mstr_symbols design_note *
  *
#ISCELL
  mstr_symbols intel_corp_bpage *
  *
#CELL
  mstr_discrete res *
  page158_i100
#ISCELL
  mstr_standard offpage *
  page158_i124
#ISCELL
  mstr_standard offpage *
  page158_i125
#ISCELL
  mstr_standard offpage *
  page158_i126
#ISCELL
  mstr_standard offpage *
  page158_i127
#ISCELL
  mstr_standard offpage *
  page158_i128
#ISCELL
  mstr_standard offpage *
  page158_i129
#CELL
  mstr_discrete led *
  page158_i130
#CELL
  mstr_discrete res *
  page158_i131
#ISCELL
  mstr_standard offpage *
  page158_i132
#CELL
  mstr_discrete led *
  page158_i134
#ISCELL
  mstr_symbols p3v3_stby *
  page158_i135
#CELL
  mstr_discrete res *
  page158_i136
#ISCELL
  mstr_standard offpage *
  page158_i137
#ISCELL
  mstr_standard offpage *
  page158_i144
#ISCELL
  mstr_standard offpage *
  page158_i147
#CELL
  mstr_discrete res *
  page158_i148
#CELL
  mstr_discrete res *
  page158_i149
#CELL
  mstr_discrete res *
  page158_i150
#CELL
  mstr_discrete res *
  page158_i152
#CELL
  mstr_discrete res *
  page158_i153
#CELL
  mstr_discrete res *
  page158_i154
#CELL
  mstr_discrete res *
  page158_i155
#ISCELL
  mstr_symbols p3v3_stby *
  page158_i156
#CELL
  dev_discrete cap_a *
  page158_i70
#ISCELL
  mstr_symbols gnd *
  page158_i72
#CELL
  mstr_analog fsa3357 *
  page158_i74
#CELL
  mstr_analog fsa3357 *
  page158_i75
#ISCELL
  mstr_symbols gnd *
  page158_i76
#ISCELL
  mstr_symbols gnd *
  page158_i77
#ISCELL
  mstr_symbols p3v3_stby *
  page158_i78
#ISCELL
  mstr_symbols p3v3_stby *
  page158_i79
#ISCELL
  mstr_standard offpage *
  page158_i85
#CELL
  mstr_discrete res *
  page158_i86
#ISCELL
  mstr_standard offpage *
  page158_i87
#CELL
  mstr_discrete res *
  page158_i91
#ISCELL
  mstr_standard offpage *
  page158_i92
#ISCELL
  mstr_standard offpage *
  page158_i93
#ISCELL
  mstr_standard offpage *
  page158_i94
#ISCELL
  mstr_standard offpage *
  page158_i95
#CELL
  dev_discrete cap_a *
  page158_i97
#ISCELL
  mstr_symbols gnd *
  page158_i98
#CELL
  mstr_discrete res *
  page158_i99
#ISCELL
  mstr_misc dns *
  *
#ISCELL
  mstr_symbols cad_note *
  *
#ISCELL
  mstr_symbols intel_corp_bpage *
  *
#ISCELL
  mstr_standard offpage *
  page159_i111
#ISCELL
  mstr_standard offpage *
  page159_i112
#ISCELL
  mstr_standard offpage *
  page159_i113
#ISCELL
  mstr_standard offpage *
  page159_i114
#ISCELL
  mstr_standard offpage *
  page159_i117
#ISCELL
  mstr_standard offpage *
  page159_i118
#ISCELL
  mstr_standard offpage *
  page159_i161
#ISCELL
  mstr_standard offpage *
  page159_i162
#ISCELL
  mstr_standard offpage *
  page159_i168
#ISCELL
  mstr_standard offpage *
  page159_i169
#ISCELL
  mstr_standard offpage *
  page159_i170
#ISCELL
  mstr_standard offpage *
  page159_i171
#ISCELL
  mstr_standard offpage *
  page159_i185
#ISCELL
  mstr_standard offpage *
  page159_i186
#ISCELL
  mstr_standard offpage *
  page159_i187
#ISCELL
  mstr_standard offpage *
  page159_i188
#ISCELL
  mstr_standard offpage *
  page159_i189
#ISCELL
  mstr_standard offpage *
  page159_i190
#ISCELL
  mstr_standard offpage *
  page159_i195
#ISCELL
  mstr_standard offpage *
  page159_i196
#ISCELL
  mstr_standard offpage *
  page159_i197
#ISCELL
  mstr_standard offpage *
  page159_i198
#ISCELL
  mstr_standard offpage *
  page159_i199
#ISCELL
  mstr_standard offpage *
  page159_i200
#ISCELL
  mstr_symbols p3v3_stby *
  page159_i209
#CELL
  mstr_discrete res *
  page159_i210
#ISCELL
  mstr_symbols p3v3_stby *
  page159_i211
#CELL
  mstr_discrete res *
  page159_i212
#ISCELL
  mstr_symbols p3v3_stby *
  page159_i213
#CELL
  mstr_discrete res *
  page159_i214
#ISCELL
  mstr_symbols p3v3_stby *
  page159_i215
#CELL
  mstr_discrete res *
  page159_i216
#CELL
  mstr_discrete res *
  page159_i218
#CELL
  mstr_discrete res *
  page159_i219
#CELL
  mstr_discrete res *
  page159_i220
#CELL
  mstr_discrete res *
  page159_i221
#CELL
  mstr_discrete res *
  page159_i222
#CELL
  mstr_discrete res *
  page159_i223
#CELL
  mstr_discrete res *
  page159_i224
#CELL
  mstr_discrete res *
  page159_i225
#CELL
  mstr_discrete res *
  page159_i226
#CELL
  mstr_discrete res *
  page159_i227
#CELL
  mstr_discrete res *
  page159_i228
#CELL
  mstr_discrete res *
  page159_i229
#CELL
  mstr_discrete res *
  page159_i230
#CELL
  mstr_discrete res *
  page159_i231
#CELL
  mstr_discrete res *
  page159_i232
#CELL
  mstr_discrete res *
  page159_i233
#ISCELL
  mstr_symbols p3v3_stby *
  page159_i234
#CELL
  mstr_discrete res *
  page159_i235
#ISCELL
  mstr_symbols p3v3_stby *
  page159_i236
#CELL
  mstr_discrete res *
  page159_i237
#ISCELL
  mstr_standard offpage *
  page159_i75
#ISCELL
  mstr_standard offpage *
  page159_i76
#ISCELL
  mstr_standard offpage *
  page159_i77
#ISCELL
  mstr_standard offpage *
  page159_i78
#ISCELL
  mstr_standard offpage *
  page159_i79
#ISCELL
  mstr_standard offpage *
  page159_i83
#ISCELL
  mstr_symbols cad_note *
  *
#ISCELL
  mstr_symbols design_note *
  *
#ISCELL
  mstr_symbols intel_corp_bpage *
  *
#ISCELL
  mstr_standard offpage *
  page160_i1
#ISCELL
  mstr_standard offpage *
  page160_i10
#ISCELL
  mstr_standard offpage *
  page160_i17
#ISCELL
  mstr_standard offpage *
  page160_i18
#ISCELL
  mstr_standard offpage *
  page160_i19
#ISCELL
  mstr_standard offpage *
  page160_i2
#ISCELL
  mstr_standard offpage *
  page160_i20
#CELL
  mstr_discrete res *
  page160_i4
#CELL
  mstr_discrete res *
  page160_i46
#ISCELL
  mstr_symbols p3v3_stby *
  page160_i47
#ISCELL
  mstr_symbols p3v3_stby *
  page160_i48
#CELL
  mstr_discrete res *
  page160_i49
#CELL
  mstr_discrete res *
  page160_i50
#CELL
  mstr_discrete res *
  page160_i51
#CELL
  mstr_discrete res *
  page160_i52
#ISCELL
  mstr_standard offpage *
  page160_i9
#ISCELL
  mstr_misc dns *
  *
#ISCELL
  mstr_symbols cad_note *
  *
#ISCELL
  mstr_symbols intel_corp_bpage *
  *
#ISCELL
  mstr_standard offpage *
  page161_i100
#CELL
  mstr_discrete res *
  page161_i102
#ISCELL
  mstr_standard offpage *
  page161_i103
#ISCELL
  mstr_symbols gnd *
  page161_i104
#ISCELL
  mstr_symbols p3v3_stby *
  page161_i105
#ISCELL
  mstr_symbols p12v_fan *
  page161_i108
#ISCELL
  mstr_symbols p12v_fan *
  page161_i110
#ISCELL
  mstr_symbols gnd *
  page161_i111
#CELL
  dev_discrete cap_a *
  page161_i113
#ISCELL
  mstr_standard offpage *
  page161_i114
#ISCELL
  mstr_standard offpage *
  page161_i115
#ISCELL
  mstr_standard offpage *
  page161_i116
#ISCELL
  mstr_symbols p3v3_stby *
  page161_i117
#ISCELL
  mstr_symbols gnd *
  page161_i118
#ISCELL
  mstr_symbols p3v3_stby *
  page161_i119
#CELL
  mstr_discrete res *
  page161_i120
#CELL
  mstr_ttl ttl1g08 *
  page161_i121
#ISCELL
  mstr_symbols gnd *
  page161_i122
#ISCELL
  mstr_symbols gnd *
  page161_i13
#CELL
  w_hdl lotes-con4-s1-gp *
  page161_i139
#CELL
  w_hdl lotes-con4-s1-gp *
  page161_i140
#CELL
  dev_discrete cap_a *
  page161_i26
#CELL
  mstr_discrete cap *
  page161_i27
#CELL
  mstr_discrete cap *
  page161_i3
#ISCELL
  mstr_symbols gnd *
  page161_i30
#CELL
  dev_discrete cap_a *
  page161_i4
#CELL
  mstr_discrete diode *
  page161_i42
#CELL
  mstr_discrete res *
  page161_i43
#CELL
  mstr_discrete res *
  page161_i45
#CELL
  dev_discrete cap_a *
  page161_i46
#ISCELL
  mstr_symbols gnd *
  page161_i47
#ISCELL
  mstr_symbols p3v3_stby *
  page161_i48
#ISCELL
  mstr_standard offpage *
  page161_i49
#CELL
  mstr_discrete diode *
  page161_i50
#CELL
  mstr_discrete res *
  page161_i51
#ISCELL
  mstr_symbols p5v_stby *
  page161_i52
#ISCELL
  mstr_standard offpage *
  page161_i53
#ISCELL
  mstr_symbols p3v3_stby *
  page161_i61
#CELL
  mstr_discrete diode *
  page161_i62
#ISCELL
  mstr_symbols p5v_stby *
  page161_i63
#CELL
  mstr_discrete diode *
  page161_i64
#CELL
  mstr_discrete res *
  page161_i65
#CELL
  mstr_discrete res *
  page161_i67
#CELL
  dev_discrete cap_a *
  page161_i68
#ISCELL
  mstr_symbols gnd *
  page161_i69
#CELL
  mstr_discrete res *
  page161_i70
#ISCELL
  mstr_standard offpage *
  page161_i75
#ISCELL
  mstr_standard offpage *
  page161_i76
#CELL
  mstr_ttl ttl1g07_a *
  page161_i88
#CELL
  dev_discrete cap_a *
  page161_i90
#CELL
  mstr_ttl ttl1g07_a *
  page161_i92
#CELL
  dev_discrete cap_a *
  page161_i93
#ISCELL
  mstr_standard offpage *
  page161_i94
#ISCELL
  mstr_symbols p3v3_stby *
  page161_i96
#ISCELL
  mstr_symbols gnd *
  page161_i97
#ISCELL
  mstr_standard offpage *
  page161_i98
#CELL
  mstr_discrete res *
  page161_i99
#ISCELL
  mstr_misc dns *
  *
#ISCELL
  mstr_symbols bom_note *
  *
#ISCELL
  mstr_symbols cad_note *
  *
#ISCELL
  mstr_symbols intel_corp_bpage *
  *
#ISCELL
  mstr_symbols p3v3_stby *
  page162_i10
#CELL
  mstr_discrete res *
  page162_i13
#ISCELL
  mstr_standard offpage *
  page162_i16
#ISCELL
  mstr_standard offpage *
  page162_i17
#ISCELL
  mstr_standard offpage *
  page162_i19
#ISCELL
  mstr_standard offpage *
  page162_i21
#CELL
  mstr_discrete res *
  page162_i22
#CELL
  mstr_discrete res *
  page162_i24
#CELL
  dev_discrete cap_a *
  page162_i28
#CELL
  dev_discrete cap_a *
  page162_i30
#ISCELL
  mstr_symbols gnd *
  page162_i31
#CELL
  mstr_memory w25q128 *
  page162_i32
#ISCELL
  mstr_symbols gnd *
  page162_i33
#CELL
  mstr_discrete res *
  page162_i35
#ISCELL
  mstr_symbols gnd *
  page162_i6
#CELL
  mstr_discrete res *
  page162_i8
#CELL
  mstr_discrete res *
  page162_i9
#ISCELL
  mstr_symbols cad_note *
  *
#ISCELL
  mstr_symbols design_note *
  *
#ISCELL
  mstr_symbols intel_corp_bpage *
  *
#CELL
  dev_discrete cap_a *
  page163_i10
#ISCELL
  mstr_symbols gnd *
  page163_i11
#CELL
  dev_discrete cap_a *
  page163_i12
#ISCELL
  mstr_symbols gnd *
  page163_i13
#CELL
  mstr_discrete res *
  page163_i15
#CELL
  mstr_discrete res *
  page163_i16
#ISCELL
  mstr_standard offpage *
  page163_i18
#ISCELL
  mstr_standard offpage *
  page163_i19
#CELL
  mstr_discrete res *
  page163_i2
#CELL
  mstr_discrete res *
  page163_i20
#CELL
  mstr_discrete res *
  page163_i21
#ISCELL
  mstr_symbols p3v3_stby *
  page163_i26
#ISCELL
  mstr_symbols p3v3_stby *
  page163_i27
#CELL
  w_hdl tca9517dgkr-gp *
  page163_i28
#ISCELL
  mstr_symbols gnd *
  page163_i29
#CELL
  mstr_discrete res *
  page163_i3
#ISCELL
  mstr_standard offpage *
  page163_i4
#ISCELL
  mstr_standard offpage *
  page163_i5
#CELL
  mstr_discrete res *
  page163_i6
#CELL
  mstr_discrete res *
  page163_i7
#ISCELL
  mstr_symbols pvccio_cpu1 *
  page163_i8
#ISCELL
  mstr_symbols pvccio_cpu1 *
  page163_i9
#ISCELL
  mstr_misc dns *
  *
#ISCELL
  mstr_symbols intel_corp_bpage *
  *
#CELL
  mstr_discrete res *
  page164_i100
#CELL
  mstr_discrete res *
  page164_i101
#CELL
  mstr_discrete res *
  page164_i11
#ISCELL
  mstr_symbols p3v3_stby *
  page164_i12
#ISCELL
  mstr_standard offpage *
  page164_i15
#ISCELL
  mstr_standard offpage *
  page164_i16
#ISCELL
  mstr_standard offpage *
  page164_i17
#ISCELL
  mstr_standard offpage *
  page164_i18
#ISCELL
  mstr_standard offpage *
  page164_i2
#CELL
  mstr_discrete res *
  page164_i21
#ISCELL
  mstr_symbols p3v3_stby *
  page164_i26
#ISCELL
  mstr_standard offpage *
  page164_i3
#ISCELL
  mstr_standard offpage *
  page164_i30
#ISCELL
  mstr_symbols gnd *
  page164_i31
#CELL
  mstr_discrete res *
  page164_i32
#CELL
  mstr_discrete res *
  page164_i34
#CELL
  mstr_discrete res *
  page164_i37
#ISCELL
  mstr_standard offpage *
  page164_i4
#CELL
  mstr_discrete res *
  page164_i40
#CELL
  mstr_discrete res *
  page164_i41
#CELL
  mstr_discrete res *
  page164_i43
#CELL
  mstr_discrete res *
  page164_i46
#CELL
  mstr_discrete res *
  page164_i47
#CELL
  mstr_discrete res *
  page164_i48
#CELL
  mstr_discrete res *
  page164_i51
#CELL
  mstr_discrete res *
  page164_i53
#ISCELL
  mstr_symbols gnd *
  page164_i55
#ISCELL
  mstr_standard offpage *
  page164_i56
#ISCELL
  mstr_symbols p3v3_stby *
  page164_i65
#CELL
  dev_discrete cap_a *
  page164_i66
#ISCELL
  mstr_symbols gnd *
  page164_i67
#CELL
  mstr_discrete res *
  page164_i7
#CELL
  mstr_discrete res *
  page164_i76
#CELL
  mstr_discrete res *
  page164_i78
#ISCELL
  mstr_symbols p3v3_stby *
  page164_i81
#ISCELL
  mstr_symbols gnd *
  page164_i82
#ISCELL
  mstr_symbols gnd *
  page164_i84
#ISCELL
  mstr_symbols gnd *
  page164_i86
#CELL
  mstr_discrete res *
  page164_i87
#ISCELL
  mstr_symbols p3v3_stby *
  page164_i88
#ISCELL
  mstr_standard offpage *
  page164_i89
#ISCELL
  mstr_symbols gnd *
  page164_i9
#ISCELL
  mstr_standard offpage *
  page164_i90
#ISCELL
  mstr_standard offpage *
  page164_i91
#ISCELL
  mstr_standard offpage *
  page164_i92
#CELL
  mstr_discrete res *
  page164_i93
#CELL
  mstr_discrete res *
  page164_i94
#CELL
  mstr_discrete res *
  page164_i95
#CELL
  mstr_discrete res *
  page164_i96
#CELL
  w_hdl pca9554pwr-gp *
  page164_i97
#ISCELL
  mstr_standard offpage *
  page164_i99
#ISCELL
  mstr_symbols intel_corp_bpage *
  *
#ISCELL
  mstr_misc dns *
  *
#ISCELL
  mstr_symbols cad_note *
  *
#ISCELL
  mstr_symbols design_note *
  *
#ISCELL
  mstr_symbols intel_corp_bpage *
  *
#ISCELL
  mstr_standard offpage *
  page166_i16
#ISCELL
  mstr_standard offpage *
  page166_i17
#CELL
  mstr_discrete res *
  page166_i28
#ISCELL
  mstr_symbols pvccio_cpu0 *
  page166_i31
#CELL
  mstr_discrete res *
  page166_i32
#ISCELL
  mstr_symbols gnd *
  page166_i33
#CELL
  w_hdl pi5a3157bc6e-gp *
  page166_i34
#CELL
  dev_discrete cap_a *
  page166_i36
#ISCELL
  mstr_symbols gnd *
  page166_i37
#ISCELL
  mstr_standard offpage *
  page166_i38
#ISCELL
  mstr_standard offpage *
  page166_i39
#ISCELL
  mstr_symbols p3v3_stby *
  page166_i40
#ISCELL
  mstr_symbols gnd *
  page166_i41
#CELL
  mstr_discrete res *
  page166_i42
#ISCELL
  mstr_symbols gnd *
  page166_i43
#ISCELL
  mstr_symbols p3v3_stby *
  page166_i45
#CELL
  mstr_discrete res *
  page166_i46
#ISCELL
  mstr_misc dns *
  *
#ISCELL
  mstr_symbols cad_note *
  *
#ISCELL
  mstr_symbols design_note *
  *
#ISCELL
  mstr_symbols intel_corp_bpage *
  *
#CELL
  mstr_analog tmp421 *
  page167_i1
#CELL
  mstr_discrete res *
  page167_i10
#ISCELL
  mstr_symbols gnd *
  page167_i12
#ISCELL
  mstr_symbols p3v3_stby *
  page167_i14
#ISCELL
  mstr_symbols gnd *
  page167_i15
#ISCELL
  mstr_standard offpage *
  page167_i16
#ISCELL
  mstr_standard offpage *
  page167_i17
#ISCELL
  mstr_symbols gnd *
  page167_i22
#ISCELL
  mstr_symbols p3v3_stby *
  page167_i23
#CELL
  mstr_discrete cap *
  page167_i24
#CELL
  mstr_discrete res *
  page167_i25
#CELL
  mstr_discrete res *
  page167_i26
#ISCELL
  mstr_symbols p3v3_stby *
  page167_i29
#CELL
  mstr_analog tmp421 *
  page167_i30
#CELL
  mstr_discrete res *
  page167_i34
#CELL
  mstr_discrete res *
  page167_i35
#CELL
  mstr_discrete res *
  page167_i38
#CELL
  dev_discrete cap_a *
  page167_i39
#CELL
  dev_discrete cap_a *
  page167_i41
#CELL
  dev_discrete cap_a *
  page167_i42
#ISCELL
  mstr_symbols gnd *
  page167_i45
#ISCELL
  mstr_symbols gnd *
  page167_i46
#ISCELL
  mstr_symbols gnd *
  page167_i47
#CELL
  mstr_memory at24c64 *
  page167_i49
#CELL
  mstr_discrete res *
  page167_i5
#CELL
  mstr_discrete res *
  page167_i50
#ISCELL
  mstr_symbols gnd *
  page167_i52
#ISCELL
  mstr_symbols gnd *
  page167_i55
#ISCELL
  mstr_symbols p3v3_stby *
  page167_i56
#ISCELL
  mstr_symbols p3v3_stby *
  page167_i57
#CELL
  mstr_discrete res *
  page167_i58
#CELL
  mstr_discrete res *
  page167_i6
#ISCELL
  mstr_standard offpage *
  page167_i60
#ISCELL
  mstr_standard offpage *
  page167_i61
#ISCELL
  mstr_standard offpage *
  page167_i62
#ISCELL
  mstr_standard offpage *
  page167_i63
#CELL
  mstr_discrete cap *
  page167_i7
#CELL
  mstr_discrete res *
  page167_i70
#ISCELL
  mstr_symbols p3v3_stby *
  page167_i71
#ISCELL
  mstr_symbols p3v3_stby *
  page167_i72
#ISCELL
  mstr_symbols p3v3_stby *
  page167_i73
#CELL
  mstr_discrete res *
  page167_i74
#CELL
  mstr_discrete res *
  page167_i75
#CELL
  mstr_discrete res *
  page167_i76
#CELL
  mstr_discrete res *
  page167_i77
#CELL
  mstr_discrete res *
  page167_i8
#CELL
  mstr_discrete res *
  page167_i80
#ISCELL
  mstr_symbols p3v3_stby *
  page167_i81
#ISCELL
  mstr_symbols p3v3_stby *
  page167_i82
#CELL
  mstr_discrete res *
  page167_i83
#CELL
  mstr_discrete res *
  page167_i84
#CELL
  mstr_discrete res *
  page167_i85
#ISCELL
  mstr_standard offpage *
  page167_i86
#ISCELL
  mstr_standard offpage *
  page167_i87
#CELL
  w_hdl 2sb2907a-b0-00001-gp *
  page167_i93
#CELL
  w_hdl 2sb2907a-b0-00001-gp *
  page167_i94
#ISCELL
  mstr_symbols intel_corp_bpage *
  *
#ISCELL
  mstr_standard offpage *
  page168_i1
#CELL
  mstr_discrete res *
  page168_i11
#ISCELL
  mstr_symbols gnd *
  page168_i14
#CELL
  mstr_discrete fet_n_dual *
  page168_i18
#CELL
  mstr_discrete fet_n_dual *
  page168_i19
#CELL
  mstr_discrete diode *
  page168_i2
#CELL
  mstr_discrete res *
  page168_i22
#ISCELL
  mstr_symbols p3v3_stby *
  page168_i24
#ISCELL
  mstr_symbols gnd *
  page168_i26
#ISCELL
  mstr_standard offpage *
  page168_i28
#ISCELL
  mstr_symbols p3v3_stby *
  page168_i29
#CELL
  mstr_discrete diode *
  page168_i3
#ISCELL
  mstr_standard offpage *
  page168_i31
#ISCELL
  mstr_symbols gnd *
  page168_i36
#ISCELL
  mstr_symbols p3v3_stby *
  page168_i38
#CELL
  mstr_discrete diode *
  page168_i4
#CELL
  mstr_discrete fet_n *
  page168_i43
#ISCELL
  mstr_symbols gnd *
  page168_i44
#ISCELL
  mstr_standard offpage *
  page168_i45
#CELL
  mstr_discrete res *
  page168_i46
#CELL
  mstr_discrete npn *
  page168_i47
#CELL
  mstr_discrete res *
  page168_i48
#CELL
  mstr_discrete diode *
  page168_i5
#CELL
  mstr_discrete res *
  page168_i6
#CELL
  mstr_discrete npn *
  page168_i8
#ISCELL
  mstr_symbols cad_note *
  *
#ISCELL
  mstr_symbols design_note *
  *
#ISCELL
  mstr_symbols intel_corp_bpage *
  *
#ISCELL
  mstr_standard offpage *
  page169_i103
#ISCELL
  mstr_standard offpage *
  page169_i105
#CELL
  mstr_discrete res *
  page169_i106
#ISCELL
  mstr_symbols gnd *
  page169_i107
#CELL
  mstr_discrete cap *
  page169_i108
#ISCELL
  mstr_symbols gnd *
  page169_i109
#CELL
  mstr_discrete res *
  page169_i115
#ISCELL
  mstr_symbols p5v_stby *
  page169_i119
#ISCELL
  mstr_symbols p1v05_pch_stby *
  page169_i121
#CELL
  mstr_discrete res *
  page169_i126
#ISCELL
  mstr_symbols p3v3_stby *
  page169_i131
#ISCELL
  mstr_symbols p12v_stby *
  page169_i132
#ISCELL
  mstr_standard offpage *
  page169_i138
#CELL
  mstr_discrete cap *
  page169_i139
#CELL
  mstr_discrete res *
  page169_i141
#ISCELL
  mstr_symbols gnd *
  page169_i143
#ISCELL
  mstr_symbols p5v *
  page169_i144
#ISCELL
  mstr_standard offpage *
  page169_i145
#CELL
  mstr_discrete cap *
  page169_i146
#CELL
  mstr_discrete res *
  page169_i148
#ISCELL
  mstr_symbols gnd *
  page169_i150
#ISCELL
  mstr_symbols p3v3 *
  page169_i151
#ISCELL
  mstr_standard offpage *
  page169_i152
#CELL
  mstr_discrete cap *
  page169_i153
#ISCELL
  mstr_symbols pvnn_pch_stby *
  page169_i154
#CELL
  mstr_discrete ferrite *
  page169_i155
#ISCELL
  mstr_symbols gnd *
  page169_i156
#CELL
  mstr_discrete fet_n_dual *
  page169_i157
#ISCELL
  mstr_symbols gnd *
  page169_i160
#ISCELL
  mstr_standard offpage *
  page169_i161
#CELL
  mstr_discrete fet_n_dual *
  page169_i162
#CELL
  mstr_discrete res *
  page169_i163
#CELL
  mstr_discrete res *
  page169_i164
#ISCELL
  mstr_symbols p3v3_stby *
  page169_i165
#ISCELL
  mstr_symbols p3v3_stby *
  page169_i166
#CELL
  w_hdl 1k82r2f-1-gp *
  page169_i169
#CELL
  w_hdl 1k82r2f-1-gp *
  page169_i170
#CELL
  w_hdl 649r2f-gp *
  page169_i171
#CELL
  mstr_discrete res *
  page169_i172
#CELL
  mstr_discrete res *
  page169_i173
#ISCELL
  mstr_standard offpage *
  page169_i55
#CELL
  mstr_discrete cap *
  page169_i56
#CELL
  mstr_discrete ferrite *
  page169_i57
#ISCELL
  mstr_symbols gnd *
  page169_i58
#ISCELL
  mstr_standard offpage *
  page169_i67
#CELL
  mstr_discrete cap *
  page169_i68
#ISCELL
  mstr_symbols gnd *
  page169_i71
#ISCELL
  mstr_standard offpage *
  page169_i79
#CELL
  mstr_discrete cap *
  page169_i80
#CELL
  mstr_discrete res *
  page169_i82
#ISCELL
  mstr_symbols gnd *
  page169_i84
#ISCELL
  mstr_standard offpage *
  page169_i85
#CELL
  mstr_discrete cap *
  page169_i86
#CELL
  mstr_discrete res *
  page169_i88
#ISCELL
  mstr_symbols gnd *
  page169_i90
#ISCELL
  mstr_misc dns *
  *
#ISCELL
  mstr_symbols cad_note *
  *
#ISCELL
  mstr_symbols design_note *
  *
#ISCELL
  mstr_symbols intel_corp_bpage *
  *
#CELL
  mstr_ttl ttl08 *
  page170_i10
#CELL
  mstr_ttl ttl08 *
  page170_i11
#CELL
  mstr_ttl ttl08 *
  page170_i12
#ISCELL
  mstr_standard offpage *
  page170_i15
#ISCELL
  mstr_standard offpage *
  page170_i16
#ISCELL
  mstr_standard offpage *
  page170_i17
#ISCELL
  mstr_standard offpage *
  page170_i18
#ISCELL
  mstr_standard offpage *
  page170_i19
#CELL
  mstr_discrete res *
  page170_i2
#CELL
  mstr_ttl ttl1g126_a *
  page170_i20
#ISCELL
  mstr_symbols p3v3_stby *
  page170_i3
#CELL
  dev_discrete cap_a *
  page170_i30
#ISCELL
  mstr_symbols gnd *
  page170_i31
#ISCELL
  mstr_symbols p3v3_stby *
  page170_i32
#CELL
  dev_discrete cap_a *
  page170_i33
#ISCELL
  mstr_symbols gnd *
  page170_i34
#ISCELL
  mstr_symbols p3v3_stby *
  page170_i35
#CELL
  mstr_ttl ttl1g126_a *
  page170_i38
#ISCELL
  mstr_symbols p3v3_stby *
  page170_i39
#CELL
  mstr_ttl ttl1g07_a *
  page170_i4
#CELL
  dev_discrete cap_a *
  page170_i40
#ISCELL
  mstr_symbols gnd *
  page170_i41
#CELL
  mstr_discrete cap *
  page170_i42
#ISCELL
  mstr_symbols gnd *
  page170_i43
#ISCELL
  mstr_standard offpage *
  page170_i44
#CELL
  mstr_ttl ttl1g07_a *
  page170_i46
#ISCELL
  mstr_standard offpage *
  page170_i47
#ISCELL
  mstr_symbols p3v3_stby *
  page170_i48
#CELL
  dev_discrete cap_a *
  page170_i49
#ISCELL
  mstr_standard offpage *
  page170_i5
#ISCELL
  mstr_symbols gnd *
  page170_i50
#CELL
  mstr_discrete res *
  page170_i51
#ISCELL
  mstr_symbols p3v3_stby *
  page170_i53
#CELL
  mstr_discrete res *
  page170_i54
#ISCELL
  mstr_symbols p3v3_stby *
  page170_i55
#CELL
  mstr_discrete res *
  page170_i56
#CELL
  mstr_discrete fet_n *
  page170_i58
#ISCELL
  mstr_standard offpage *
  page170_i59
#ISCELL
  mstr_symbols p3v3_stby *
  page170_i6
#ISCELL
  mstr_symbols gnd *
  page170_i60
#CELL
  mstr_discrete res *
  page170_i61
#ISCELL
  mstr_symbols p3v3_stby *
  page170_i62
#CELL
  mstr_discrete res *
  page170_i63
#ISCELL
  mstr_symbols gnd *
  page170_i64
#CELL
  mstr_discrete res *
  page170_i65
#ISCELL
  mstr_symbols p3v3_stby *
  page170_i66
#CELL
  mstr_discrete fet_n *
  page170_i67
#ISCELL
  mstr_symbols gnd *
  page170_i68
#ISCELL
  mstr_standard offpage *
  page170_i69
#ISCELL
  mstr_symbols gnd *
  page170_i7
#ISCELL
  mstr_symbols p3v3_stby *
  page170_i70
#CELL
  mstr_discrete res *
  page170_i71
#ISCELL
  mstr_symbols p3v3_stby *
  page170_i72
#CELL
  mstr_discrete res *
  page170_i73
#CELL
  mstr_discrete res *
  page170_i74
#CELL
  mstr_discrete res *
  page170_i75
#CELL
  dev_discrete cap_a *
  page170_i8
#ISCELL
  mstr_symbols intel_corp_bpage *
  *
#ISCELL
  mstr_symbols design_note *
  *
#ISCELL
  mstr_symbols intel_corp_bpage *
  *
#ISCELL
  mstr_standard offpage *
  page172_i10
#ISCELL
  mstr_standard offpage *
  page172_i11
#ISCELL
  mstr_standard offpage *
  page172_i12
#ISCELL
  mstr_symbols gnd *
  page172_i35
#CELL
  mstr_discrete cap *
  page172_i36
#ISCELL
  mstr_symbols p12v *
  page172_i37
#CELL
  mstr_discrete cap *
  page172_i39
#ISCELL
  mstr_symbols gnd *
  page172_i40
#ISCELL
  mstr_symbols p5v *
  page172_i42
#CELL
  dev_discrete cap_a *
  page172_i5
#ISCELL
  mstr_symbols gnd *
  page172_i57
#ISCELL
  mstr_symbols gnd *
  page172_i58
#ISCELL
  mstr_symbols gnd *
  page172_i59
#CELL
  dev_discrete cap_a *
  page172_i6
#ISCELL
  mstr_symbols gnd *
  page172_i60
#ISCELL
  mstr_symbols gnd *
  page172_i61
#ISCELL
  mstr_symbols gnd *
  page172_i62
#ISCELL
  mstr_symbols gnd *
  page172_i63
#ISCELL
  mstr_symbols gnd *
  page172_i64
#CELL
  mstr_discrete fuse *
  page172_i66
#CELL
  w_hdl skt-sata7p-6p-165-gp-u1 *
  page172_i67
#CELL
  w_hdl skt-sata7p-6p-165-gp-u1 *
  page172_i68
#ISCELL
  mstr_symbols gnd *
  page172_i69
#CELL
  dev_discrete cap_a *
  page172_i7
#ISCELL
  mstr_symbols gnd *
  page172_i70
#CELL
  w_hdl fuse-3a75v-gp *
  page172_i71
#CELL
  dev_discrete cap_a *
  page172_i8
#ISCELL
  mstr_standard offpage *
  page172_i9
#ISCELL
  mstr_symbols cad_note *
  *
#ISCELL
  mstr_symbols design_note *
  *
#ISCELL
  mstr_symbols intel_corp_bpage *
  *
#ISCELL
  mstr_symbols gnd *
  page173_i103
#ISCELL
  mstr_symbols gnd *
  page173_i162
#CELL
  mstr_conn conn72_g97614002_a *
  page173_i163
#CELL
  dev_discrete cap_a *
  page173_i165
#CELL
  dev_discrete cap_a *
  page173_i166
#ISCELL
  mstr_standard offpage *
  page173_i170
#ISCELL
  mstr_standard offpage *
  page173_i171
#CELL
  dev_discrete cap_a *
  page173_i172
#CELL
  dev_discrete cap_a *
  page173_i173
#CELL
  dev_discrete cap_a *
  page173_i174
#ISCELL
  mstr_standard tap *
  page173_i175
#ISCELL
  mstr_standard tap *
  page173_i176
#ISCELL
  mstr_standard tap *
  page173_i177
#CELL
  dev_discrete cap_a *
  page173_i191
#CELL
  dev_discrete cap_a *
  page173_i192
#CELL
  dev_discrete cap_a *
  page173_i194
#CELL
  dev_discrete cap_a *
  page173_i195
#CELL
  dev_discrete cap_a *
  page173_i196
#CELL
  dev_discrete cap_a *
  page173_i197
#ISCELL
  mstr_standard tap *
  page173_i198
#ISCELL
  mstr_standard tap *
  page173_i199
#ISCELL
  mstr_standard tap *
  page173_i200
#ISCELL
  mstr_standard tap *
  page173_i201
#ISCELL
  mstr_standard tap *
  page173_i202
#ISCELL
  mstr_standard tap *
  page173_i203
#ISCELL
  mstr_standard tap *
  page173_i204
#CELL
  dev_discrete cap_a *
  page173_i205
#CELL
  dev_discrete cap_a *
  page173_i206
#CELL
  dev_discrete cap_a *
  page173_i207
#CELL
  dev_discrete cap_a *
  page173_i208
#CELL
  dev_discrete cap_a *
  page173_i209
#ISCELL
  mstr_standard tap *
  page173_i210
#ISCELL
  mstr_standard tap *
  page173_i211
#ISCELL
  mstr_standard tap *
  page173_i212
#ISCELL
  mstr_standard tap *
  page173_i213
#ISCELL
  mstr_standard tap *
  page173_i214
#ISCELL
  mstr_standard tap *
  page173_i215
#ISCELL
  mstr_standard tap *
  page173_i216
#ISCELL
  mstr_standard tap *
  page173_i217
#ISCELL
  mstr_standard tap *
  page173_i218
#ISCELL
  mstr_standard tap *
  page173_i219
#CELL
  dev_discrete cap_a *
  page173_i220
#CELL
  dev_discrete cap_a *
  page173_i221
#CELL
  dev_discrete cap_a *
  page173_i222
#ISCELL
  mstr_standard offpage *
  page173_i223
#ISCELL
  mstr_standard offpage *
  page173_i224
#CELL
  dev_discrete cap_a *
  page173_i228
#ISCELL
  mstr_standard tap *
  page173_i229
#ISCELL
  mstr_standard tap *
  page173_i230
#ISCELL
  mstr_standard tap *
  page173_i231
#ISCELL
  mstr_standard tap *
  page173_i232
#CELL
  dev_discrete cap_a *
  page173_i233
#CELL
  dev_discrete cap_a *
  page173_i234
#ISCELL
  mstr_standard tap *
  page173_i235
#ISCELL
  mstr_standard tap *
  page173_i236
#ISCELL
  mstr_standard tap *
  page173_i237
#CELL
  dev_discrete cap_a *
  page173_i238
#CELL
  dev_discrete cap_a *
  page173_i239
#CELL
  dev_discrete cap_a *
  page173_i240
#CELL
  dev_discrete cap_a *
  page173_i241
#CELL
  dev_discrete cap_a *
  page173_i242
#ISCELL
  mstr_standard tap *
  page173_i251
#ISCELL
  mstr_standard tap *
  page173_i252
#ISCELL
  mstr_standard tap *
  page173_i253
#ISCELL
  mstr_standard tap *
  page173_i254
#CELL
  dev_discrete cap_a *
  page173_i255
#CELL
  dev_discrete cap_a *
  page173_i256
#CELL
  dev_discrete cap_a *
  page173_i257
#CELL
  dev_discrete cap_a *
  page173_i258
#CELL
  dev_discrete cap_a *
  page173_i259
#ISCELL
  mstr_symbols p3v3 *
  page173_i260
#CELL
  mstr_discrete res *
  page173_i261
#ISCELL
  mstr_symbols p3v3 *
  page173_i262
#CELL
  mstr_discrete res *
  page173_i263
#CELL
  mstr_discrete res *
  page173_i264
#ISCELL
  mstr_symbols gnd *
  page173_i265
#CELL
  mstr_discrete res *
  page173_i266
#ISCELL
  mstr_symbols gnd *
  page173_i267
#ISCELL
  mstr_standard offpage *
  page173_i268
#ISCELL
  mstr_standard offpage *
  page173_i269
#ISCELL
  mstr_standard offpage *
  page173_i270
#ISCELL
  mstr_standard tap *
  page173_i271
#ISCELL
  mstr_symbols intel_corp_bpage *
  *
#ISCELL
  mstr_symbols cad_note *
  *
#ISCELL
  mstr_symbols intel_corp_bpage *
  *
#ISCELL
  mstr_standard offpage *
  page175_i100
#CELL
  dev_discrete cap_a *
  page175_i11
#ISCELL
  mstr_symbols gnd *
  page175_i12
#CELL
  mstr_discrete res *
  page175_i13
#ISCELL
  mstr_standard offpage *
  page175_i14
#CELL
  dev_discrete cap_a *
  page175_i19
#ISCELL
  mstr_symbols gnd *
  page175_i20
#ISCELL
  mstr_symbols p3v3_stby *
  page175_i21
#CELL
  mstr_discrete res *
  page175_i22
#ISCELL
  mstr_symbols gnd *
  page175_i27
#ISCELL
  mstr_standard offpage *
  page175_i28
#ISCELL
  mstr_symbols gnd *
  page175_i3
#CELL
  dev_discrete cap_a *
  page175_i37
#CELL
  dev_discrete cap_a *
  page175_i38
#CELL
  mstr_discrete res *
  page175_i4
#CELL
  dev_discrete cap_a *
  page175_i40
#ISCELL
  mstr_symbols gnd *
  page175_i41
#ISCELL
  mstr_symbols gnd *
  page175_i42
#ISCELL
  mstr_symbols p3v3_stby *
  page175_i43
#ISCELL
  mstr_symbols p3v3_stby *
  page175_i44
#CELL
  mstr_discrete res *
  page175_i45
#CELL
  mstr_discrete fet_n *
  page175_i49
#CELL
  mstr_discrete res *
  page175_i5
#CELL
  mstr_discrete led *
  page175_i50
#ISCELL
  mstr_standard offpage *
  page175_i52
#ISCELL
  mstr_symbols gnd *
  page175_i54
#CELL
  mstr_ttl ttl1g86 *
  page175_i57
#CELL
  mstr_discrete res *
  page175_i58
#ISCELL
  mstr_symbols p5v_stby *
  page175_i59
#ISCELL
  mstr_symbols p3v3_stby *
  page175_i6
#ISCELL
  mstr_standard offpage *
  page175_i61
#ISCELL
  mstr_standard offpage *
  page175_i62
#CELL
  mstr_discrete res *
  page175_i63
#CELL
  dev_discrete cap_a *
  page175_i64
#ISCELL
  mstr_symbols gnd *
  page175_i66
#CELL
  mstr_discrete led *
  page175_i67
#ISCELL
  mstr_symbols p3v3_stby *
  page175_i70
#ISCELL
  mstr_symbols gnd *
  page175_i71
#CELL
  mstr_misc switch_d37771002 *
  page175_i78
#ISCELL
  mstr_symbols p3v3_stby *
  page175_i85
#ISCELL
  mstr_symbols p5v_stby *
  page175_i86
#ISCELL
  mstr_standard offpage *
  page175_i87
#CELL
  mstr_misc switch_d37771002 *
  page175_i92
#CELL
  w_hdl tc7pz14fu-gp *
  page175_i93
#ISCELL
  mstr_standard offpage *
  page175_i94
#CELL
  mstr_discrete res *
  page175_i95
#ISCELL
  mstr_symbols gnd *
  page175_i96
#CELL
  w_hdl tc7pz14fu-gp *
  page175_i97
#ISCELL
  mstr_symbols gnd *
  page175_i98
#CELL
  mstr_discrete res *
  page175_i99
#ISCELL
  mstr_misc dns *
  *
#ISCELL
  mstr_symbols cad_note *
  *
#ISCELL
  mstr_symbols design_note *
  *
#ISCELL
  mstr_symbols intel_corp_bpage *
  *
#CELL
  mstr_vreg tps2061 *
  page176_i100
#ISCELL
  mstr_symbols p5v *
  page176_i101
#ISCELL
  mstr_symbols gnd *
  page176_i102
#ISCELL
  mstr_standard offpage *
  page176_i103
#ISCELL
  mstr_standard offpage *
  page176_i104
#CELL
  mstr_discrete res *
  page176_i105
#CELL
  dev_discrete cap_a *
  page176_i108
#ISCELL
  mstr_symbols gnd *
  page176_i109
#ISCELL
  mstr_symbols p3v3_stby *
  page176_i110
#CELL
  mstr_discrete res *
  page176_i111
#ISCELL
  mstr_symbols gnd *
  page176_i112
#CELL
  mstr_discrete capp *
  page176_i113
#ISCELL
  mstr_symbols gnd *
  page176_i114
#ISCELL
  mstr_standard offpage *
  page176_i119
#ISCELL
  mstr_standard offpage *
  page176_i123
#ISCELL
  mstr_symbols gnd *
  page176_i125
#ISCELL
  mstr_symbols p3v3_stby *
  page176_i126
#ISCELL
  mstr_standard offpage *
  page176_i127
#ISCELL
  mstr_standard offpage *
  page176_i130
#CELL
  mstr_discrete res *
  page176_i132
#CELL
  mstr_discrete res *
  page176_i133
#ISCELL
  mstr_symbols p5v_stby *
  page176_i134
#ISCELL
  mstr_standard offpage *
  page176_i135
#ISCELL
  mstr_standard offpage *
  page176_i136
#CELL
  mstr_discrete res *
  page176_i137
#CELL
  mstr_discrete res *
  page176_i138
#CELL
  dev_discrete cap_a *
  page176_i139
#ISCELL
  mstr_symbols p3v3_stby *
  page176_i140
#CELL
  mstr_discrete res *
  page176_i142
#CELL
  mstr_discrete res *
  page176_i143
#ISCELL
  mstr_standard offpage *
  page176_i144
#ISCELL
  mstr_standard offpage *
  page176_i145
#CELL
  mstr_ttl ttl1g126_a *
  page176_i146
#CELL
  mstr_discrete res *
  page176_i147
#CELL
  mstr_ttl ttl1g126_a *
  page176_i148
#ISCELL
  mstr_standard offpage *
  page176_i149
#ISCELL
  mstr_symbols gnd *
  page176_i151
#ISCELL
  mstr_standard offpage *
  page176_i155
#CELL
  mstr_discrete res *
  page176_i156
#CELL
  mstr_ttl ttl1g126_a *
  page176_i157
#CELL
  mstr_discrete res *
  page176_i158
#ISCELL
  mstr_symbols p3v3_stby *
  page176_i159
#CELL
  mstr_discrete res *
  page176_i16
#CELL
  mstr_discrete res *
  page176_i160
#CELL
  mstr_discrete res *
  page176_i161
#CELL
  mstr_digital pca9617 *
  page176_i162
#CELL
  dev_discrete cap_a *
  page176_i163
#ISCELL
  mstr_symbols gnd *
  page176_i164
#CELL
  dev_discrete cap_a *
  page176_i166
#ISCELL
  mstr_symbols gnd *
  page176_i167
#ISCELL
  mstr_symbols p3v3_stby *
  page176_i168
#ISCELL
  mstr_symbols p3v3_stby *
  page176_i169
#ISCELL
  mstr_symbols p3v3_stby *
  page176_i170
#ISCELL
  mstr_symbols p3v3_stby *
  page176_i171
#CELL
  mstr_discrete res *
  page176_i172
#CELL
  mstr_discrete res *
  page176_i173
#ISCELL
  mstr_symbols p3v3_stby *
  page176_i174
#CELL
  mstr_discrete res *
  page176_i175
#CELL
  mstr_discrete res *
  page176_i176
#CELL
  mstr_discrete res *
  page176_i178
#ISCELL
  mstr_symbols p3v3_stby *
  page176_i179
#CELL
  mstr_discrete choke_4pin *
  page176_i181
#CELL
  mstr_analog nc7sb3157 *
  page176_i182
#ISCELL
  mstr_symbols gnd *
  page176_i183
#CELL
  mstr_discrete res *
  page176_i31
#ISCELL
  mstr_standard offpage *
  page176_i46
#ISCELL
  mstr_standard offpage *
  page176_i47
#CELL
  mstr_conn conn9_h51826001 *
  page176_i69
#ISCELL
  mstr_symbols gnd *
  page176_i70
#ISCELL
  mstr_symbols gnd *
  page176_i71
#ISCELL
  mstr_standard offpage *
  page176_i75
#CELL
  mstr_discrete diodeac_dual_array *
  page176_i98
#ISCELL
  mstr_symbols gnd *
  page176_i99
#ISCELL
  mstr_symbols cad_note *
  *
#ISCELL
  mstr_symbols intel_corp_bpage *
  *
#ISCELL
  mstr_standard offpage *
  page177_i1
#ISCELL
  mstr_symbols p3v3 *
  page177_i10
#CELL
  dev_discrete cap_a *
  page177_i20
#CELL
  mstr_discrete res *
  page177_i3
#ISCELL
  mstr_symbols gnd *
  page177_i30
#CELL
  mstr_discrete led *
  page177_i31
#CELL
  mstr_discrete res *
  page177_i33
#ISCELL
  mstr_symbols p5v_stby *
  page177_i36
#ISCELL
  mstr_standard offpage *
  page177_i4
#CELL
  mstr_discrete led *
  page177_i42
#CELL
  mstr_discrete res *
  page177_i43
#ISCELL
  mstr_symbols p3v3 *
  page177_i45
#ISCELL
  mstr_symbols gnd *
  page177_i46
#CELL
  mstr_discrete res *
  page177_i6
#CELL
  mstr_ttl ttl1g08 *
  page177_i70
#CELL
  mstr_discrete led *
  page177_i71
#CELL
  mstr_discrete res *
  page177_i72
#ISCELL
  mstr_symbols gnd *
  page177_i74
#CELL
  mstr_discrete res *
  page177_i76
#ISCELL
  mstr_symbols p3v3_stby *
  page177_i77
#ISCELL
  mstr_symbols p3v3_stby *
  page177_i78
#CELL
  mstr_discrete fet_n_dual *
  page177_i79
#CELL
  mstr_discrete res *
  page177_i8
#CELL
  mstr_discrete fet_n_dual *
  page177_i80
#ISCELL
  mstr_symbols p3v3_stby *
  page177_i81
#CELL
  mstr_discrete res *
  page177_i82
#ISCELL
  mstr_symbols gnd *
  page177_i83
#ISCELL
  mstr_standard offpage *
  page177_i84
#ISCELL
  mstr_symbols p3v3 *
  page177_i85
#CELL
  mstr_discrete res *
  page177_i9
#ISCELL
  mstr_symbols design_note *
  *
#ISCELL
  mstr_symbols intel_corp_bpage *
  *
#CELL
  mstr_discrete res *
  page178_i1
#ISCELL
  mstr_standard offpage *
  page178_i10
#CELL
  mstr_discrete res *
  page178_i11
#CELL
  mstr_discrete res *
  page178_i12
#CELL
  mstr_discrete res *
  page178_i13
#CELL
  mstr_discrete res *
  page178_i17
#CELL
  mstr_discrete res *
  page178_i18
#ISCELL
  mstr_symbols p3v3_stby *
  page178_i19
#CELL
  mstr_discrete res *
  page178_i2
#CELL
  mstr_discrete res *
  page178_i20
#CELL
  mstr_discrete res *
  page178_i21
#CELL
  mstr_discrete res *
  page178_i22
#CELL
  mstr_discrete res *
  page178_i23
#ISCELL
  mstr_standard offpage *
  page178_i24
#ISCELL
  mstr_standard offpage *
  page178_i25
#ISCELL
  mstr_standard offpage *
  page178_i26
#ISCELL
  mstr_standard offpage *
  page178_i3
#ISCELL
  mstr_standard offpage *
  page178_i4
#ISCELL
  mstr_symbols p3v3_stby *
  page178_i5
#ISCELL
  mstr_standard offpage *
  page178_i6
#ISCELL
  mstr_standard offpage *
  page178_i7
#CELL
  mstr_discrete res *
  page178_i8
#ISCELL
  mstr_standard offpage *
  page178_i9
#ISCELL
  mstr_symbols intel_corp_bpage *
  *
#ISCELL
  mstr_symbols intel_corp_bpage *
  *
#ISCELL
  mstr_misc dns *
  *
#ISCELL
  mstr_symbols cad_note *
  *
#ISCELL
  mstr_symbols design_note *
  *
#ISCELL
  mstr_symbols intel_corp_bpage *
  *
#ISCELL
  mstr_standard offpage *
  page181_i1
#ISCELL
  mstr_standard offpage *
  page181_i10
#ISCELL
  mstr_standard offpage *
  page181_i100
#ISCELL
  mstr_standard offpage *
  page181_i101
#ISCELL
  mstr_standard offpage *
  page181_i102
#ISCELL
  mstr_standard offpage *
  page181_i103
#ISCELL
  mstr_symbols gnd *
  page181_i104
#ISCELL
  mstr_symbols p3v3_stby *
  page181_i105
#CELL
  mstr_conn conn8_h62179001 *
  page181_i106
#ISCELL
  mstr_standard tap *
  page181_i107
#ISCELL
  mstr_standard tap *
  page181_i108
#ISCELL
  mstr_standard offpage *
  page181_i109
#ISCELL
  mstr_standard offpage *
  page181_i11
#ISCELL
  mstr_standard offpage *
  page181_i110
#ISCELL
  mstr_standard offpage *
  page181_i111
#ISCELL
  mstr_standard tap *
  page181_i112
#ISCELL
  mstr_standard tap *
  page181_i113
#ISCELL
  mstr_standard tap *
  page181_i114
#ISCELL
  mstr_standard tap *
  page181_i115
#ISCELL
  mstr_standard tap *
  page181_i116
#ISCELL
  mstr_standard tap *
  page181_i117
#ISCELL
  mstr_standard offpage *
  page181_i118
#ISCELL
  mstr_standard offpage *
  page181_i119
#ISCELL
  mstr_standard offpage *
  page181_i12
#ISCELL
  mstr_standard offpage *
  page181_i120
#ISCELL
  mstr_standard offpage *
  page181_i121
#ISCELL
  mstr_standard offpage *
  page181_i122
#ISCELL
  mstr_standard offpage *
  page181_i123
#ISCELL
  mstr_standard offpage *
  page181_i124
#ISCELL
  mstr_standard offpage *
  page181_i125
#ISCELL
  mstr_standard offpage *
  page181_i126
#ISCELL
  mstr_standard offpage *
  page181_i127
#ISCELL
  mstr_standard offpage *
  page181_i128
#ISCELL
  mstr_standard offpage *
  page181_i129
#ISCELL
  mstr_standard offpage *
  page181_i13
#ISCELL
  mstr_standard offpage *
  page181_i130
#ISCELL
  mstr_standard offpage *
  page181_i131
#ISCELL
  mstr_standard tap *
  page181_i132
#CELL
  w_hdl dm-fci-conn76-8r-gp-u-01 *
  page181_i134
#ISCELL
  mstr_symbols gnd *
  page181_i136
#CELL
  mstr_discrete res *
  page181_i137
#ISCELL
  mstr_standard offpage *
  page181_i14
#ISCELL
  mstr_standard offpage *
  page181_i15
#ISCELL
  mstr_standard offpage *
  page181_i16
#ISCELL
  mstr_standard offpage *
  page181_i17
#ISCELL
  mstr_standard offpage *
  page181_i18
#ISCELL
  mstr_standard offpage *
  page181_i19
#ISCELL
  mstr_standard offpage *
  page181_i20
#ISCELL
  mstr_symbols p12v_psu *
  page181_i21
#CELL
  mstr_discrete res *
  page181_i22
#ISCELL
  mstr_standard offpage *
  page181_i23
#ISCELL
  mstr_standard offpage *
  page181_i24
#ISCELL
  mstr_standard offpage *
  page181_i25
#CELL
  mstr_discrete res *
  page181_i26
#CELL
  mstr_discrete res *
  page181_i27
#CELL
  mstr_discrete res *
  page181_i28
#CELL
  mstr_discrete res *
  page181_i29
#CELL
  mstr_discrete res *
  page181_i30
#CELL
  mstr_discrete res *
  page181_i31
#CELL
  mstr_discrete res *
  page181_i32
#CELL
  mstr_discrete res *
  page181_i33
#CELL
  dev_discrete cap_a *
  page181_i34
#ISCELL
  mstr_symbols gnd *
  page181_i35
#ISCELL
  mstr_symbols p3v3_stby *
  page181_i36
#CELL
  mstr_discrete diode *
  page181_i37
#ISCELL
  mstr_standard offpage *
  page181_i38
#ISCELL
  mstr_symbols gnd *
  page181_i39
#CELL
  mstr_discrete res *
  page181_i4
#CELL
  mstr_discrete cap *
  page181_i40
#ISCELL
  mstr_standard offpage *
  page181_i41
#CELL
  mstr_discrete npn *
  page181_i42
#ISCELL
  mstr_symbols gnd *
  page181_i43
#ISCELL
  mstr_standard tap *
  page181_i44
#ISCELL
  mstr_standard tap *
  page181_i45
#ISCELL
  mstr_standard tap *
  page181_i46
#ISCELL
  mstr_standard tap *
  page181_i47
#ISCELL
  mstr_standard tap *
  page181_i48
#ISCELL
  mstr_standard tap *
  page181_i49
#CELL
  mstr_discrete diode *
  page181_i5
#ISCELL
  mstr_standard tap *
  page181_i50
#ISCELL
  mstr_standard offpage *
  page181_i51
#ISCELL
  mstr_standard tap *
  page181_i52
#ISCELL
  mstr_standard tap *
  page181_i53
#ISCELL
  mstr_standard tap *
  page181_i54
#ISCELL
  mstr_standard tap *
  page181_i55
#ISCELL
  mstr_standard tap *
  page181_i56
#ISCELL
  mstr_standard tap *
  page181_i57
#ISCELL
  mstr_standard tap *
  page181_i58
#ISCELL
  mstr_standard tap *
  page181_i59
#ISCELL
  mstr_standard offpage *
  page181_i6
#CELL
  mstr_ttl ttl08 *
  page181_i60
#ISCELL
  mstr_symbols gnd *
  page181_i61
#ISCELL
  mstr_symbols gnd *
  page181_i62
#CELL
  mstr_discrete res *
  page181_i63
#CELL
  mstr_discrete res *
  page181_i64
#ISCELL
  mstr_standard offpage *
  page181_i65
#ISCELL
  mstr_standard offpage *
  page181_i66
#ISCELL
  mstr_symbols gnd *
  page181_i67
#CELL
  mstr_discrete res *
  page181_i68
#ISCELL
  mstr_symbols p12v_psu *
  page181_i69
#ISCELL
  mstr_standard offpage *
  page181_i7
#CELL
  mstr_discrete cap *
  page181_i70
#CELL
  mstr_discrete cap *
  page181_i71
#CELL
  mstr_discrete cap *
  page181_i72
#CELL
  mstr_discrete cap *
  page181_i73
#CELL
  mstr_discrete cap *
  page181_i74
#CELL
  mstr_discrete cap *
  page181_i75
#CELL
  mstr_discrete cap *
  page181_i76
#CELL
  mstr_discrete cap *
  page181_i77
#CELL
  mstr_discrete cap *
  page181_i78
#CELL
  mstr_discrete cap *
  page181_i79
#ISCELL
  mstr_standard offpage *
  page181_i8
#CELL
  mstr_discrete res *
  page181_i80
#CELL
  mstr_discrete res *
  page181_i81
#CELL
  mstr_discrete res *
  page181_i82
#ISCELL
  mstr_symbols p3v3_stby *
  page181_i83
#ISCELL
  mstr_standard tap *
  page181_i84
#ISCELL
  mstr_standard tap *
  page181_i85
#CELL
  mstr_discrete cap *
  page181_i86
#CELL
  mstr_discrete cap *
  page181_i87
#CELL
  mstr_discrete cap *
  page181_i88
#CELL
  mstr_discrete cap *
  page181_i89
#ISCELL
  mstr_standard offpage *
  page181_i9
#CELL
  mstr_discrete cap *
  page181_i90
#CELL
  mstr_discrete cap *
  page181_i91
#ISCELL
  mstr_standard tap *
  page181_i92
#ISCELL
  mstr_standard tap *
  page181_i93
#ISCELL
  mstr_standard tap *
  page181_i94
#ISCELL
  mstr_standard tap *
  page181_i95
#ISCELL
  mstr_standard tap *
  page181_i96
#ISCELL
  mstr_standard tap *
  page181_i97
#ISCELL
  mstr_standard offpage *
  page181_i98
#ISCELL
  mstr_standard offpage *
  page181_i99
#ISCELL
  mstr_misc dns *
  *
#ISCELL
  mstr_symbols design_note *
  *
#ISCELL
  mstr_symbols intel_corp_bpage *
  *
#ISCELL
  mstr_standard offpage *
  page182_i1
#CELL
  mstr_discrete res *
  page182_i10
#ISCELL
  mstr_standard offpage *
  page182_i11
#ISCELL
  mstr_standard offpage *
  page182_i12
#ISCELL
  mstr_standard offpage *
  page182_i13
#ISCELL
  mstr_standard offpage *
  page182_i14
#ISCELL
  mstr_standard offpage *
  page182_i15
#ISCELL
  mstr_standard offpage *
  page182_i16
#ISCELL
  mstr_standard offpage *
  page182_i17
#ISCELL
  mstr_standard offpage *
  page182_i18
#ISCELL
  mstr_symbols gnd *
  page182_i19
#ISCELL
  mstr_standard offpage *
  page182_i2
#ISCELL
  mstr_standard tap *
  page182_i20
#ISCELL
  mstr_standard tap *
  page182_i21
#ISCELL
  mstr_standard tap *
  page182_i22
#ISCELL
  mstr_standard tap *
  page182_i23
#ISCELL
  mstr_standard tap *
  page182_i24
#ISCELL
  mstr_standard tap *
  page182_i25
#ISCELL
  mstr_standard tap *
  page182_i26
#ISCELL
  mstr_standard tap *
  page182_i27
#ISCELL
  mstr_standard tap *
  page182_i28
#ISCELL
  mstr_standard tap *
  page182_i29
#ISCELL
  mstr_standard offpage *
  page182_i3
#ISCELL
  mstr_standard tap *
  page182_i30
#ISCELL
  mstr_standard tap *
  page182_i31
#ISCELL
  mstr_standard tap *
  page182_i32
#ISCELL
  mstr_standard tap *
  page182_i33
#ISCELL
  mstr_standard tap *
  page182_i34
#ISCELL
  mstr_symbols gnd *
  page182_i35
#CELL
  mstr_discrete cap *
  page182_i36
#CELL
  mstr_discrete cap *
  page182_i37
#CELL
  mstr_discrete cap *
  page182_i38
#CELL
  mstr_discrete cap *
  page182_i39
#ISCELL
  mstr_standard offpage *
  page182_i4
#CELL
  mstr_discrete cap *
  page182_i40
#CELL
  mstr_discrete cap *
  page182_i41
#CELL
  mstr_discrete cap *
  page182_i42
#CELL
  mstr_discrete cap *
  page182_i43
#CELL
  mstr_discrete cap *
  page182_i44
#CELL
  mstr_discrete cap *
  page182_i45
#CELL
  mstr_discrete cap *
  page182_i46
#CELL
  mstr_discrete cap *
  page182_i47
#CELL
  mstr_discrete cap *
  page182_i48
#CELL
  mstr_discrete cap *
  page182_i49
#ISCELL
  mstr_standard offpage *
  page182_i5
#ISCELL
  mstr_standard offpage *
  page182_i50
#ISCELL
  mstr_standard offpage *
  page182_i51
#CELL
  mstr_discrete cap *
  page182_i52
#CELL
  mstr_discrete cap *
  page182_i53
#ISCELL
  mstr_standard offpage *
  page182_i54
#ISCELL
  mstr_standard offpage *
  page182_i55
#ISCELL
  mstr_standard offpage *
  page182_i56
#ISCELL
  mstr_standard offpage *
  page182_i57
#ISCELL
  mstr_standard offpage *
  page182_i58
#ISCELL
  mstr_standard tap *
  page182_i59
#CELL
  mstr_discrete res *
  page182_i6
#ISCELL
  mstr_standard tap *
  page182_i60
#ISCELL
  mstr_standard tap *
  page182_i61
#ISCELL
  mstr_standard tap *
  page182_i62
#ISCELL
  mstr_standard tap *
  page182_i63
#ISCELL
  mstr_standard tap *
  page182_i64
#ISCELL
  mstr_standard tap *
  page182_i65
#ISCELL
  mstr_standard tap *
  page182_i66
#ISCELL
  mstr_standard tap *
  page182_i67
#ISCELL
  mstr_standard tap *
  page182_i68
#ISCELL
  mstr_standard tap *
  page182_i69
#CELL
  mstr_discrete res *
  page182_i7
#ISCELL
  mstr_standard tap *
  page182_i70
#ISCELL
  mstr_standard tap *
  page182_i71
#ISCELL
  mstr_standard tap *
  page182_i72
#ISCELL
  mstr_standard tap *
  page182_i73
#ISCELL
  mstr_standard tap *
  page182_i74
#ISCELL
  mstr_standard offpage *
  page182_i75
#ISCELL
  mstr_standard offpage *
  page182_i76
#ISCELL
  mstr_standard tap *
  page182_i77
#CELL
  w_hdl dm-fci-conn76-8r-gp-u-01 *
  page182_i79
#CELL
  mstr_discrete res *
  page182_i8
#CELL
  mstr_discrete res *
  page182_i9
#ISCELL
  mstr_symbols intel_corp_bpage *
  *
#ISCELL
  mstr_standard offpage *
  page183_i1
#ISCELL
  mstr_symbols p3v3_stby *
  page183_i2
#CELL
  mstr_discrete res *
  page183_i3
#ISCELL
  mstr_symbols cad_note *
  *
#ISCELL
  mstr_symbols intel_corp_bpage *
  *
#ISCELL
  mstr_standard offpage *
  page184_i100
#ISCELL
  mstr_symbols gnd *
  page184_i101
#ISCELL
  mstr_standard offpage *
  page184_i102
#ISCELL
  mstr_standard offpage *
  page184_i103
#CELL
  mstr_misc standoff *
  page184_i104
#ISCELL
  mstr_symbols gnd *
  page184_i105
#CELL
  mstr_sconn sconn11_h67026001 *
  page184_i87
#CELL
  mstr_discrete res *
  page184_i88
#ISCELL
  mstr_standard offpage *
  page184_i89
#ISCELL
  mstr_standard offpage *
  page184_i90
#ISCELL
  mstr_standard offpage *
  page184_i91
#CELL
  mstr_discrete res *
  page184_i92
#CELL
  mstr_discrete res *
  page184_i93
#ISCELL
  mstr_standard offpage *
  page184_i94
#CELL
  mstr_discrete res *
  page184_i95
#ISCELL
  mstr_standard offpage *
  page184_i96
#ISCELL
  mstr_symbols p3v3_stby *
  page184_i97
#ISCELL
  mstr_standard offpage *
  page184_i98
#CELL
  mstr_discrete res *
  page184_i99
#ISCELL
  mstr_symbols cad_note *
  *
#ISCELL
  mstr_symbols design_note *
  *
#ISCELL
  mstr_symbols intel_corp_bpage *
  *
#ISCELL
  mstr_standard offpage *
  page185_i100
#ISCELL
  mstr_standard offpage *
  page185_i101
#ISCELL
  mstr_standard offpage *
  page185_i102
#ISCELL
  mstr_standard offpage *
  page185_i103
#ISCELL
  mstr_standard offpage *
  page185_i104
#CELL
  mstr_discrete res *
  page185_i105
#CELL
  mstr_discrete res *
  page185_i106
#ISCELL
  mstr_standard offpage *
  page185_i107
#ISCELL
  mstr_standard offpage *
  page185_i108
#ISCELL
  mstr_standard offpage *
  page185_i109
#CELL
  mstr_ttl ttl1g07_a *
  page185_i110
#CELL
  mstr_discrete res *
  page185_i111
#ISCELL
  mstr_symbols p3v3 *
  page185_i112
#CELL
  mstr_discrete res *
  page185_i113
#ISCELL
  mstr_symbols p3v3_stby *
  page185_i114
#CELL
  mstr_discrete res *
  page185_i115
#ISCELL
  mstr_standard offpage *
  page185_i116
#CELL
  dev_discrete cap_a *
  page185_i117
#ISCELL
  mstr_symbols p3v3_stby *
  page185_i118
#ISCELL
  mstr_symbols gnd *
  page185_i119
#CELL
  dev_discrete cap_a *
  page185_i120
#ISCELL
  mstr_symbols gnd *
  page185_i122
#CELL
  dev_discrete cap_a *
  page185_i123
#CELL
  dev_discrete cap_a *
  page185_i124
#ISCELL
  mstr_symbols p3v3 *
  page185_i125
#CELL
  dev_discrete cap_a *
  page185_i126
#CELL
  dev_discrete cap_a *
  page185_i127
#ISCELL
  mstr_symbols p3v3 *
  page185_i128
#CELL
  dev_discrete cap_a *
  page185_i129
#ISCELL
  mstr_symbols gnd *
  page185_i130
#CELL
  dev_discrete cap_a *
  page185_i131
#CELL
  dev_discrete cap_a *
  page185_i132
#ISCELL
  mstr_symbols p3v3 *
  page185_i133
#ISCELL
  mstr_symbols gnd *
  page185_i134
#CELL
  dev_discrete cap_a *
  page185_i135
#CELL
  mstr_discrete res *
  page185_i136
#ISCELL
  mstr_symbols p3v3 *
  page185_i137
#CELL
  dev_discrete cap_a *
  page185_i138
#CELL
  dev_discrete cap_a *
  page185_i139
#CELL
  mstr_discrete cap *
  page185_i140
#CELL
  dev_discrete cap_a *
  page185_i141
#CELL
  dev_discrete cap_a *
  page185_i142
#CELL
  w_hdl skt-mini67p-41-gp *
  page185_i143
#ISCELL
  mstr_symbols gnd *
  page185_i144
#ISCELL
  mstr_symbols gnd *
  page185_i145
#ISCELL
  mstr_symbols gnd *
  page185_i146
#ISCELL
  mstr_symbols gnd *
  page185_i147
#ISCELL
  mstr_symbols gnd *
  page185_i148
#ISCELL
  mstr_symbols gnd *
  page185_i149
#ISCELL
  mstr_symbols gnd *
  page185_i150
#ISCELL
  mstr_symbols gnd *
  page185_i151
#ISCELL
  mstr_symbols gnd *
  page185_i152
#ISCELL
  mstr_symbols gnd *
  page185_i153
#ISCELL
  mstr_symbols gnd *
  page185_i154
#ISCELL
  mstr_symbols p3v3 *
  page185_i155
#ISCELL
  mstr_symbols p3v3 *
  page185_i156
#ISCELL
  mstr_standard offpage *
  page185_i157
#ISCELL
  mstr_standard offpage *
  page185_i158
#ISCELL
  mstr_standard offpage *
  page185_i159
#ISCELL
  mstr_standard offpage *
  page185_i160
#ISCELL
  mstr_standard offpage *
  page185_i161
#ISCELL
  mstr_standard offpage *
  page185_i162
#ISCELL
  mstr_standard offpage *
  page185_i163
#ISCELL
  mstr_standard offpage *
  page185_i164
#ISCELL
  mstr_standard offpage *
  page185_i165
#ISCELL
  mstr_standard offpage *
  page185_i166
#CELL
  mstr_discrete cap *
  page185_i167
#CELL
  mstr_discrete cap *
  page185_i168
#ISCELL
  mstr_standard offpage *
  page185_i169
#ISCELL
  mstr_standard offpage *
  page185_i170
#CELL
  mstr_discrete cap *
  page185_i171
#CELL
  mstr_discrete cap *
  page185_i172
#ISCELL
  mstr_standard offpage *
  page185_i173
#ISCELL
  mstr_standard offpage *
  page185_i174
#ISCELL
  mstr_standard offpage *
  page185_i175
#ISCELL
  mstr_standard offpage *
  page185_i176
#ISCELL
  mstr_standard offpage *
  page185_i177
#ISCELL
  mstr_standard offpage *
  page185_i178
#CELL
  mstr_discrete cap *
  page185_i179
#CELL
  mstr_discrete cap *
  page185_i180
#ISCELL
  mstr_standard offpage *
  page185_i181
#ISCELL
  mstr_standard offpage *
  page185_i182
#CELL
  mstr_discrete res *
  page185_i183
#CELL
  mstr_discrete res *
  page185_i184
#ISCELL
  mstr_symbols gnd *
  page185_i185
#ISCELL
  mstr_symbols gnd *
  page185_i186
#CELL
  mstr_discrete res *
  page185_i187
#CELL
  dev_discrete cap_a *
  page185_i188
#ISCELL
  mstr_symbols gnd *
  page185_i189
#CELL
  dev_discrete cap_a *
  page185_i190
#CELL
  w_hdl tca9517dgkr-gp *
  page185_i191
#ISCELL
  mstr_symbols gnd *
  page185_i192
#CELL
  dev_discrete cap_a *
  page185_i193
#ISCELL
  mstr_symbols p3v3_stby *
  page185_i194
#ISCELL
  mstr_symbols gnd *
  page185_i195
#CELL
  dev_discrete cap_a *
  page185_i196
#ISCELL
  mstr_standard offpage *
  page185_i197
#ISCELL
  mstr_standard offpage *
  page185_i198
#ISCELL
  mstr_symbols gnd *
  page185_i199
#CELL
  mstr_discrete res *
  page185_i200
#ISCELL
  mstr_standard offpage *
  page185_i201
#ISCELL
  mstr_symbols p3v3_stby *
  page185_i202
#ISCELL
  mstr_symbols gnd *
  page185_i203
#CELL
  w_hdl tca9517dgkr-gp *
  page185_i204
#ISCELL
  mstr_symbols gnd *
  page185_i205
#CELL
  mstr_discrete res *
  page185_i206
#CELL
  mstr_discrete res *
  page185_i207
#CELL
  mstr_discrete res *
  page185_i208
#ISCELL
  mstr_symbols p3v3 *
  page185_i209
#ISCELL
  mstr_symbols gnd *
  page185_i210
#CELL
  mstr_discrete res *
  page185_i211
#ISCELL
  mstr_symbols gnd *
  page185_i212
#CELL
  w_hdl lmv431aimfx-gp *
  page185_i213
#CELL
  mstr_discrete res *
  page185_i214
#CELL
  mstr_discrete res *
  page185_i215
#CELL
  mstr_discrete res *
  page185_i216
#CELL
  mstr_discrete cap *
  page185_i217
#ISCELL
  mstr_symbols gnd *
  page185_i218
#ISCELL
  mstr_standard offpage *
  page185_i91
#ISCELL
  mstr_standard offpage *
  page185_i92
#ISCELL
  mstr_standard offpage *
  page185_i93
#ISCELL
  mstr_standard offpage *
  page185_i94
#CELL
  mstr_discrete cap *
  page185_i96
#ISCELL
  mstr_symbols cad_note *
  *
#ISCELL
  mstr_symbols design_note *
  *
#ISCELL
  mstr_symbols intel_corp_bpage *
  *
#CELL
  dev_discrete cap_a *
  page186_i10
#ISCELL
  mstr_symbols gnd *
  page186_i14
#ISCELL
  mstr_symbols gnd *
  page186_i192
#ISCELL
  mstr_symbols gnd *
  page186_i193
#ISCELL
  mstr_symbols p3v3 *
  page186_i195
#ISCELL
  mstr_standard offpage *
  page186_i217
#CELL
  mstr_discrete res *
  page186_i220
#ISCELL
  mstr_standard offpage *
  page186_i221
#ISCELL
  mstr_symbols gnd *
  page186_i223
#ISCELL
  mstr_standard offpage *
  page186_i227
#ISCELL
  mstr_standard offpage *
  page186_i228
#ISCELL
  mstr_standard offpage *
  page186_i229
#ISCELL
  mstr_standard offpage *
  page186_i233
#ISCELL
  mstr_standard offpage *
  page186_i234
#ISCELL
  mstr_symbols p3v3 *
  page186_i247
#ISCELL
  mstr_standard offpage *
  page186_i249
#ISCELL
  mstr_standard offpage *
  page186_i250
#ISCELL
  mstr_standard offpage *
  page186_i251
#ISCELL
  mstr_standard offpage *
  page186_i252
#ISCELL
  mstr_standard offpage *
  page186_i254
#ISCELL
  mstr_standard offpage *
  page186_i255
#ISCELL
  mstr_standard offpage *
  page186_i256
#ISCELL
  mstr_standard offpage *
  page186_i257
#ISCELL
  mstr_symbols p3v3 *
  page186_i268
#ISCELL
  mstr_symbols gnd *
  page186_i269
#CELL
  dev_discrete cap_a *
  page186_i270
#ISCELL
  mstr_symbols p3v3_stby *
  page186_i274
#ISCELL
  mstr_symbols p3v3_stby *
  page186_i275
#ISCELL
  mstr_symbols p5v_stby *
  page186_i276
#ISCELL
  mstr_symbols p12v_stby *
  page186_i278
#ISCELL
  mstr_symbols p12v_stby *
  page186_i279
#ISCELL
  mstr_symbols p3v3_stby *
  page186_i296
#ISCELL
  mstr_standard tap *
  page186_i297
#ISCELL
  mstr_standard tap *
  page186_i298
#ISCELL
  mstr_standard tap *
  page186_i299
#CELL
  mstr_discrete cap *
  page186_i3
#ISCELL
  mstr_standard tap *
  page186_i300
#ISCELL
  mstr_standard tap *
  page186_i301
#ISCELL
  mstr_standard tap *
  page186_i302
#ISCELL
  mstr_standard tap *
  page186_i303
#ISCELL
  mstr_standard tap *
  page186_i304
#ISCELL
  mstr_standard tap *
  page186_i305
#ISCELL
  mstr_standard tap *
  page186_i306
#ISCELL
  mstr_standard tap *
  page186_i307
#ISCELL
  mstr_standard tap *
  page186_i308
#ISCELL
  mstr_standard tap *
  page186_i309
#ISCELL
  mstr_standard tap *
  page186_i310
#ISCELL
  mstr_standard tap *
  page186_i311
#ISCELL
  mstr_standard tap *
  page186_i312
#ISCELL
  mstr_standard offpage *
  page186_i313
#ISCELL
  mstr_standard offpage *
  page186_i314
#ISCELL
  mstr_standard tap *
  page186_i315
#ISCELL
  mstr_standard tap *
  page186_i316
#ISCELL
  mstr_standard tap *
  page186_i317
#ISCELL
  mstr_standard tap *
  page186_i318
#ISCELL
  mstr_standard offpage *
  page186_i320
#ISCELL
  mstr_standard tap *
  page186_i321
#ISCELL
  mstr_standard tap *
  page186_i322
#ISCELL
  mstr_standard tap *
  page186_i323
#ISCELL
  mstr_standard tap *
  page186_i324
#ISCELL
  mstr_standard tap *
  page186_i325
#ISCELL
  mstr_standard tap *
  page186_i326
#ISCELL
  mstr_standard tap *
  page186_i327
#ISCELL
  mstr_standard tap *
  page186_i328
#ISCELL
  mstr_standard tap *
  page186_i329
#ISCELL
  mstr_standard tap *
  page186_i330
#ISCELL
  mstr_standard tap *
  page186_i331
#ISCELL
  mstr_standard tap *
  page186_i332
#ISCELL
  mstr_standard offpage *
  page186_i333
#CELL
  dev_discrete cap_a *
  page186_i334
#CELL
  dev_discrete cap_a *
  page186_i335
#CELL
  mstr_sconn sconn120_a28699018 *
  page186_i336
#CELL
  mstr_discrete res *
  page186_i337
#CELL
  mstr_discrete res *
  page186_i338
#CELL
  mstr_discrete res *
  page186_i339
#CELL
  mstr_discrete res *
  page186_i340
#ISCELL
  mstr_standard offpage *
  page186_i341
#ISCELL
  mstr_standard offpage *
  page186_i342
#ISCELL
  mstr_standard offpage *
  page186_i343
#ISCELL
  mstr_standard offpage *
  page186_i344
#CELL
  dev_discrete cap_a *
  page186_i345
#ISCELL
  mstr_symbols gnd *
  page186_i346
#ISCELL
  mstr_symbols p5v_stby *
  page186_i348
#ISCELL
  mstr_symbols p3v3_stby *
  page186_i350
#ISCELL
  mstr_standard offpage *
  page186_i354
#CELL
  mstr_discrete res *
  page186_i356
#CELL
  w_hdl sc1u10v2kx-4-gp *
  page186_i357
#CELL
  w_hdl 887r2f-l-gp *
  page186_i358
#CELL
  mstr_discrete cap *
  page186_i6
#CELL
  dev_discrete cap_a *
  page186_i7
#CELL
  dev_discrete cap_a *
  page186_i8
#ISCELL
  mstr_symbols gnd *
  page186_i9
#ISCELL
  mstr_symbols design_note *
  *
#ISCELL
  mstr_symbols intel_corp_bpage *
  *
#ISCELL
  mstr_standard offpage *
  page187_i100
#ISCELL
  mstr_standard tap *
  page187_i111
#ISCELL
  mstr_standard tap *
  page187_i112
#ISCELL
  mstr_standard tap *
  page187_i113
#ISCELL
  mstr_standard tap *
  page187_i114
#ISCELL
  mstr_standard tap *
  page187_i115
#ISCELL
  mstr_standard tap *
  page187_i116
#CELL
  mstr_sconn sconn80_e67482007 *
  page187_i119
#ISCELL
  mstr_standard tap *
  page187_i140
#ISCELL
  mstr_standard tap *
  page187_i141
#ISCELL
  mstr_standard tap *
  page187_i142
#ISCELL
  mstr_standard offpage *
  page187_i143
#ISCELL
  mstr_standard offpage *
  page187_i144
#CELL
  mstr_discrete res *
  page187_i145
#ISCELL
  mstr_standard offpage *
  page187_i146
#ISCELL
  mstr_standard tap *
  page187_i147
#ISCELL
  mstr_standard tap *
  page187_i148
#ISCELL
  mstr_standard tap *
  page187_i149
#CELL
  mstr_discrete res *
  page187_i150
#ISCELL
  mstr_standard offpage *
  page187_i151
#ISCELL
  mstr_standard offpage *
  page187_i152
#CELL
  mstr_discrete res *
  page187_i153
#ISCELL
  mstr_symbols gnd *
  page187_i154
#ISCELL
  mstr_standard tap *
  page187_i155
#ISCELL
  mstr_standard tap *
  page187_i156
#ISCELL
  mstr_standard tap *
  page187_i157
#ISCELL
  mstr_standard tap *
  page187_i158
#ISCELL
  mstr_standard offpage *
  page187_i159
#ISCELL
  mstr_standard offpage *
  page187_i160
#ISCELL
  mstr_symbols gnd *
  page187_i162
#ISCELL
  mstr_standard tap *
  page187_i164
#ISCELL
  mstr_standard tap *
  page187_i165
#ISCELL
  mstr_standard tap *
  page187_i166
#ISCELL
  mstr_standard tap *
  page187_i167
#ISCELL
  mstr_standard offpage *
  page187_i168
#ISCELL
  mstr_symbols gnd *
  page187_i169
#ISCELL
  mstr_symbols p3v3_stby *
  page187_i171
#CELL
  mstr_discrete res *
  page187_i174
#CELL
  w_hdl 887r2f-l-gp *
  page187_i175
#ISCELL
  mstr_standard offpage *
  page187_i44
#ISCELL
  mstr_standard offpage *
  page187_i45
#ISCELL
  mstr_standard tap *
  page187_i46
#ISCELL
  mstr_standard tap *
  page187_i47
#ISCELL
  mstr_standard tap *
  page187_i50
#ISCELL
  mstr_standard tap *
  page187_i51
#ISCELL
  mstr_symbols p12v_stby *
  page187_i70
#ISCELL
  mstr_standard tap *
  page187_i87
#ISCELL
  mstr_standard tap *
  page187_i88
#ISCELL
  mstr_standard tap *
  page187_i89
#ISCELL
  mstr_standard tap *
  page187_i90
#ISCELL
  mstr_standard tap *
  page187_i95
#ISCELL
  mstr_standard tap *
  page187_i96
#ISCELL
  mstr_standard tap *
  page187_i97
#ISCELL
  mstr_standard tap *
  page187_i98
#ISCELL
  mstr_standard offpage *
  page187_i99
#ISCELL
  mstr_symbols cad_note *
  *
#ISCELL
  mstr_symbols intel_corp_bpage *
  *
#ISCELL
  mstr_standard offpage *
  page188_i100
#ISCELL
  mstr_standard offpage *
  page188_i101
#ISCELL
  mstr_standard offpage *
  page188_i102
#ISCELL
  mstr_standard offpage *
  page188_i103
#ISCELL
  mstr_standard offpage *
  page188_i104
#ISCELL
  mstr_standard offpage *
  page188_i105
#ISCELL
  mstr_standard offpage *
  page188_i106
#ISCELL
  mstr_standard offpage *
  page188_i107
#ISCELL
  mstr_standard offpage *
  page188_i108
#ISCELL
  mstr_standard offpage *
  page188_i109
#ISCELL
  mstr_standard offpage *
  page188_i110
#ISCELL
  mstr_standard offpage *
  page188_i111
#ISCELL
  mstr_standard offpage *
  page188_i112
#ISCELL
  mstr_standard offpage *
  page188_i113
#ISCELL
  mstr_standard offpage *
  page188_i114
#ISCELL
  mstr_standard offpage *
  page188_i115
#ISCELL
  mstr_symbols p3v3_stby *
  page188_i116
#ISCELL
  mstr_standard offpage *
  page188_i117
#ISCELL
  mstr_standard offpage *
  page188_i118
#ISCELL
  mstr_standard offpage *
  page188_i119
#CELL
  dev_discrete cap_a *
  page188_i120
#CELL
  dev_discrete cap_a *
  page188_i121
#ISCELL
  mstr_standard offpage *
  page188_i122
#ISCELL
  mstr_standard offpage *
  page188_i123
#ISCELL
  mstr_standard offpage *
  page188_i124
#ISCELL
  mstr_standard offpage *
  page188_i125
#ISCELL
  mstr_standard offpage *
  page188_i126
#ISCELL
  mstr_standard offpage *
  page188_i127
#CELL
  mstr_discrete res *
  page188_i128
#CELL
  mstr_discrete res *
  page188_i129
#ISCELL
  mstr_standard offpage *
  page188_i13
#ISCELL
  mstr_symbols gnd *
  page188_i130
#CELL
  mstr_discrete res *
  page188_i131
#CELL
  mstr_discrete res *
  page188_i132
#CELL
  mstr_discrete res *
  page188_i133
#CELL
  mstr_discrete res *
  page188_i134
#ISCELL
  mstr_standard offpage *
  page188_i14
#ISCELL
  mstr_standard offpage *
  page188_i15
#ISCELL
  mstr_standard offpage *
  page188_i16
#CELL
  dev_discrete cap_a *
  page188_i2
#CELL
  dev_discrete cap_a *
  page188_i21
#CELL
  dev_discrete cap_a *
  page188_i23
#ISCELL
  mstr_symbols gnd *
  page188_i24
#CELL
  dev_discrete cap_a *
  page188_i25
#CELL
  mstr_sconn sconn64_h87568002_a *
  page188_i27
#ISCELL
  mstr_standard offpage *
  page188_i28
#ISCELL
  mstr_standard offpage *
  page188_i29
#CELL
  dev_discrete cap_a *
  page188_i3
#ISCELL
  mstr_standard offpage *
  page188_i32
#ISCELL
  mstr_standard offpage *
  page188_i33
#ISCELL
  mstr_standard offpage *
  page188_i36
#ISCELL
  mstr_standard offpage *
  page188_i37
#ISCELL
  mstr_symbols gnd *
  page188_i39
#CELL
  dev_discrete cap_a *
  page188_i40
#CELL
  mstr_discrete cap *
  page188_i41
#CELL
  dev_discrete cap_a *
  page188_i53
#CELL
  dev_discrete cap_a *
  page188_i55
#CELL
  dev_discrete cap_a *
  page188_i56
#CELL
  dev_discrete cap_a *
  page188_i57
#ISCELL
  mstr_symbols gnd *
  page188_i58
#ISCELL
  mstr_symbols p12v_stby *
  page188_i59
#ISCELL
  mstr_standard offpage *
  page188_i6
#ISCELL
  mstr_symbols p12v_stby *
  page188_i60
#ISCELL
  mstr_symbols p12v_stby *
  page188_i61
#ISCELL
  mstr_symbols p12v_stby *
  page188_i62
#ISCELL
  mstr_symbols p12v_stby *
  page188_i63
#ISCELL
  mstr_standard offpage *
  page188_i7
#ISCELL
  mstr_standard offpage *
  page188_i76
#ISCELL
  mstr_standard offpage *
  page188_i79
#ISCELL
  mstr_standard offpage *
  page188_i8
#CELL
  dev_discrete cap_a *
  page188_i82
#ISCELL
  mstr_standard offpage *
  page188_i85
#CELL
  dev_discrete cap_a *
  page188_i86
#ISCELL
  mstr_standard offpage *
  page188_i87
#CELL
  mstr_discrete res *
  page188_i88
#CELL
  mstr_discrete res *
  page188_i89
#ISCELL
  mstr_standard offpage *
  page188_i9
#CELL
  mstr_discrete res *
  page188_i90
#CELL
  mstr_discrete res *
  page188_i91
#CELL
  mstr_discrete res *
  page188_i92
#CELL
  mstr_discrete res *
  page188_i93
#CELL
  mstr_discrete res *
  page188_i94
#CELL
  mstr_discrete res *
  page188_i95
#ISCELL
  mstr_standard offpage *
  page188_i96
#ISCELL
  mstr_standard offpage *
  page188_i97
#ISCELL
  mstr_standard offpage *
  page188_i98
#ISCELL
  mstr_standard offpage *
  page188_i99
#ISCELL
  mstr_misc dns *
  *
#ISCELL
  mstr_symbols bom_note *
  *
#ISCELL
  mstr_symbols design_note *
  *
#ISCELL
  mstr_symbols intel_corp_bpage *
  *
#ISCELL
  mstr_standard offpage *
  page189_i1
#ISCELL
  mstr_standard offpage *
  page189_i10
#ISCELL
  mstr_standard offpage *
  page189_i11
#ISCELL
  mstr_standard offpage *
  page189_i12
#CELL
  mstr_discrete res *
  page189_i13
#ISCELL
  mstr_standard offpage *
  page189_i14
#ISCELL
  mstr_standard offpage *
  page189_i15
#ISCELL
  mstr_standard offpage *
  page189_i16
#CELL
  mstr_discrete res *
  page189_i17
#CELL
  mstr_discrete res *
  page189_i18
#CELL
  mstr_discrete res *
  page189_i19
#ISCELL
  mstr_standard offpage *
  page189_i2
#CELL
  mstr_discrete res *
  page189_i20
#CELL
  mstr_discrete res *
  page189_i21
#CELL
  mstr_discrete res *
  page189_i22
#CELL
  mstr_discrete res *
  page189_i23
#CELL
  mstr_discrete res *
  page189_i24
#CELL
  mstr_discrete res *
  page189_i25
#CELL
  mstr_discrete res *
  page189_i26
#CELL
  mstr_discrete res *
  page189_i27
#ISCELL
  mstr_standard offpage *
  page189_i28
#ISCELL
  mstr_standard offpage *
  page189_i29
#ISCELL
  mstr_standard offpage *
  page189_i3
#ISCELL
  mstr_standard offpage *
  page189_i30
#ISCELL
  mstr_standard offpage *
  page189_i31
#ISCELL
  mstr_standard offpage *
  page189_i32
#ISCELL
  mstr_standard offpage *
  page189_i33
#ISCELL
  mstr_standard offpage *
  page189_i34
#ISCELL
  mstr_standard offpage *
  page189_i35
#CELL
  mstr_discrete res *
  page189_i36
#CELL
  mstr_discrete res *
  page189_i37
#CELL
  mstr_discrete res *
  page189_i38
#ISCELL
  mstr_standard offpage *
  page189_i39
#ISCELL
  mstr_standard offpage *
  page189_i4
#ISCELL
  mstr_standard offpage *
  page189_i40
#ISCELL
  mstr_standard offpage *
  page189_i41
#ISCELL
  mstr_standard offpage *
  page189_i42
#ISCELL
  mstr_symbols p3v3_stby *
  page189_i43
#CELL
  mstr_discrete res *
  page189_i44
#CELL
  mstr_discrete res *
  page189_i45
#ISCELL
  mstr_symbols gnd *
  page189_i46
#CELL
  mstr_conn conn8_c77962004 *
  page189_i47
#ISCELL
  mstr_symbols p3v3_stby *
  page189_i48
#CELL
  mstr_discrete diode *
  page189_i49
#ISCELL
  mstr_standard offpage *
  page189_i5
#CELL
  mstr_discrete res *
  page189_i50
#CELL
  mstr_discrete res *
  page189_i51
#ISCELL
  mstr_symbols p3v3_stby *
  page189_i52
#CELL
  mstr_discrete res *
  page189_i53
#ISCELL
  mstr_symbols gnd *
  page189_i54
#ISCELL
  mstr_symbols gnd *
  page189_i55
#CELL
  mstr_discrete res *
  page189_i56
#ISCELL
  mstr_standard offpage *
  page189_i57
#ISCELL
  mstr_standard offpage *
  page189_i58
#ISCELL
  mstr_standard offpage *
  page189_i59
#ISCELL
  mstr_standard offpage *
  page189_i6
#ISCELL
  mstr_standard offpage *
  page189_i60
#ISCELL
  mstr_standard offpage *
  page189_i61
#ISCELL
  mstr_standard offpage *
  page189_i62
#CELL
  mstr_discrete res *
  page189_i63
#CELL
  mstr_discrete res *
  page189_i64
#CELL
  mstr_discrete res *
  page189_i65
#CELL
  mstr_discrete res *
  page189_i66
#CELL
  mstr_ttl ttl3126 *
  page189_i67
#ISCELL
  mstr_symbols p3v3_stby *
  page189_i68
#CELL
  mstr_discrete cap *
  page189_i69
#CELL
  mstr_discrete res *
  page189_i7
#ISCELL
  mstr_symbols gnd *
  page189_i70
#ISCELL
  mstr_standard offpage *
  page189_i71
#ISCELL
  mstr_standard offpage *
  page189_i72
#ISCELL
  mstr_standard offpage *
  page189_i73
#ISCELL
  mstr_standard offpage *
  page189_i74
#ISCELL
  mstr_standard offpage *
  page189_i75
#CELL
  mstr_discrete res *
  page189_i76
#CELL
  mstr_discrete res *
  page189_i77
#ISCELL
  mstr_standard offpage *
  page189_i78
#ISCELL
  mstr_standard offpage *
  page189_i79
#CELL
  mstr_discrete res *
  page189_i8
#ISCELL
  mstr_standard offpage *
  page189_i80
#CELL
  mstr_discrete res *
  page189_i9
#ISCELL
  mstr_misc dns *
  *
#ISCELL
  mstr_symbols intel_corp_bpage *
  *
#CELL
  mstr_discrete res *
  page190_i116
#CELL
  mstr_discrete res *
  page190_i117
#ISCELL
  mstr_standard offpage *
  page190_i118
#ISCELL
  mstr_standard offpage *
  page190_i119
#ISCELL
  mstr_standard offpage *
  page190_i120
#ISCELL
  mstr_standard offpage *
  page190_i121
#ISCELL
  mstr_standard offpage *
  page190_i122
#ISCELL
  mstr_standard offpage *
  page190_i134
#ISCELL
  mstr_standard offpage *
  page190_i139
#ISCELL
  mstr_standard offpage *
  page190_i146
#ISCELL
  mstr_standard offpage *
  page190_i157
#ISCELL
  mstr_standard offpage *
  page190_i159
#ISCELL
  mstr_standard offpage *
  page190_i161
#ISCELL
  mstr_standard offpage *
  page190_i162
#ISCELL
  mstr_standard offpage *
  page190_i165
#ISCELL
  mstr_standard offpage *
  page190_i167
#ISCELL
  mstr_standard offpage *
  page190_i168
#ISCELL
  mstr_standard offpage *
  page190_i171
#CELL
  mstr_memory lcmxo2_a *
  page190_i179
#ISCELL
  mstr_standard offpage *
  page190_i220
#ISCELL
  mstr_standard offpage *
  page190_i221
#ISCELL
  mstr_standard offpage *
  page190_i224
#ISCELL
  mstr_standard offpage *
  page190_i225
#ISCELL
  mstr_standard offpage *
  page190_i226
#ISCELL
  mstr_standard offpage *
  page190_i227
#ISCELL
  mstr_standard offpage *
  page190_i231
#ISCELL
  mstr_standard offpage *
  page190_i234
#ISCELL
  mstr_standard offpage *
  page190_i235
#ISCELL
  mstr_standard offpage *
  page190_i236
#ISCELL
  mstr_standard offpage *
  page190_i237
#ISCELL
  mstr_standard offpage *
  page190_i239
#ISCELL
  mstr_standard offpage *
  page190_i240
#ISCELL
  mstr_standard offpage *
  page190_i241
#ISCELL
  mstr_standard offpage *
  page190_i243
#ISCELL
  mstr_standard offpage *
  page190_i244
#ISCELL
  mstr_standard offpage *
  page190_i246
#ISCELL
  mstr_standard offpage *
  page190_i248
#ISCELL
  mstr_standard offpage *
  page190_i252
#ISCELL
  mstr_standard offpage *
  page190_i255
#ISCELL
  mstr_standard offpage *
  page190_i260
#ISCELL
  mstr_standard offpage *
  page190_i261
#ISCELL
  mstr_standard offpage *
  page190_i263
#ISCELL
  mstr_standard offpage *
  page190_i267
#ISCELL
  mstr_standard offpage *
  page190_i268
#ISCELL
  mstr_standard offpage *
  page190_i269
#ISCELL
  mstr_standard offpage *
  page190_i270
#ISCELL
  mstr_standard offpage *
  page190_i271
#ISCELL
  mstr_standard offpage *
  page190_i272
#ISCELL
  mstr_standard offpage *
  page190_i273
#ISCELL
  mstr_standard offpage *
  page190_i275
#ISCELL
  mstr_standard offpage *
  page190_i276
#ISCELL
  mstr_standard offpage *
  page190_i277
#ISCELL
  mstr_standard offpage *
  page190_i279
#ISCELL
  mstr_standard offpage *
  page190_i280
#ISCELL
  mstr_standard offpage *
  page190_i284
#ISCELL
  mstr_standard offpage *
  page190_i285
#ISCELL
  mstr_standard offpage *
  page190_i298
#ISCELL
  mstr_standard offpage *
  page190_i299
#ISCELL
  mstr_standard offpage *
  page190_i301
#ISCELL
  mstr_standard offpage *
  page190_i302
#ISCELL
  mstr_standard offpage *
  page190_i303
#ISCELL
  mstr_standard offpage *
  page190_i304
#ISCELL
  mstr_standard offpage *
  page190_i305
#ISCELL
  mstr_standard offpage *
  page190_i306
#ISCELL
  mstr_standard offpage *
  page190_i307
#ISCELL
  mstr_standard offpage *
  page190_i308
#ISCELL
  mstr_standard offpage *
  page190_i309
#ISCELL
  mstr_standard offpage *
  page190_i312
#ISCELL
  mstr_standard offpage *
  page190_i313
#ISCELL
  mstr_standard offpage *
  page190_i314
#ISCELL
  mstr_standard offpage *
  page190_i317
#ISCELL
  mstr_standard offpage *
  page190_i318
#ISCELL
  mstr_standard offpage *
  page190_i319
#ISCELL
  mstr_standard offpage *
  page190_i320
#ISCELL
  mstr_standard offpage *
  page190_i321
#ISCELL
  mstr_standard offpage *
  page190_i322
#ISCELL
  mstr_standard offpage *
  page190_i323
#ISCELL
  mstr_standard offpage *
  page190_i324
#ISCELL
  mstr_standard offpage *
  page190_i325
#ISCELL
  mstr_standard offpage *
  page190_i326
#ISCELL
  mstr_standard offpage *
  page190_i327
#ISCELL
  mstr_standard offpage *
  page190_i328
#ISCELL
  mstr_standard offpage *
  page190_i329
#ISCELL
  mstr_standard offpage *
  page190_i332
#ISCELL
  mstr_standard offpage *
  page190_i333
#ISCELL
  mstr_standard offpage *
  page190_i334
#ISCELL
  mstr_standard offpage *
  page190_i335
#ISCELL
  mstr_standard offpage *
  page190_i336
#ISCELL
  mstr_standard offpage *
  page190_i337
#CELL
  mstr_discrete res *
  page190_i338
#ISCELL
  mstr_standard offpage *
  page190_i339
#ISCELL
  mstr_standard offpage *
  page190_i340
#ISCELL
  mstr_standard offpage *
  page190_i341
#ISCELL
  mstr_standard offpage *
  page190_i342
#ISCELL
  mstr_standard offpage *
  page190_i343
#ISCELL
  mstr_standard offpage *
  page190_i344
#ISCELL
  mstr_standard offpage *
  page190_i345
#ISCELL
  mstr_standard offpage *
  page190_i346
#ISCELL
  mstr_standard offpage *
  page190_i347
#ISCELL
  mstr_standard offpage *
  page190_i348
#CELL
  mstr_discrete res *
  page190_i349
#ISCELL
  mstr_symbols gnd *
  page190_i350
#CELL
  mstr_discrete res *
  page190_i351
#ISCELL
  mstr_standard offpage *
  page190_i352
#ISCELL
  mstr_symbols cad_note *
  *
#ISCELL
  mstr_symbols design_note *
  *
#ISCELL
  mstr_symbols intel_corp_bpage *
  *
#ISCELL
  mstr_standard offpage *
  page191_i1
#ISCELL
  mstr_standard offpage *
  page191_i102
#ISCELL
  mstr_standard offpage *
  page191_i115
#ISCELL
  mstr_standard offpage *
  page191_i118
#ISCELL
  mstr_standard offpage *
  page191_i120
#ISCELL
  mstr_standard offpage *
  page191_i125
#ISCELL
  mstr_standard offpage *
  page191_i127
#ISCELL
  mstr_standard offpage *
  page191_i128
#ISCELL
  mstr_standard offpage *
  page191_i129
#ISCELL
  mstr_standard offpage *
  page191_i132
#ISCELL
  mstr_standard offpage *
  page191_i133
#ISCELL
  mstr_standard offpage *
  page191_i134
#ISCELL
  mstr_standard offpage *
  page191_i135
#ISCELL
  mstr_standard offpage *
  page191_i136
#ISCELL
  mstr_standard offpage *
  page191_i137
#ISCELL
  mstr_standard offpage *
  page191_i139
#ISCELL
  mstr_standard offpage *
  page191_i141
#ISCELL
  mstr_standard offpage *
  page191_i142
#ISCELL
  mstr_standard offpage *
  page191_i143
#ISCELL
  mstr_standard offpage *
  page191_i145
#ISCELL
  mstr_standard offpage *
  page191_i147
#ISCELL
  mstr_standard offpage *
  page191_i148
#ISCELL
  mstr_standard offpage *
  page191_i149
#ISCELL
  mstr_standard offpage *
  page191_i151
#ISCELL
  mstr_standard offpage *
  page191_i156
#ISCELL
  mstr_standard offpage *
  page191_i157
#ISCELL
  mstr_standard offpage *
  page191_i158
#ISCELL
  mstr_standard offpage *
  page191_i160
#ISCELL
  mstr_standard offpage *
  page191_i161
#ISCELL
  mstr_standard offpage *
  page191_i162
#ISCELL
  mstr_standard offpage *
  page191_i163
#ISCELL
  mstr_standard offpage *
  page191_i164
#ISCELL
  mstr_standard offpage *
  page191_i165
#CELL
  mstr_discrete res *
  page191_i166
#ISCELL
  mstr_standard offpage *
  page191_i167
#ISCELL
  mstr_standard offpage *
  page191_i168
#ISCELL
  mstr_standard offpage *
  page191_i169
#ISCELL
  mstr_standard offpage *
  page191_i17
#ISCELL
  mstr_standard offpage *
  page191_i170
#ISCELL
  mstr_symbols p3v3_stby *
  page191_i171
#CELL
  mstr_discrete res *
  page191_i172
#ISCELL
  mstr_standard offpage *
  page191_i173
#ISCELL
  mstr_standard offpage *
  page191_i174
#ISCELL
  mstr_standard offpage *
  page191_i175
#ISCELL
  mstr_standard offpage *
  page191_i176
#ISCELL
  mstr_standard offpage *
  page191_i177
#ISCELL
  mstr_standard offpage *
  page191_i178
#ISCELL
  mstr_standard offpage *
  page191_i179
#ISCELL
  mstr_standard offpage *
  page191_i18
#ISCELL
  mstr_standard offpage *
  page191_i180
#ISCELL
  mstr_standard offpage *
  page191_i181
#ISCELL
  mstr_standard offpage *
  page191_i182
#ISCELL
  mstr_standard offpage *
  page191_i183
#CELL
  mstr_discrete res *
  page191_i184
#ISCELL
  mstr_standard offpage *
  page191_i185
#ISCELL
  mstr_standard offpage *
  page191_i186
#ISCELL
  mstr_standard offpage *
  page191_i187
#ISCELL
  mstr_standard offpage *
  page191_i188
#ISCELL
  mstr_standard offpage *
  page191_i189
#ISCELL
  mstr_standard offpage *
  page191_i19
#ISCELL
  mstr_standard offpage *
  page191_i190
#ISCELL
  mstr_standard offpage *
  page191_i191
#ISCELL
  mstr_standard offpage *
  page191_i192
#CELL
  mstr_discrete res *
  page191_i193
#ISCELL
  mstr_symbols p3v3_stby *
  page191_i194
#CELL
  mstr_discrete res *
  page191_i195
#ISCELL
  mstr_symbols p3v3_stby *
  page191_i196
#CELL
  mstr_discrete res *
  page191_i197
#CELL
  mstr_discrete res *
  page191_i198
#ISCELL
  mstr_standard offpage *
  page191_i199
#ISCELL
  mstr_standard offpage *
  page191_i2
#ISCELL
  mstr_standard offpage *
  page191_i22
#ISCELL
  mstr_standard offpage *
  page191_i24
#ISCELL
  mstr_standard offpage *
  page191_i26
#ISCELL
  mstr_standard offpage *
  page191_i27
#ISCELL
  mstr_standard offpage *
  page191_i33
#ISCELL
  mstr_standard offpage *
  page191_i38
#ISCELL
  mstr_standard offpage *
  page191_i47
#ISCELL
  mstr_standard offpage *
  page191_i49
#CELL
  mstr_memory lcmxo2_a *
  page191_i59
#ISCELL
  mstr_standard offpage *
  page191_i84
#ISCELL
  mstr_standard offpage *
  page191_i87
#ISCELL
  mstr_standard offpage *
  page191_i88
#ISCELL
  mstr_standard offpage *
  page191_i93
#ISCELL
  mstr_standard offpage *
  page191_i95
#ISCELL
  mstr_standard offpage *
  page191_i96
#ISCELL
  mstr_standard offpage *
  page191_i97
#ISCELL
  mstr_standard offpage *
  page191_i99
#ISCELL
  mstr_misc dns *
  *
#ISCELL
  mstr_symbols intel_corp_bpage *
  *
#CELL
  dev_discrete cap_a *
  page192_i1
#CELL
  dev_discrete cap_a *
  page192_i10
#CELL
  dev_discrete cap_a *
  page192_i11
#CELL
  dev_discrete cap_a *
  page192_i12
#CELL
  mstr_memory lcmxo2_a *
  page192_i14
#CELL
  dev_discrete cap_a *
  page192_i15
#CELL
  dev_discrete cap_a *
  page192_i16
#CELL
  dev_discrete cap_a *
  page192_i17
#CELL
  dev_discrete cap_a *
  page192_i18
#CELL
  dev_discrete cap_a *
  page192_i19
#ISCELL
  mstr_symbols gnd *
  page192_i2
#CELL
  dev_discrete cap_a *
  page192_i20
#CELL
  dev_discrete cap_a *
  page192_i21
#CELL
  dev_discrete cap_a *
  page192_i22
#CELL
  dev_discrete cap_a *
  page192_i23
#CELL
  dev_discrete cap_a *
  page192_i25
#ISCELL
  mstr_symbols gnd *
  page192_i26
#CELL
  dev_discrete cap_a *
  page192_i28
#ISCELL
  mstr_symbols p3v3_stby *
  page192_i29
#CELL
  dev_discrete cap_a *
  page192_i3
#ISCELL
  mstr_symbols p3v3_stby *
  page192_i30
#ISCELL
  mstr_symbols p3v3_stby *
  page192_i31
#ISCELL
  mstr_symbols p3v3_stby *
  page192_i32
#CELL
  mstr_discrete res *
  page192_i33
#CELL
  mstr_discrete res *
  page192_i34
#ISCELL
  mstr_symbols p3v3_stby *
  page192_i35
#ISCELL
  mstr_standard offpage *
  page192_i36
#ISCELL
  mstr_standard offpage *
  page192_i37
#CELL
  mstr_discrete res *
  page192_i38
#ISCELL
  mstr_symbols p3v3_stby *
  page192_i39
#CELL
  dev_discrete cap_a *
  page192_i4
#ISCELL
  mstr_standard offpage *
  page192_i40
#CELL
  mstr_discrete res *
  page192_i41
#ISCELL
  mstr_symbols p3v3_stby *
  page192_i42
#ISCELL
  mstr_standard offpage *
  page192_i45
#CELL
  mstr_discrete res *
  page192_i48
#CELL
  mstr_discrete res *
  page192_i49
#ISCELL
  mstr_symbols gnd *
  page192_i5
#ISCELL
  mstr_standard offpage *
  page192_i50
#ISCELL
  mstr_standard offpage *
  page192_i51
#ISCELL
  mstr_symbols pvpp_abc *
  page192_i52
#ISCELL
  mstr_standard offpage *
  page192_i54
#CELL
  mstr_discrete res *
  page192_i55
#ISCELL
  mstr_symbols p3v3_stby *
  page192_i56
#CELL
  mstr_discrete res *
  page192_i57
#ISCELL
  mstr_symbols p3v3_stby *
  page192_i58
#CELL
  mstr_discrete res *
  page192_i59
#CELL
  dev_discrete cap_a *
  page192_i6
#ISCELL
  mstr_standard offpage *
  page192_i60
#ISCELL
  mstr_symbols gnd *
  page192_i61
#ISCELL
  mstr_symbols pvpp_klm *
  page192_i62
#CELL
  dev_discrete cap_a *
  page192_i7
#CELL
  dev_discrete cap_a *
  page192_i8
#CELL
  dev_discrete cap_a *
  page192_i9
#ISCELL
  mstr_symbols design_note *
  *
#ISCELL
  mstr_symbols intel_corp_bpage *
  *
#ISCELL
  mstr_symbols vcc_core *
  page193_i107
#ISCELL
  mstr_standard offpage *
  page193_i111
#ISCELL
  mstr_standard offpage *
  page193_i112
#ISCELL
  mstr_standard offpage *
  page193_i113
#ISCELL
  mstr_standard offpage *
  page193_i114
#ISCELL
  mstr_symbols vcc_core *
  page193_i131
#ISCELL
  mstr_symbols vcc_core *
  page193_i134
#ISCELL
  mstr_standard offpage *
  page193_i138
#CELL
  dev_discrete cap_a *
  page193_i140
#CELL
  dev_discrete cap_a *
  page193_i141
#ISCELL
  mstr_symbols pvccio_cpu1 *
  page193_i144
#ISCELL
  mstr_standard offpage *
  page193_i149
#ISCELL
  mstr_standard offpage *
  page193_i150
#ISCELL
  mstr_standard offpage *
  page193_i151
#ISCELL
  mstr_standard offpage *
  page193_i152
#ISCELL
  mstr_standard offpage *
  page193_i153
#ISCELL
  mstr_standard offpage *
  page193_i154
#ISCELL
  mstr_standard offpage *
  page193_i155
#ISCELL
  mstr_standard offpage *
  page193_i156
#ISCELL
  mstr_standard offpage *
  page193_i157
#ISCELL
  mstr_symbols vcc_core *
  page193_i161
#ISCELL
  mstr_symbols vcc_core *
  page193_i162
#ISCELL
  mstr_symbols vcc_core *
  page193_i164
#ISCELL
  mstr_symbols vcc_core *
  page193_i165
#ISCELL
  mstr_symbols vcc_core *
  page193_i166
#ISCELL
  mstr_symbols vcc_core *
  page193_i167
#ISCELL
  mstr_symbols vcc_core *
  page193_i168
#CELL
  mstr_discrete res *
  page193_i169
#CELL
  mstr_discrete res *
  page193_i170
#ISCELL
  mstr_symbols gnd *
  page193_i171
#ISCELL
  mstr_symbols p3v3 *
  page193_i173
#ISCELL
  mstr_standard offpage *
  page193_i174
#CELL
  mstr_discrete capp *
  page193_i175
#ISCELL
  mstr_standard offpage *
  page193_i2
#CELL
  mstr_discrete capp *
  page193_i29
#ISCELL
  mstr_symbols gnd *
  page193_i30
#CELL
  dev_discrete cap_a *
  page193_i31
#ISCELL
  mstr_symbols gnd *
  page193_i37
#CELL
  dev_discrete cap_a *
  page193_i38
#ISCELL
  mstr_standard offpage *
  page193_i4
#CELL
  mstr_sconn sconn120_h61426002 *
  page193_i45
#CELL
  mstr_sconn sconn120_h61426002 *
  page193_i46
#ISCELL
  mstr_standard offpage *
  page193_i49
#ISCELL
  mstr_standard offpage *
  page193_i5
#ISCELL
  mstr_standard offpage *
  page193_i50
#ISCELL
  mstr_symbols gnd *
  page193_i56
#ISCELL
  mstr_symbols gnd *
  page193_i60
#CELL
  mstr_discrete capp *
  page193_i61
#CELL
  mstr_discrete capp *
  page193_i62
#ISCELL
  mstr_symbols gnd *
  page193_i64
#CELL
  dev_discrete cap_a *
  page193_i68
#CELL
  dev_discrete cap_a *
  page193_i70
#ISCELL
  mstr_symbols gnd *
  page193_i75
#ISCELL
  mstr_symbols gnd *
  page193_i81
#ISCELL
  mstr_standard offpage *
  page193_i83
#ISCELL
  mstr_standard offpage *
  page193_i84
#ISCELL
  mstr_symbols gnd *
  page193_i85
#ISCELL
  mstr_symbols p12v_stby *
  page193_i86
#ISCELL
  mstr_symbols p3v3_stby *
  page193_i87
#ISCELL
  mstr_symbols p5v_stby *
  page193_i88
#ISCELL
  mstr_standard offpage *
  page193_i90
#ISCELL
  mstr_symbols gnd *
  page193_i94
#ISCELL
  mstr_symbols gnd *
  page193_i95
#ISCELL
  mstr_symbols design_note *
  *
#ISCELL
  mstr_symbols intel_corp_bpage *
  *
#ISCELL
  mstr_symbols gnd *
  page194_i100
#CELL
  mstr_discrete capp *
  page194_i101
#ISCELL
  mstr_symbols vcc_core *
  page194_i102
#ISCELL
  mstr_symbols gnd *
  page194_i110
#ISCELL
  mstr_symbols gnd *
  page194_i111
#ISCELL
  mstr_standard offpage *
  page194_i114
#ISCELL
  mstr_standard offpage *
  page194_i116
#ISCELL
  mstr_symbols p12v_stby *
  page194_i119
#ISCELL
  mstr_symbols p3v3_stby *
  page194_i120
#ISCELL
  mstr_symbols p5v_stby *
  page194_i121
#ISCELL
  mstr_standard offpage *
  page194_i123
#ISCELL
  mstr_standard offpage *
  page194_i124
#ISCELL
  mstr_standard offpage *
  page194_i125
#ISCELL
  mstr_symbols gnd *
  page194_i127
#ISCELL
  mstr_symbols vcc_core *
  page194_i130
#ISCELL
  mstr_standard offpage *
  page194_i131
#ISCELL
  mstr_standard offpage *
  page194_i132
#ISCELL
  mstr_standard offpage *
  page194_i133
#ISCELL
  mstr_standard offpage *
  page194_i134
#ISCELL
  mstr_symbols vcc_core *
  page194_i141
#ISCELL
  mstr_symbols vcc_core *
  page194_i142
#ISCELL
  mstr_symbols vcc_core *
  page194_i143
#ISCELL
  mstr_symbols vcc_core *
  page194_i144
#ISCELL
  mstr_standard offpage *
  page194_i148
#CELL
  dev_discrete cap_a *
  page194_i149
#CELL
  dev_discrete cap_a *
  page194_i150
#ISCELL
  mstr_symbols gnd *
  page194_i151
#ISCELL
  mstr_symbols pvccio_cpu0 *
  page194_i154
#CELL
  mstr_discrete res *
  page194_i155
#CELL
  mstr_discrete res *
  page194_i156
#ISCELL
  mstr_symbols gnd *
  page194_i157
#ISCELL
  mstr_standard offpage *
  page194_i158
#ISCELL
  mstr_standard offpage *
  page194_i159
#CELL
  dev_discrete cap_a *
  page194_i16
#ISCELL
  mstr_standard offpage *
  page194_i160
#ISCELL
  mstr_standard offpage *
  page194_i161
#ISCELL
  mstr_standard offpage *
  page194_i162
#ISCELL
  mstr_standard offpage *
  page194_i163
#ISCELL
  mstr_standard offpage *
  page194_i164
#ISCELL
  mstr_standard offpage *
  page194_i165
#ISCELL
  mstr_standard offpage *
  page194_i166
#ISCELL
  mstr_standard offpage *
  page194_i167
#ISCELL
  mstr_symbols p3v3 *
  page194_i170
#ISCELL
  mstr_standard offpage *
  page194_i171
#ISCELL
  mstr_symbols gnd *
  page194_i28
#CELL
  mstr_discrete capp *
  page194_i29
#ISCELL
  mstr_symbols vcc_core *
  page194_i30
#CELL
  mstr_discrete capp *
  page194_i31
#ISCELL
  mstr_symbols gnd *
  page194_i33
#CELL
  mstr_sconn sconn120_h61426002 *
  page194_i55
#CELL
  mstr_sconn sconn120_h61426002 *
  page194_i56
#ISCELL
  mstr_symbols gnd *
  page194_i61
#ISCELL
  mstr_symbols gnd *
  page194_i62
#ISCELL
  mstr_standard offpage *
  page194_i64
#ISCELL
  mstr_standard offpage *
  page194_i67
#ISCELL
  mstr_symbols vcc_core *
  page194_i68
#ISCELL
  mstr_symbols vcc_core *
  page194_i69
#CELL
  dev_discrete cap_a *
  page194_i86
#CELL
  dev_discrete cap_a *
  page194_i9
#ISCELL
  mstr_symbols gnd *
  page194_i92
#ISCELL
  mstr_symbols vcc_core *
  page194_i95
#CELL
  dev_discrete cap_a *
  page194_i99
#ISCELL
  mstr_misc dns *
  *
#ISCELL
  mstr_symbols intel_corp_bpage *
  *
#CELL
  mstr_discrete capp *
  page195_i100
#CELL
  mstr_discrete capp *
  page195_i101
#CELL
  mstr_discrete capp *
  page195_i102
#CELL
  mstr_discrete capp *
  page195_i103
#CELL
  mstr_discrete capp *
  page195_i104
#CELL
  mstr_discrete capp *
  page195_i105
#CELL
  mstr_discrete capp *
  page195_i106
#ISCELL
  mstr_symbols p12v_stby *
  page195_i107
#CELL
  mstr_discrete capp *
  page195_i108
#CELL
  mstr_discrete capp *
  page195_i109
#ISCELL
  mstr_symbols gnd *
  page195_i110
#CELL
  mstr_discrete capp *
  page195_i111
#CELL
  mstr_discrete capp *
  page195_i112
#CELL
  mstr_discrete capp *
  page195_i113
#CELL
  w_hdl fci-conn12-2r-gp *
  page195_i114
#CELL
  w_hdl fci-conn12-2r-gp *
  page195_i115
#CELL
  w_hdl stft363b238r224h453-gp *
  page195_i117
#ISCELL
  mstr_symbols gnd *
  page195_i118
#ISCELL
  mstr_symbols p12v_psu *
  page195_i25
#CELL
  mstr_conn conn3_g98259001 *
  page195_i26
#ISCELL
  mstr_symbols gnd *
  page195_i27
#ISCELL
  mstr_symbols gnd *
  page195_i28
#ISCELL
  mstr_symbols gnd *
  page195_i30
#CELL
  mstr_discrete cap *
  page195_i31
#CELL
  mstr_discrete cap *
  page195_i32
#ISCELL
  mstr_symbols gnd *
  page195_i33
#ISCELL
  mstr_symbols p12v_psu *
  page195_i34
#CELL
  mstr_discrete cap *
  page195_i35
#CELL
  dev_discrete cap_a *
  page195_i36
#CELL
  dev_discrete cap_a *
  page195_i37
#CELL
  dev_discrete cap_a *
  page195_i38
#CELL
  dev_discrete cap_a *
  page195_i39
#ISCELL
  mstr_symbols p12v_psu *
  page195_i40
#ISCELL
  mstr_symbols gnd *
  page195_i48
#CELL
  mstr_misc mtg_keyhole *
  page195_i49
#CELL
  mstr_misc mtg_keyhole *
  page195_i52
#ISCELL
  mstr_symbols gnd *
  page195_i53
#CELL
  mstr_misc mtg_keyhole *
  page195_i54
#ISCELL
  mstr_symbols gnd *
  page195_i55
#CELL
  mstr_misc mtg_keyhole *
  page195_i56
#ISCELL
  mstr_symbols gnd *
  page195_i57
#CELL
  mstr_misc mtg_keyhole *
  page195_i62
#ISCELL
  mstr_symbols gnd *
  page195_i63
#ISCELL
  mstr_symbols gnd *
  page195_i64
#CELL
  mstr_misc mtg_keyhole *
  page195_i65
#ISCELL
  mstr_symbols gnd *
  page195_i66
#CELL
  mstr_misc mtg_keyhole *
  page195_i67
#ISCELL
  mstr_symbols p12v_psu *
  page195_i77
#ISCELL
  mstr_symbols gnd *
  page195_i79
#ISCELL
  mstr_symbols p12v_psu *
  page195_i80
#ISCELL
  mstr_symbols gnd *
  page195_i81
#CELL
  mstr_discrete capp *
  page195_i82
#CELL
  mstr_discrete capp *
  page195_i83
#CELL
  mstr_discrete capp *
  page195_i84
#CELL
  mstr_discrete capp *
  page195_i85
#ISCELL
  mstr_symbols p12v_stby *
  page195_i92
#ISCELL
  mstr_symbols p12v_stby *
  page195_i93
#ISCELL
  mstr_symbols gnd *
  page195_i94
#ISCELL
  mstr_symbols gnd *
  page195_i95
#CELL
  mstr_discrete capp *
  page195_i96
#CELL
  mstr_discrete capp *
  page195_i97
#CELL
  mstr_discrete capp *
  page195_i98
#CELL
  mstr_discrete capp *
  page195_i99
#ISCELL
  mstr_misc dns *
  *
#ISCELL
  mstr_symbols cad_note *
  *
#ISCELL
  mstr_symbols design_note *
  *
#ISCELL
  mstr_symbols intel_corp_bpage *
  *
#CELL
  dev_discrete cap_a *
  page196_i102
#CELL
  mstr_discrete diode *
  page196_i103
#CELL
  mstr_vreg tps3700 *
  page196_i104
#CELL
  dev_discrete cap_a *
  page196_i105
#CELL
  mstr_discrete res *
  page196_i106
#ISCELL
  mstr_standard offpage *
  page196_i107
#ISCELL
  mstr_symbols gnd *
  page196_i108
#ISCELL
  mstr_symbols gnd *
  page196_i110
#ISCELL
  mstr_symbols p3v3_stby *
  page196_i111
#CELL
  mstr_discrete res *
  page196_i112
#CELL
  mstr_discrete res *
  page196_i114
#CELL
  mstr_discrete res *
  page196_i115
#ISCELL
  mstr_symbols p5v *
  page196_i116
#ISCELL
  mstr_symbols p12v *
  page196_i117
#ISCELL
  mstr_symbols gnd *
  page196_i118
#ISCELL
  mstr_symbols gnd *
  page196_i119
#CELL
  mstr_discrete res *
  page196_i120
#CELL
  mstr_discrete res *
  page196_i121
#CELL
  mstr_discrete res *
  page196_i122
#ISCELL
  mstr_symbols p3v3_stby *
  page196_i123
#ISCELL
  mstr_symbols gnd *
  page196_i125
#ISCELL
  mstr_symbols p3v3_stby *
  page196_i126
#ISCELL
  mstr_symbols p3v3_stby *
  page196_i127
#CELL
  mstr_discrete diode *
  page196_i128
#CELL
  mstr_discrete fet_n *
  page196_i129
#CELL
  mstr_discrete res *
  page196_i130
#ISCELL
  mstr_symbols gnd *
  page196_i43
#ISCELL
  mstr_standard offpage *
  page196_i45
#CELL
  mstr_discrete res *
  page196_i46
#CELL
  mstr_misc battery *
  page196_i47
#CELL
  mstr_discrete vert_batt_3pin *
  page196_i51
#ISCELL
  mstr_symbols gnd *
  page196_i52
#CELL
  mstr_discrete diode2a_dual *
  page196_i53
#ISCELL
  mstr_symbols p3v3_stby *
  page196_i54
#ISCELL
  mstr_symbols p3v3_stby *
  page196_i56
#ISCELL
  mstr_symbols p12v_stby *
  page196_i57
#ISCELL
  mstr_symbols p3v3_stby *
  page196_i58
#CELL
  mstr_discrete res *
  page196_i59
#CELL
  mstr_discrete cap *
  page196_i60
#ISCELL
  mstr_symbols gnd *
  page196_i61
#ISCELL
  mstr_symbols gnd *
  page196_i62
#ISCELL
  mstr_standard offpage *
  page196_i63
#ISCELL
  mstr_standard offpage *
  page196_i64
#CELL
  mstr_discrete res *
  page196_i65
#CELL
  mstr_discrete res *
  page196_i68
#ISCELL
  mstr_symbols p3v3_stby *
  page196_i69
#CELL
  mstr_analog adm1085 *
  page196_i70
#CELL
  mstr_discrete res *
  page196_i71
#CELL
  dev_discrete cap_a *
  page196_i72
#ISCELL
  mstr_symbols gnd *
  page196_i73
#CELL
  mstr_discrete res *
  page196_i74
#CELL
  mstr_discrete res *
  page196_i75
#ISCELL
  mstr_symbols gnd *
  page196_i76
#CELL
  mstr_analog adm809 *
  page196_i80
#CELL
  dev_discrete cap_a *
  page196_i81
#ISCELL
  mstr_symbols gnd *
  page196_i82
#ISCELL
  mstr_symbols p3v3 *
  page196_i83
#ISCELL
  mstr_standard offpage *
  page196_i88
#CELL
  mstr_analog adm809 *
  page196_i89
#CELL
  mstr_discrete res *
  page196_i90
#ISCELL
  mstr_standard offpage *
  page196_i91
#CELL
  dev_discrete cap_a *
  page196_i94
#ISCELL
  mstr_symbols gnd *
  page196_i95
#ISCELL
  mstr_standard offpage *
  page196_i96
#ISCELL
  mstr_symbols p3v3_rtc_stby *
  page196_i97
#ISCELL
  mstr_standard offpage *
  page196_i98
#ISCELL
  mstr_symbols cad_note *
  *
#ISCELL
  mstr_symbols intel_corp_bpage *
  *
#CELL
  mstr_discrete cap *
  page197_i1
#CELL
  w_hdl 665kr5b-1-gp *
  page197_i101
#CELL
  w_hdl 665kr2b-gp *
  page197_i109
#CELL
  w_hdl 665kr2b-gp *
  page197_i110
#CELL
  w_hdl 665kr2b-gp *
  page197_i111
#CELL
  w_hdl 665kr2b-gp *
  page197_i112
#CELL
  w_hdl 4d02r2f-gp *
  page197_i113
#CELL
  w_hdl 4d02r2f-gp *
  page197_i114
#CELL
  w_hdl 4d02r2f-gp *
  page197_i115
#CELL
  w_hdl 4d02r2f-gp *
  page197_i116
#CELL
  w_hdl 665kr5b-1-gp *
  page197_i117
#CELL
  w_hdl 665kr5b-1-gp *
  page197_i118
#CELL
  w_hdl 665kr5b-1-gp *
  page197_i119
#CELL
  w_hdl 665kr5b-1-gp *
  page197_i120
#CELL
  w_hdl 665kr5b-1-gp *
  page197_i121
#CELL
  w_hdl 665kr5b-1-gp *
  page197_i122
#CELL
  w_hdl 665kr5b-1-gp *
  page197_i123
#CELL
  mstr_discrete res *
  page197_i14
#ISCELL
  mstr_standard offpage *
  page197_i15
#ISCELL
  mstr_standard offpage *
  page197_i16
#ISCELL
  mstr_standard offpage *
  page197_i17
#CELL
  mstr_discrete cap *
  page197_i18
#CELL
  w_hdl bsl308c-h6327-gp *
  page197_i19
#ISCELL
  mstr_symbols p12v_stby *
  page197_i2
#ISCELL
  mstr_symbols gnd *
  page197_i20
#CELL
  mstr_discrete res *
  page197_i21
#ISCELL
  mstr_standard offpage *
  page197_i22
#ISCELL
  mstr_symbols p12v_nvdimm_def *
  page197_i23
#ISCELL
  mstr_standard offpage *
  page197_i24
#ISCELL
  mstr_standard offpage *
  page197_i25
#CELL
  mstr_discrete res *
  page197_i29
#ISCELL
  mstr_symbols p12v_stby *
  page197_i30
#ISCELL
  mstr_standard offpage *
  page197_i31
#ISCELL
  mstr_standard offpage *
  page197_i32
#ISCELL
  mstr_standard offpage *
  page197_i33
#CELL
  w_hdl bsl308c-h6327-gp *
  page197_i35
#ISCELL
  mstr_symbols gnd *
  page197_i36
#CELL
  mstr_discrete res *
  page197_i37
#ISCELL
  mstr_symbols p12v_nvdimm_klm *
  page197_i38
#ISCELL
  mstr_standard offpage *
  page197_i39
#ISCELL
  mstr_standard offpage *
  page197_i40
#ISCELL
  mstr_standard offpage *
  page197_i41
#CELL
  mstr_discrete cap *
  page197_i42
#CELL
  w_hdl bsl308c-h6327-gp *
  page197_i43
#ISCELL
  mstr_symbols gnd *
  page197_i44
#CELL
  mstr_discrete res *
  page197_i45
#ISCELL
  mstr_symbols p12v_stby *
  page197_i49
#CELL
  mstr_discrete res *
  page197_i50
#ISCELL
  mstr_symbols gnd *
  page197_i52
#CELL
  mstr_discrete res *
  page197_i53
#ISCELL
  mstr_symbols p12v_nvdimm_ghj *
  page197_i54
#ISCELL
  mstr_symbols gnd *
  page197_i55
#CELL
  mstr_discrete cap *
  page197_i56
#ISCELL
  mstr_symbols p12v_nvdimm_ghj *
  page197_i57
#ISCELL
  mstr_symbols gnd *
  page197_i58
#ISCELL
  mstr_symbols gnd *
  page197_i59
#CELL
  mstr_discrete res *
  page197_i6
#CELL
  mstr_discrete cap *
  page197_i60
#ISCELL
  mstr_symbols p12v_nvdimm_klm *
  page197_i61
#ISCELL
  mstr_symbols gnd *
  page197_i62
#CELL
  mstr_discrete cap *
  page197_i63
#ISCELL
  mstr_symbols p12v_nvdimm_ghj *
  page197_i64
#ISCELL
  mstr_symbols gnd *
  page197_i65
#CELL
  mstr_discrete cap *
  page197_i66
#ISCELL
  mstr_symbols p12v_nvdimm_ghj *
  page197_i67
#ISCELL
  mstr_symbols gnd *
  page197_i68
#CELL
  mstr_discrete cap *
  page197_i69
#ISCELL
  mstr_symbols gnd *
  page197_i70
#CELL
  mstr_discrete cap *
  page197_i71
#CELL
  mstr_discrete cap *
  page197_i72
#ISCELL
  mstr_symbols p12v_nvdimm_klm *
  page197_i73
#ISCELL
  mstr_symbols gnd *
  page197_i74
#CELL
  mstr_discrete cap *
  page197_i75
#ISCELL
  mstr_symbols p12v_nvdimm_klm *
  page197_i76
#ISCELL
  mstr_symbols gnd *
  page197_i77
#CELL
  mstr_discrete cap *
  page197_i78
#ISCELL
  mstr_symbols p12v_nvdimm_def *
  page197_i79
#CELL
  mstr_discrete cap *
  page197_i8
#ISCELL
  mstr_symbols gnd *
  page197_i80
#CELL
  mstr_discrete cap *
  page197_i81
#ISCELL
  mstr_symbols p12v_nvdimm_abc *
  page197_i82
#ISCELL
  mstr_symbols gnd *
  page197_i83
#CELL
  mstr_discrete cap *
  page197_i84
#ISCELL
  mstr_symbols p12v_nvdimm_abc *
  page197_i85
#ISCELL
  mstr_symbols p12v_nvdimm_def *
  page197_i86
#ISCELL
  mstr_symbols gnd *
  page197_i87
#CELL
  mstr_discrete cap *
  page197_i88
#ISCELL
  mstr_symbols p12v_nvdimm_def *
  page197_i89
#ISCELL
  mstr_symbols p12v_stby *
  page197_i9
#ISCELL
  mstr_symbols p12v_nvdimm_abc *
  page197_i90
#CELL
  w_hdl bsl308c-h6327-gp *
  page197_i91
#ISCELL
  mstr_symbols p12v_nvdimm_abc *
  page197_i92
#ISCELL
  mstr_misc dns *
  *
#ISCELL
  mstr_symbols intel_corp_bpage *
  *
#CELL
  mstr_vreg slg55021 *
  page198_i1
#ISCELL
  mstr_symbols gnd *
  page198_i12
#CELL
  mstr_vreg slg55021 *
  page198_i13
#ISCELL
  mstr_symbols p5v_stby *
  page198_i15
#ISCELL
  mstr_symbols gnd *
  page198_i18
#CELL
  mstr_vreg slg55021 *
  page198_i19
#ISCELL
  mstr_symbols p5v_stby *
  page198_i2
#ISCELL
  mstr_symbols p5v_stby *
  page198_i20
#ISCELL
  mstr_symbols p5v *
  page198_i21
#ISCELL
  mstr_symbols p12v *
  page198_i22
#ISCELL
  mstr_symbols p12v_stby *
  page198_i23
#CELL
  dev_discrete cap_a *
  page198_i24
#ISCELL
  mstr_symbols gnd *
  page198_i25
#CELL
  dev_discrete cap_a *
  page198_i26
#ISCELL
  mstr_symbols gnd *
  page198_i27
#CELL
  dev_discrete cap_a *
  page198_i28
#ISCELL
  mstr_symbols gnd *
  page198_i29
#ISCELL
  mstr_symbols gnd *
  page198_i3
#ISCELL
  mstr_standard offpage *
  page198_i32
#CELL
  dev_discrete cap_a *
  page198_i37
#CELL
  mstr_discrete cap *
  page198_i38
#ISCELL
  mstr_symbols gnd *
  page198_i39
#CELL
  mstr_discrete cap *
  page198_i40
#CELL
  dev_discrete cap_a *
  page198_i41
#ISCELL
  mstr_symbols gnd *
  page198_i42
#CELL
  dev_discrete cap_a *
  page198_i43
#CELL
  mstr_discrete cap *
  page198_i44
#ISCELL
  mstr_symbols gnd *
  page198_i45
#CELL
  dev_discrete cap_a *
  page198_i46
#CELL
  mstr_discrete cap *
  page198_i47
#ISCELL
  mstr_symbols gnd *
  page198_i48
#CELL
  dev_discrete cap_a *
  page198_i49
#CELL
  mstr_discrete cap *
  page198_i50
#ISCELL
  mstr_symbols gnd *
  page198_i51
#CELL
  dev_discrete cap_a *
  page198_i52
#CELL
  mstr_discrete cap *
  page198_i53
#ISCELL
  mstr_symbols gnd *
  page198_i54
#ISCELL
  mstr_standard offpage *
  page198_i58
#ISCELL
  mstr_standard offpage *
  page198_i59
#ISCELL
  mstr_symbols p3v3_stby *
  page198_i6
#CELL
  mstr_discrete cap *
  page198_i61
#ISCELL
  mstr_symbols gnd *
  page198_i63
#CELL
  dev_discrete cap_a *
  page198_i64
#ISCELL
  mstr_standard offpage *
  page198_i65
#ISCELL
  mstr_symbols gnd *
  page198_i66
#CELL
  dev_discrete cap_a *
  page198_i67
#ISCELL
  mstr_symbols p5v_stby *
  page198_i68
#CELL
  mstr_vreg slg55021 *
  page198_i69
#ISCELL
  mstr_symbols p3v3 *
  page198_i7
#ISCELL
  mstr_symbols gnd *
  page198_i70
#ISCELL
  mstr_symbols p12v_stby *
  page198_i73
#CELL
  mstr_discrete cap *
  page198_i74
#ISCELL
  mstr_symbols gnd *
  page198_i75
#CELL
  dev_discrete cap_a *
  page198_i76
#ISCELL
  mstr_symbols p12v_fan *
  page198_i77
#CELL
  mstr_discrete res *
  page198_i78
#ISCELL
  mstr_symbols p3v3_stby *
  page198_i79
#CELL
  mstr_discrete res *
  page198_i83
#ISCELL
  mstr_symbols gnd *
  page198_i84
#CELL
  mstr_discrete mosfet_n *
  page198_i85
#CELL
  mstr_discrete mosfet_n *
  page198_i86
#CELL
  mstr_discrete mosfet_n *
  page198_i87
#CELL
  mstr_discrete mosfet_n *
  page198_i88
#ISCELL
  mstr_symbols p5v_stby *
  page198_i9
#ISCELL
  mstr_misc dns *
  *
#ISCELL
  mstr_symbols design_note *
  *
#ISCELL
  mstr_symbols intel_corp_bpage *
  *
#CELL
  mstr_controller adm1278 *
  page199_i10
#CELL
  mstr_discrete res *
  page199_i100
#ISCELL
  mstr_symbols agnd0 *
  page199_i101
#CELL
  mstr_discrete res *
  page199_i102
#CELL
  dev_discrete cap_a *
  page199_i105
#ISCELL
  mstr_symbols agnd0 *
  page199_i106
#CELL
  dev_discrete cap_a *
  page199_i107
#CELL
  mstr_discrete res *
  page199_i108
#CELL
  mstr_discrete res *
  page199_i109
#ISCELL
  mstr_symbols gnd *
  page199_i11
#CELL
  mstr_discrete res *
  page199_i110
#ISCELL
  mstr_symbols agnd0 *
  page199_i112
#ISCELL
  mstr_symbols agnd0 *
  page199_i113
#ISCELL
  mstr_symbols agnd0 *
  page199_i115
#ISCELL
  mstr_symbols gnd *
  page199_i116
#ISCELL
  mstr_symbols agnd0 *
  page199_i117
#ISCELL
  mstr_symbols agnd0 *
  page199_i118
#CELL
  mstr_discrete cap *
  page199_i119
#CELL
  mstr_discrete res *
  page199_i12
#ISCELL
  mstr_symbols agnd0 *
  page199_i120
#CELL
  dev_discrete cap_a *
  page199_i121
#ISCELL
  mstr_symbols agnd0 *
  page199_i122
#ISCELL
  mstr_standard offpage *
  page199_i125
#ISCELL
  mstr_standard offpage *
  page199_i126
#ISCELL
  mstr_symbols gnd *
  page199_i128
#ISCELL
  mstr_standard offpage *
  page199_i129
#CELL
  mstr_discrete res *
  page199_i13
#CELL
  mstr_discrete fet_n *
  page199_i130
#CELL
  w_hdl clx-conn3a-1-gp *
  page199_i131
#CELL
  mstr_discrete cap *
  page199_i132
#ISCELL
  mstr_symbols gnd *
  page199_i133
#CELL
  mstr_discrete res *
  page199_i134
#CELL
  mstr_discrete res *
  page199_i135
#CELL
  mstr_discrete res *
  page199_i137
#CELL
  mstr_discrete res *
  page199_i138
#CELL
  mstr_discrete res *
  page199_i15
#CELL
  mstr_discrete res *
  page199_i16
#CELL
  mstr_discrete res *
  page199_i17
#ISCELL
  mstr_symbols agnd0 *
  page199_i18
#CELL
  mstr_discrete res *
  page199_i19
#CELL
  mstr_discrete res *
  page199_i2
#ISCELL
  mstr_symbols gnd *
  page199_i20
#ISCELL
  mstr_symbols agnd0 *
  page199_i21
#ISCELL
  mstr_symbols agnd0 *
  page199_i23
#CELL
  mstr_discrete cap *
  page199_i24
#CELL
  mstr_discrete res *
  page199_i26
#CELL
  mstr_discrete res *
  page199_i27
#CELL
  mstr_discrete res *
  page199_i28
#CELL
  mstr_discrete cap *
  page199_i3
#ISCELL
  mstr_standard offpage *
  page199_i30
#ISCELL
  mstr_standard offpage *
  page199_i31
#CELL
  mstr_discrete res *
  page199_i33
#ISCELL
  mstr_symbols agnd0 *
  page199_i34
#CELL
  mstr_discrete res *
  page199_i36
#CELL
  mstr_discrete res *
  page199_i38
#CELL
  mstr_discrete res *
  page199_i41
#CELL
  mstr_discrete res *
  page199_i43
#ISCELL
  mstr_symbols gnd *
  page199_i44
#ISCELL
  mstr_standard offpage *
  page199_i45
#ISCELL
  mstr_standard offpage *
  page199_i49
#ISCELL
  mstr_standard offpage *
  page199_i50
#ISCELL
  mstr_symbols agnd0 *
  page199_i52
#CELL
  dev_discrete cap_a *
  page199_i53
#CELL
  mstr_discrete res *
  page199_i54
#CELL
  mstr_discrete res *
  page199_i55
#ISCELL
  mstr_symbols agnd0 *
  page199_i56
#CELL
  mstr_discrete npn *
  page199_i58
#ISCELL
  mstr_standard offpage *
  page199_i63
#ISCELL
  mstr_standard offpage *
  page199_i64
#CELL
  mstr_discrete res *
  page199_i65
#CELL
  dev_discrete cap_a *
  page199_i67
#ISCELL
  mstr_symbols agnd0 *
  page199_i68
#ISCELL
  mstr_standard offpage *
  page199_i69
#CELL
  dev_discrete cap_a *
  page199_i7
#ISCELL
  mstr_standard offpage *
  page199_i71
#ISCELL
  mstr_standard offpage *
  page199_i72
#ISCELL
  mstr_standard offpage *
  page199_i73
#ISCELL
  mstr_standard offpage *
  page199_i74
#ISCELL
  mstr_symbols p12v_stby *
  page199_i75
#ISCELL
  mstr_symbols p12v_stby *
  page199_i76
#ISCELL
  mstr_symbols p12v_stby *
  page199_i77
#ISCELL
  mstr_symbols p12v_psu *
  page199_i79
#CELL
  mstr_discrete fet_n_dual *
  page199_i82
#ISCELL
  mstr_symbols agnd0 *
  page199_i83
#CELL
  mstr_discrete res *
  page199_i84
#CELL
  mstr_discrete res *
  page199_i85
#CELL
  mstr_discrete fet_n_dual *
  page199_i86
#CELL
  mstr_discrete res *
  page199_i87
#CELL
  mstr_discrete res *
  page199_i88
#ISCELL
  mstr_symbols agnd0 *
  page199_i89
#CELL
  mstr_discrete res *
  page199_i9
#ISCELL
  mstr_symbols p12v_psu *
  page199_i90
#CELL
  mstr_discrete res *
  page199_i92
#ISCELL
  mstr_standard offpage *
  page199_i98
#CELL
  mstr_discrete zener *
  page199_i99
#ISCELL
  mstr_misc dns *
  *
#ISCELL
  mstr_symbols intel_corp_bpage *
  *
#CELL
  mstr_ttl ttl1g126_a *
  page200_i103
#ISCELL
  mstr_symbols agnd0 *
  page200_i106
#CELL
  mstr_discrete res *
  page200_i108
#ISCELL
  mstr_symbols p12v_stby *
  page200_i109
#ISCELL
  mstr_symbols gnd *
  page200_i114
#ISCELL
  mstr_standard offpage *
  page200_i118
#ISCELL
  mstr_standard offpage *
  page200_i121
#ISCELL
  mstr_standard offpage *
  page200_i134
#ISCELL
  mstr_standard offpage *
  page200_i135
#ISCELL
  mstr_symbols p12v_stby *
  page200_i144
#ISCELL
  mstr_symbols agnd0 *
  page200_i147
#CELL
  mstr_discrete res *
  page200_i149
#ISCELL
  mstr_symbols p3v3_stby *
  page200_i150
#ISCELL
  mstr_standard offpage *
  page200_i153
#CELL
  mstr_discrete res *
  page200_i154
#CELL
  mstr_discrete cap *
  page200_i155
#ISCELL
  mstr_symbols gnd *
  page200_i156
#ISCELL
  mstr_symbols p3v3_stby *
  page200_i157
#CELL
  mstr_discrete res *
  page200_i158
#CELL
  mstr_vreg tps3700 *
  page200_i163
#CELL
  mstr_vreg tps3700 *
  page200_i170
#CELL
  mstr_discrete res *
  page200_i174
#CELL
  mstr_discrete res *
  page200_i175
#ISCELL
  mstr_symbols gnd *
  page200_i178
#ISCELL
  mstr_symbols gnd *
  page200_i179
#ISCELL
  mstr_symbols agnd0 *
  page200_i180
#ISCELL
  mstr_symbols agnd0 *
  page200_i181
#ISCELL
  mstr_symbols gnd *
  page200_i183
#ISCELL
  mstr_symbols p12v_stby *
  page200_i184
#CELL
  dev_discrete cap_a *
  page200_i185
#ISCELL
  mstr_symbols agnd0 *
  page200_i186
#CELL
  dev_discrete cap_a *
  page200_i187
#ISCELL
  mstr_symbols agnd0 *
  page200_i188
#ISCELL
  mstr_symbols p3v3_stby *
  page200_i190
#CELL
  mstr_discrete res *
  page200_i191
#CELL
  mstr_discrete res *
  page200_i192
#ISCELL
  mstr_symbols p3v3_stby *
  page200_i194
#CELL
  mstr_discrete fet_n_dual *
  page200_i196
#ISCELL
  mstr_symbols gnd *
  page200_i197
#CELL
  mstr_discrete fet_n_dual *
  page200_i199
#CELL
  mstr_vreg tps3700 *
  page200_i200
#CELL
  dev_discrete cap_a *
  page200_i201
#ISCELL
  mstr_symbols gnd *
  page200_i202
#CELL
  mstr_discrete fet_n *
  page200_i203
#CELL
  mstr_discrete res *
  page200_i204
#ISCELL
  mstr_symbols p3v3_stby *
  page200_i205
#ISCELL
  mstr_symbols gnd *
  page200_i206
#ISCELL
  mstr_standard offpage *
  page200_i207
#CELL
  mstr_discrete res *
  page200_i210
#ISCELL
  mstr_symbols p3v3_stby *
  page200_i211
#CELL
  mstr_discrete diode *
  page200_i213
#CELL
  mstr_discrete diode *
  page200_i214
#CELL
  mstr_discrete res *
  page200_i215
#ISCELL
  mstr_symbols p3v3_stby *
  page200_i216
#ISCELL
  mstr_symbols agnd0 *
  page200_i217
#CELL
  mstr_discrete res *
  page200_i218
#ISCELL
  mstr_symbols agnd0 *
  page200_i219
#CELL
  mstr_discrete diode *
  page200_i220
#ISCELL
  mstr_symbols gnd *
  page200_i221
#CELL
  mstr_discrete res *
  page200_i222
#ISCELL
  mstr_symbols p12v_stby *
  page200_i223
#ISCELL
  mstr_standard offpage *
  page200_i224
#CELL
  mstr_discrete fet_n *
  page200_i225
#ISCELL
  mstr_standard offpage *
  page200_i226
#ISCELL
  mstr_symbols gnd *
  page200_i227
#CELL
  w_hdl sc22p50v2jn-4gp *
  page200_i235
#CELL
  w_hdl sc22p50v2jn-4gp *
  page200_i236
#ISCELL
  mstr_symbols agnd0 *
  page200_i237
#ISCELL
  mstr_symbols agnd0 *
  page200_i238
#ISCELL
  mstr_standard offpage *
  page200_i241
#CELL
  mstr_discrete res *
  page200_i243
#CELL
  mstr_discrete res *
  page200_i244
#CELL
  mstr_discrete res *
  page200_i246
#CELL
  w_hdl 270kr2f-gp *
  page200_i249
#CELL
  w_hdl 232kr2f-2-gp *
  page200_i250
#CELL
  mstr_discrete res *
  page200_i251
#CELL
  mstr_discrete res *
  page200_i252
#CELL
  mstr_discrete res *
  page200_i253
#CELL
  dev_discrete cap_a *
  page200_i36
#ISCELL
  mstr_standard offpage *
  page200_i37
#ISCELL
  mstr_standard offpage *
  page200_i38
#ISCELL
  mstr_symbols agnd0 *
  page200_i39
#CELL
  dev_discrete cap_a *
  page200_i40
#ISCELL
  mstr_symbols agnd0 *
  page200_i41
#CELL
  dev_discrete cap_a *
  page200_i42
#CELL
  mstr_discrete res *
  page200_i43
#CELL
  mstr_discrete res *
  page200_i44
#ISCELL
  mstr_standard offpage *
  page200_i45
#ISCELL
  mstr_standard offpage *
  page200_i46
#CELL
  mstr_discrete res *
  page200_i47
#CELL
  mstr_discrete res *
  page200_i48
#CELL
  mstr_discrete res_pwr *
  page200_i49
#CELL
  mstr_discrete res_pwr *
  page200_i50
#CELL
  mstr_discrete res *
  page200_i51
#CELL
  mstr_discrete res *
  page200_i52
#ISCELL
  mstr_symbols p12v_psu *
  page200_i53
#CELL
  mstr_discrete mosfetn_1d3s *
  page200_i54
#ISCELL
  mstr_standard offpage *
  page200_i55
#CELL
  mstr_discrete res *
  page200_i56
#CELL
  mstr_discrete mosfetn_1d3s *
  page200_i57
#CELL
  mstr_discrete res *
  page200_i58
#CELL
  mstr_discrete mosfetn_1d3s *
  page200_i59
#CELL
  mstr_discrete res *
  page200_i60
#ISCELL
  mstr_symbols p12v_stby *
  page200_i64
#CELL
  mstr_discrete res *
  page200_i70
#CELL
  mstr_discrete res *
  page200_i71
#ISCELL
  mstr_standard offpage *
  page200_i72
#ISCELL
  mstr_symbols p3v3_stby *
  page200_i78
#CELL
  mstr_discrete res *
  page200_i86
#ISCELL
  mstr_standard offpage *
  page200_i92
#ISCELL
  mstr_standard offpage *
  page200_i94
#ISCELL
  mstr_misc dns *
  *
#ISCELL
  mstr_symbols design_note *
  *
#ISCELL
  mstr_symbols intel_corp_bpage *
  *
#ISCELL
  mstr_standard offpage *
  page201_i1
#ISCELL
  mstr_standard offpage *
  page201_i10
#CELL
  mstr_discrete res *
  page201_i102
#CELL
  mstr_discrete res *
  page201_i103
#CELL
  mstr_discrete res *
  page201_i109
#ISCELL
  mstr_standard offpage *
  page201_i11
#CELL
  mstr_discrete res *
  page201_i110
#CELL
  mstr_discrete res *
  page201_i111
#ISCELL
  mstr_symbols p3v3_stby *
  page201_i112
#ISCELL
  mstr_symbols p3v3_stby *
  page201_i113
#ISCELL
  mstr_symbols p3v3_stby *
  page201_i115
#CELL
  mstr_discrete res *
  page201_i116
#ISCELL
  mstr_standard offpage *
  page201_i118
#ISCELL
  mstr_standard offpage *
  page201_i12
#CELL
  mstr_discrete res *
  page201_i120
#CELL
  mstr_discrete res *
  page201_i121
#ISCELL
  mstr_symbols gnd *
  page201_i123
#CELL
  mstr_discrete res *
  page201_i124
#CELL
  mstr_discrete cap *
  page201_i125
#ISCELL
  mstr_symbols gnd *
  page201_i126
#CELL
  mstr_discrete res *
  page201_i127
#CELL
  mstr_discrete res *
  page201_i128
#CELL
  mstr_discrete res *
  page201_i131
#CELL
  mstr_discrete res *
  page201_i132
#ISCELL
  mstr_standard offpage *
  page201_i14
#ISCELL
  mstr_standard offpage *
  page201_i15
#CELL
  mstr_controller pxe1610b *
  page201_i155
#CELL
  w_hdl sc22p50v2jn-4gp *
  page201_i168
#CELL
  w_hdl sc22p50v2jn-4gp *
  page201_i169
#ISCELL
  mstr_standard offpage *
  page201_i17
#CELL
  w_hdl sc22p50v2jn-4gp *
  page201_i170
#CELL
  w_hdl sc22p50v2jn-4gp *
  page201_i171
#CELL
  w_hdl sc22p50v2jn-4gp *
  page201_i172
#CELL
  w_hdl sc22p50v2jn-4gp *
  page201_i173
#ISCELL
  mstr_symbols pvccio_cpu0 *
  page201_i18
#CELL
  mstr_discrete res *
  page201_i180
#CELL
  mstr_discrete res *
  page201_i182
#CELL
  mstr_discrete res *
  page201_i183
#CELL
  mstr_discrete res *
  page201_i184
#CELL
  mstr_discrete res *
  page201_i185
#CELL
  mstr_discrete res *
  page201_i186
#CELL
  mstr_discrete res *
  page201_i187
#CELL
  mstr_discrete res *
  page201_i189
#CELL
  mstr_discrete res *
  page201_i190
#CELL
  w_hdl pin-con3-27-gp *
  page201_i191
#CELL
  dev_discrete cap_a *
  page201_i192
#ISCELL
  mstr_standard offpage *
  page201_i2
#CELL
  mstr_discrete res *
  page201_i22
#CELL
  mstr_discrete res *
  page201_i25
#CELL
  mstr_discrete res *
  page201_i26
#CELL
  mstr_discrete res *
  page201_i27
#ISCELL
  mstr_symbols gnd *
  page201_i29
#ISCELL
  mstr_standard offpage *
  page201_i3
#CELL
  dev_discrete cap_a *
  page201_i30
#CELL
  dev_discrete cap_a *
  page201_i32
#ISCELL
  mstr_symbols gnd *
  page201_i33
#ISCELL
  mstr_symbols gnd *
  page201_i35
#ISCELL
  mstr_symbols gnd *
  page201_i36
#CELL
  dev_discrete cap_a *
  page201_i37
#ISCELL
  mstr_symbols gnd *
  page201_i38
#CELL
  dev_discrete cap_a *
  page201_i39
#ISCELL
  mstr_standard offpage *
  page201_i4
#CELL
  mstr_discrete res *
  page201_i40
#ISCELL
  mstr_symbols gnd *
  page201_i48
#ISCELL
  mstr_standard offpage *
  page201_i5
#ISCELL
  mstr_symbols gnd *
  page201_i50
#ISCELL
  mstr_symbols pvccio_cpu0 *
  page201_i51
#ISCELL
  mstr_symbols vcc_core *
  page201_i53
#CELL
  mstr_discrete res *
  page201_i54
#CELL
  mstr_discrete res *
  page201_i55
#CELL
  mstr_discrete res *
  page201_i56
#ISCELL
  mstr_symbols gnd *
  page201_i58
#ISCELL
  mstr_standard offpage *
  page201_i6
#ISCELL
  mstr_symbols gnd *
  page201_i61
#CELL
  mstr_discrete cap *
  page201_i64
#CELL
  mstr_discrete cap *
  page201_i66
#ISCELL
  mstr_symbols gnd *
  page201_i67
#CELL
  mstr_discrete cap *
  page201_i68
#ISCELL
  mstr_symbols gnd *
  page201_i69
#ISCELL
  mstr_standard offpage *
  page201_i7
#CELL
  mstr_discrete cap *
  page201_i70
#ISCELL
  mstr_standard offpage *
  page201_i73
#ISCELL
  mstr_standard offpage *
  page201_i74
#ISCELL
  mstr_standard offpage *
  page201_i75
#ISCELL
  mstr_standard offpage *
  page201_i76
#ISCELL
  mstr_standard offpage *
  page201_i77
#ISCELL
  mstr_standard offpage *
  page201_i78
#ISCELL
  mstr_standard offpage *
  page201_i79
#ISCELL
  mstr_standard offpage *
  page201_i8
#ISCELL
  mstr_standard offpage *
  page201_i80
#ISCELL
  mstr_standard offpage *
  page201_i82
#ISCELL
  mstr_standard offpage *
  page201_i83
#ISCELL
  mstr_standard offpage *
  page201_i84
#ISCELL
  mstr_standard offpage *
  page201_i85
#ISCELL
  mstr_standard offpage *
  page201_i87
#ISCELL
  mstr_standard offpage *
  page201_i88
#ISCELL
  mstr_standard offpage *
  page201_i89
#ISCELL
  mstr_standard offpage *
  page201_i9
#ISCELL
  mstr_standard offpage *
  page201_i90
#ISCELL
  mstr_standard offpage *
  page201_i91
#ISCELL
  mstr_standard offpage *
  page201_i92
#ISCELL
  mstr_standard offpage *
  page201_i93
#ISCELL
  mstr_standard offpage *
  page201_i94
#ISCELL
  mstr_standard offpage *
  page201_i96
#ISCELL
  mstr_standard offpage *
  page201_i97
#CELL
  mstr_discrete res *
  page201_i98
#ISCELL
  mstr_misc dns *
  *
#ISCELL
  mstr_symbols intel_corp_bpage *
  *
#ISCELL
  mstr_standard offpage *
  page202_i1
#ISCELL
  mstr_standard offpage *
  page202_i10
#CELL
  mstr_discrete res *
  page202_i101
#CELL
  mstr_discrete res *
  page202_i102
#CELL
  mstr_discrete res *
  page202_i107
#CELL
  mstr_discrete res *
  page202_i108
#CELL
  w_hdl ind-120nh-30-gp *
  page202_i109
#ISCELL
  mstr_standard offpage *
  page202_i11
#CELL
  w_hdl ind-120nh-30-gp *
  page202_i110
#CELL
  w_hdl sc1u10v2kx-4-gp *
  page202_i111
#CELL
  w_hdl sc1u10v2kx-4-gp *
  page202_i112
#CELL
  w_hdl 1r3f-gp *
  page202_i114
#CELL
  w_hdl 1r3f-gp *
  page202_i115
#ISCELL
  mstr_standard offpage *
  page202_i12
#ISCELL
  mstr_symbols gnd *
  page202_i13
#CELL
  mstr_discrete cap *
  page202_i18
#ISCELL
  mstr_standard offpage *
  page202_i2
#CELL
  mstr_discrete cap *
  page202_i22
#CELL
  mstr_discrete cap *
  page202_i24
#ISCELL
  mstr_symbols pvccin_cpu0 *
  page202_i26
#CELL
  dev_discrete cap_a *
  page202_i27
#ISCELL
  mstr_symbols gnd *
  page202_i28
#ISCELL
  mstr_standard offpage *
  page202_i3
#ISCELL
  mstr_symbols gnd *
  page202_i30
#CELL
  mstr_discrete cap *
  page202_i32
#CELL
  mstr_discrete cap *
  page202_i34
#CELL
  dev_discrete cap_a *
  page202_i35
#CELL
  mstr_discrete cap *
  page202_i36
#CELL
  mstr_discrete cap *
  page202_i37
#CELL
  mstr_discrete cap *
  page202_i38
#ISCELL
  mstr_symbols pvccin_cpu0 *
  page202_i4
#ISCELL
  mstr_standard offpage *
  page202_i40
#ISCELL
  mstr_symbols vcc_core *
  page202_i41
#CELL
  mstr_discrete cap *
  page202_i42
#ISCELL
  mstr_symbols gnd *
  page202_i43
#ISCELL
  mstr_symbols vcc_core *
  page202_i44
#CELL
  mstr_discrete cap *
  page202_i45
#CELL
  dev_discrete cap_a *
  page202_i46
#CELL
  mstr_discrete cap *
  page202_i47
#CELL
  mstr_discrete cap *
  page202_i48
#CELL
  mstr_discrete cap *
  page202_i49
#ISCELL
  mstr_standard offpage *
  page202_i50
#CELL
  mstr_discrete cap *
  page202_i51
#ISCELL
  mstr_symbols gnd *
  page202_i52
#ISCELL
  mstr_symbols p5v_stby *
  page202_i59
#ISCELL
  mstr_symbols p5v_stby *
  page202_i60
#CELL
  dev_discrete cap_a *
  page202_i61
#CELL
  dev_discrete cap_a *
  page202_i62
#CELL
  mstr_discrete ir354xx *
  page202_i63
#CELL
  mstr_discrete ir354xx *
  page202_i64
#CELL
  mstr_discrete res *
  page202_i65
#ISCELL
  mstr_symbols gnd *
  page202_i66
#CELL
  mstr_discrete res *
  page202_i67
#ISCELL
  mstr_symbols gnd *
  page202_i68
#CELL
  dev_discrete cap_a *
  page202_i70
#ISCELL
  mstr_symbols gnd *
  page202_i71
#ISCELL
  mstr_symbols gnd *
  page202_i73
#ISCELL
  mstr_symbols gnd *
  page202_i77
#CELL
  mstr_discrete cap *
  page202_i78
#ISCELL
  mstr_symbols gnd *
  page202_i8
#ISCELL
  mstr_symbols gnd *
  page202_i80
#CELL
  dev_discrete cap_a *
  page202_i81
#ISCELL
  mstr_symbols gnd *
  page202_i84
#ISCELL
  mstr_symbols gnd *
  page202_i86
#CELL
  mstr_discrete cap *
  page202_i87
#CELL
  dev_discrete cap_a *
  page202_i9
#CELL
  mstr_discrete cap *
  page202_i97
#CELL
  mstr_discrete cap *
  page202_i98
#ISCELL
  mstr_misc dns *
  *
#ISCELL
  mstr_symbols intel_corp_bpage *
  *
#CELL
  mstr_discrete cap *
  page203_i1
#ISCELL
  mstr_symbols gnd *
  page203_i100
#ISCELL
  mstr_symbols gnd *
  page203_i103
#ISCELL
  mstr_symbols gnd *
  page203_i104
#ISCELL
  mstr_symbols gnd *
  page203_i107
#CELL
  mstr_discrete cap *
  page203_i108
#ISCELL
  mstr_symbols pvccin_cpu0 *
  page203_i109
#CELL
  mstr_discrete cap *
  page203_i118
#CELL
  mstr_discrete cap *
  page203_i119
#ISCELL
  mstr_symbols pvccin_cpu0 *
  page203_i12
#CELL
  mstr_discrete res *
  page203_i122
#CELL
  mstr_discrete res *
  page203_i123
#CELL
  mstr_discrete res *
  page203_i128
#CELL
  mstr_discrete res *
  page203_i129
#CELL
  w_hdl ind-120nh-30-gp *
  page203_i130
#CELL
  w_hdl ind-120nh-30-gp *
  page203_i131
#CELL
  w_hdl sc1u10v2kx-4-gp *
  page203_i132
#CELL
  w_hdl sc1u10v2kx-4-gp *
  page203_i133
#CELL
  w_hdl 1r3f-gp *
  page203_i134
#CELL
  w_hdl 1r3f-gp *
  page203_i135
#ISCELL
  mstr_symbols gnd *
  page203_i14
#CELL
  mstr_discrete capp *
  page203_i16
#ISCELL
  mstr_symbols gnd *
  page203_i17
#CELL
  mstr_discrete capp *
  page203_i18
#ISCELL
  mstr_standard offpage *
  page203_i19
#CELL
  mstr_discrete cap *
  page203_i2
#ISCELL
  mstr_standard offpage *
  page203_i20
#ISCELL
  mstr_standard offpage *
  page203_i21
#CELL
  dev_discrete cap_a *
  page203_i25
#ISCELL
  mstr_symbols gnd *
  page203_i26
#ISCELL
  mstr_symbols gnd *
  page203_i27
#CELL
  mstr_discrete capp *
  page203_i28
#CELL
  mstr_discrete capp *
  page203_i29
#CELL
  mstr_discrete cap *
  page203_i3
#CELL
  mstr_discrete capp *
  page203_i30
#CELL
  mstr_discrete capp *
  page203_i32
#ISCELL
  mstr_symbols pvccin_cpu0 *
  page203_i33
#CELL
  mstr_discrete capp *
  page203_i34
#ISCELL
  mstr_symbols vcc_core *
  page203_i39
#CELL
  mstr_discrete cap *
  page203_i40
#CELL
  mstr_discrete cap *
  page203_i42
#CELL
  mstr_discrete cap *
  page203_i45
#CELL
  dev_discrete cap_a *
  page203_i46
#CELL
  mstr_discrete cap *
  page203_i47
#CELL
  mstr_discrete cap *
  page203_i48
#ISCELL
  mstr_standard offpage *
  page203_i5
#CELL
  mstr_discrete cap *
  page203_i51
#CELL
  dev_discrete cap_a *
  page203_i52
#CELL
  mstr_discrete cap *
  page203_i53
#CELL
  mstr_discrete cap *
  page203_i54
#ISCELL
  mstr_standard offpage *
  page203_i55
#ISCELL
  mstr_symbols gnd *
  page203_i56
#CELL
  mstr_discrete cap *
  page203_i57
#CELL
  mstr_discrete cap *
  page203_i58
#CELL
  mstr_discrete cap *
  page203_i59
#ISCELL
  mstr_standard offpage *
  page203_i6
#ISCELL
  mstr_standard offpage *
  page203_i60
#ISCELL
  mstr_symbols vcc_core *
  page203_i61
#ISCELL
  mstr_symbols gnd *
  page203_i62
#ISCELL
  mstr_symbols gnd *
  page203_i63
#ISCELL
  mstr_symbols p5v_stby *
  page203_i64
#ISCELL
  mstr_symbols p5v_stby *
  page203_i65
#CELL
  dev_discrete cap_a *
  page203_i66
#CELL
  mstr_discrete res *
  page203_i67
#CELL
  dev_discrete cap_a *
  page203_i68
#CELL
  dev_discrete cap_a *
  page203_i69
#ISCELL
  mstr_standard offpage *
  page203_i7
#CELL
  mstr_discrete ir354xx *
  page203_i70
#CELL
  mstr_discrete ir354xx *
  page203_i71
#CELL
  mstr_discrete res *
  page203_i89
#ISCELL
  mstr_symbols gnd *
  page203_i90
#CELL
  mstr_discrete res *
  page203_i91
#ISCELL
  mstr_symbols gnd *
  page203_i92
#CELL
  dev_discrete cap_a *
  page203_i93
#ISCELL
  mstr_symbols gnd *
  page203_i94
#CELL
  dev_discrete cap_a *
  page203_i96
#ISCELL
  mstr_symbols gnd *
  page203_i97
#CELL
  mstr_discrete cap *
  page203_i99
#ISCELL
  mstr_misc dns *
  *
#ISCELL
  mstr_symbols design_note *
  *
#ISCELL
  mstr_symbols intel_corp_bpage *
  *
#ISCELL
  mstr_standard offpage *
  page204_i1
#CELL
  mstr_discrete res *
  page204_i103
#CELL
  w_hdl ind-120nh-30-gp *
  page204_i104
#CELL
  w_hdl ind-80nh-1-gp *
  page204_i105
#CELL
  w_hdl sc1u10v2kx-4-gp *
  page204_i113
#CELL
  w_hdl 1r3f-gp *
  page204_i114
#ISCELL
  mstr_symbols gnd *
  page204_i13
#CELL
  mstr_discrete cap *
  page204_i18
#ISCELL
  mstr_standard offpage *
  page204_i2
#CELL
  mstr_discrete cap *
  page204_i22
#ISCELL
  mstr_standard offpage *
  page204_i3
#CELL
  mstr_discrete cap *
  page204_i34
#CELL
  dev_discrete cap_a *
  page204_i35
#CELL
  mstr_discrete cap *
  page204_i36
#CELL
  mstr_discrete cap *
  page204_i37
#CELL
  mstr_discrete cap *
  page204_i38
#ISCELL
  mstr_symbols pvccin_cpu0 *
  page204_i4
#ISCELL
  mstr_standard offpage *
  page204_i40
#ISCELL
  mstr_symbols vcc_core *
  page204_i41
#CELL
  mstr_discrete cap *
  page204_i42
#ISCELL
  mstr_symbols gnd *
  page204_i43
#ISCELL
  mstr_symbols vcc_core *
  page204_i44
#CELL
  mstr_discrete capp *
  page204_i48
#ISCELL
  mstr_symbols gnd *
  page204_i49
#CELL
  mstr_discrete capp *
  page204_i50
#ISCELL
  mstr_standard offpage *
  page204_i56
#ISCELL
  mstr_standard offpage *
  page204_i57
#ISCELL
  mstr_symbols pvccin_cpu0 *
  page204_i58
#ISCELL
  mstr_symbols gnd *
  page204_i59
#CELL
  mstr_discrete res *
  page204_i60
#CELL
  mstr_discrete res *
  page204_i61
#CELL
  mstr_discrete res *
  page204_i62
#CELL
  mstr_discrete res *
  page204_i63
#CELL
  mstr_discrete res *
  page204_i64
#ISCELL
  mstr_standard offpage *
  page204_i65
#ISCELL
  mstr_standard offpage *
  page204_i66
#CELL
  mstr_discrete capp *
  page204_i67
#ISCELL
  mstr_symbols p12v_stby *
  page204_i68
#ISCELL
  mstr_symbols p5v_stby *
  page204_i69
#CELL
  dev_discrete cap_a *
  page204_i70
#CELL
  mstr_discrete ir354xx *
  page204_i71
#ISCELL
  mstr_symbols gnd *
  page204_i8
#CELL
  mstr_discrete res *
  page204_i83
#ISCELL
  mstr_symbols gnd *
  page204_i84
#CELL
  dev_discrete cap_a *
  page204_i85
#ISCELL
  mstr_symbols gnd *
  page204_i86
#CELL
  mstr_discrete cap *
  page204_i88
#ISCELL
  mstr_symbols gnd *
  page204_i89
#CELL
  dev_discrete cap_a *
  page204_i9
#ISCELL
  mstr_symbols gnd *
  page204_i92
#CELL
  mstr_discrete cap *
  page204_i97
#CELL
  mstr_discrete res *
  page204_i99
#ISCELL
  mstr_misc dns *
  *
#ISCELL
  mstr_symbols design_note *
  *
#ISCELL
  mstr_symbols intel_corp_bpage *
  *
#ISCELL
  mstr_standard offpage *
  page205_i1
#ISCELL
  mstr_symbols pvsa_cpu0 *
  page205_i11
#CELL
  mstr_discrete capp *
  page205_i12
#ISCELL
  mstr_symbols gnd *
  page205_i13
#CELL
  mstr_discrete capp *
  page205_i14
#ISCELL
  mstr_symbols gnd *
  page205_i15
#CELL
  mstr_discrete cap *
  page205_i16
#ISCELL
  mstr_standard offpage *
  page205_i2
#CELL
  mstr_discrete cap *
  page205_i20
#ISCELL
  mstr_standard offpage *
  page205_i22
#ISCELL
  mstr_symbols pvsa_cpu0 *
  page205_i23
#CELL
  mstr_discrete res *
  page205_i24
#CELL
  mstr_discrete cap *
  page205_i25
#CELL
  mstr_discrete res *
  page205_i26
#ISCELL
  mstr_standard offpage *
  page205_i27
#ISCELL
  mstr_symbols gnd *
  page205_i28
#CELL
  mstr_discrete res *
  page205_i29
#ISCELL
  mstr_standard offpage *
  page205_i3
#CELL
  mstr_discrete res *
  page205_i30
#CELL
  dev_discrete cap_a *
  page205_i31
#CELL
  mstr_discrete cap *
  page205_i32
#CELL
  mstr_discrete cap *
  page205_i33
#CELL
  mstr_discrete cap *
  page205_i34
#CELL
  mstr_discrete cap *
  page205_i35
#ISCELL
  mstr_symbols vcc_core *
  page205_i36
#CELL
  mstr_discrete res *
  page205_i37
#ISCELL
  mstr_standard offpage *
  page205_i38
#ISCELL
  mstr_symbols gnd *
  page205_i39
#ISCELL
  mstr_symbols pvsa_cpu0 *
  page205_i4
#ISCELL
  mstr_standard offpage *
  page205_i40
#ISCELL
  mstr_standard offpage *
  page205_i41
#ISCELL
  mstr_symbols p5v_stby *
  page205_i42
#CELL
  dev_discrete cap_a *
  page205_i43
#CELL
  mstr_discrete res *
  page205_i45
#CELL
  mstr_discrete ir354xx *
  page205_i46
#CELL
  dev_discrete cap_a *
  page205_i5
#ISCELL
  mstr_symbols gnd *
  page205_i6
#CELL
  mstr_discrete res *
  page205_i62
#ISCELL
  mstr_symbols gnd *
  page205_i63
#CELL
  mstr_discrete cap *
  page205_i65
#ISCELL
  mstr_symbols gnd *
  page205_i66
#ISCELL
  mstr_symbols gnd *
  page205_i67
#CELL
  dev_discrete cap_a *
  page205_i69
#ISCELL
  mstr_symbols gnd *
  page205_i70
#CELL
  mstr_discrete cap *
  page205_i76
#CELL
  mstr_discrete res *
  page205_i78
#CELL
  mstr_discrete res *
  page205_i81
#CELL
  w_hdl ind-300nh-20-gp *
  page205_i82
#CELL
  w_hdl sc1u10v2kx-4-gp *
  page205_i83
#CELL
  w_hdl 1r3f-gp *
  page205_i84
#ISCELL
  mstr_misc dns *
  *
#ISCELL
  mstr_symbols design_note *
  *
#ISCELL
  mstr_symbols intel_corp_bpage *
  *
#ISCELL
  mstr_symbols pvccio_cpu1 *
  page206_i1
#ISCELL
  mstr_standard offpage *
  page206_i10
#ISCELL
  mstr_standard offpage *
  page206_i101
#ISCELL
  mstr_standard offpage *
  page206_i102
#ISCELL
  mstr_symbols p3v3_stby *
  page206_i103
#ISCELL
  mstr_symbols p3v3_stby *
  page206_i104
#ISCELL
  mstr_standard offpage *
  page206_i109
#ISCELL
  mstr_standard offpage *
  page206_i11
#CELL
  mstr_discrete res *
  page206_i111
#CELL
  mstr_discrete res *
  page206_i112
#CELL
  mstr_discrete res *
  page206_i113
#CELL
  mstr_discrete cap *
  page206_i114
#ISCELL
  mstr_symbols gnd *
  page206_i115
#CELL
  mstr_discrete res *
  page206_i116
#CELL
  mstr_discrete res *
  page206_i117
#CELL
  mstr_discrete res *
  page206_i119
#ISCELL
  mstr_standard offpage *
  page206_i12
#CELL
  mstr_discrete res *
  page206_i120
#ISCELL
  mstr_standard offpage *
  page206_i13
#CELL
  mstr_controller pxe1610b *
  page206_i130
#CELL
  w_hdl sc22p50v2jn-4gp *
  page206_i137
#CELL
  w_hdl sc22p50v2jn-4gp *
  page206_i138
#CELL
  w_hdl sc22p50v2jn-4gp *
  page206_i139
#ISCELL
  mstr_standard offpage *
  page206_i14
#CELL
  w_hdl sc22p50v2jn-4gp *
  page206_i140
#CELL
  w_hdl sc22p50v2jn-4gp *
  page206_i141
#CELL
  w_hdl sc22p50v2jn-4gp *
  page206_i142
#CELL
  mstr_discrete res *
  page206_i149
#ISCELL
  mstr_standard offpage *
  page206_i15
#CELL
  mstr_discrete res *
  page206_i150
#CELL
  mstr_discrete res *
  page206_i151
#CELL
  mstr_discrete res *
  page206_i152
#CELL
  mstr_discrete res *
  page206_i153
#CELL
  mstr_discrete res *
  page206_i154
#CELL
  mstr_discrete res *
  page206_i155
#CELL
  dev_discrete cap_a *
  page206_i156
#ISCELL
  mstr_standard offpage *
  page206_i16
#ISCELL
  mstr_standard offpage *
  page206_i17
#ISCELL
  mstr_standard offpage *
  page206_i18
#ISCELL
  mstr_standard offpage *
  page206_i23
#ISCELL
  mstr_standard offpage *
  page206_i24
#ISCELL
  mstr_standard offpage *
  page206_i26
#CELL
  dev_discrete cap_a *
  page206_i29
#ISCELL
  mstr_symbols gnd *
  page206_i30
#CELL
  dev_discrete cap_a *
  page206_i31
#ISCELL
  mstr_symbols gnd *
  page206_i32
#CELL
  mstr_discrete res *
  page206_i33
#CELL
  mstr_discrete res *
  page206_i34
#CELL
  mstr_discrete res *
  page206_i35
#CELL
  mstr_discrete res *
  page206_i36
#CELL
  mstr_discrete res *
  page206_i37
#CELL
  mstr_discrete res *
  page206_i38
#CELL
  mstr_discrete res *
  page206_i4
#ISCELL
  mstr_symbols gnd *
  page206_i40
#CELL
  dev_discrete cap_a *
  page206_i41
#CELL
  dev_discrete cap_a *
  page206_i42
#ISCELL
  mstr_symbols gnd *
  page206_i43
#ISCELL
  mstr_symbols gnd *
  page206_i44
#CELL
  mstr_discrete res *
  page206_i46
#ISCELL
  mstr_symbols pvccio_cpu1 *
  page206_i47
#ISCELL
  mstr_symbols vcc_core *
  page206_i48
#CELL
  mstr_discrete res *
  page206_i49
#ISCELL
  mstr_standard offpage *
  page206_i5
#ISCELL
  mstr_standard offpage *
  page206_i50
#CELL
  mstr_discrete res *
  page206_i53
#CELL
  mstr_discrete res *
  page206_i54
#CELL
  mstr_discrete res *
  page206_i56
#ISCELL
  mstr_symbols gnd *
  page206_i57
#CELL
  mstr_discrete res *
  page206_i6
#ISCELL
  mstr_symbols gnd *
  page206_i65
#ISCELL
  mstr_symbols gnd *
  page206_i67
#CELL
  mstr_discrete cap *
  page206_i68
#CELL
  mstr_discrete cap *
  page206_i69
#ISCELL
  mstr_symbols gnd *
  page206_i70
#CELL
  mstr_discrete cap *
  page206_i71
#ISCELL
  mstr_symbols gnd *
  page206_i72
#ISCELL
  mstr_symbols gnd *
  page206_i74
#CELL
  mstr_discrete res *
  page206_i77
#CELL
  mstr_discrete cap *
  page206_i78
#CELL
  mstr_discrete res *
  page206_i79
#ISCELL
  mstr_standard offpage *
  page206_i8
#ISCELL
  mstr_standard offpage *
  page206_i80
#ISCELL
  mstr_standard offpage *
  page206_i81
#ISCELL
  mstr_standard offpage *
  page206_i82
#ISCELL
  mstr_standard offpage *
  page206_i83
#ISCELL
  mstr_standard offpage *
  page206_i84
#ISCELL
  mstr_standard offpage *
  page206_i85
#ISCELL
  mstr_standard offpage *
  page206_i86
#ISCELL
  mstr_standard offpage *
  page206_i87
#ISCELL
  mstr_standard offpage *
  page206_i88
#ISCELL
  mstr_standard offpage *
  page206_i89
#ISCELL
  mstr_standard offpage *
  page206_i9
#ISCELL
  mstr_standard offpage *
  page206_i90
#ISCELL
  mstr_standard offpage *
  page206_i91
#ISCELL
  mstr_standard offpage *
  page206_i92
#ISCELL
  mstr_standard offpage *
  page206_i94
#ISCELL
  mstr_standard offpage *
  page206_i95
#ISCELL
  mstr_standard offpage *
  page206_i96
#ISCELL
  mstr_standard offpage *
  page206_i97
#ISCELL
  mstr_standard offpage *
  page206_i98
#ISCELL
  mstr_standard offpage *
  page206_i99
#ISCELL
  mstr_misc dns *
  *
#ISCELL
  mstr_symbols intel_corp_bpage *
  *
#ISCELL
  mstr_standard offpage *
  page207_i1
#CELL
  mstr_discrete res *
  page207_i100
#CELL
  mstr_discrete res *
  page207_i105
#CELL
  mstr_discrete res *
  page207_i106
#CELL
  w_hdl ind-120nh-30-gp *
  page207_i107
#CELL
  w_hdl ind-120nh-30-gp *
  page207_i108
#CELL
  w_hdl sc1u10v2kx-4-gp *
  page207_i109
#ISCELL
  mstr_standard offpage *
  page207_i11
#CELL
  w_hdl sc1u10v2kx-4-gp *
  page207_i110
#CELL
  w_hdl 1r3f-gp *
  page207_i111
#CELL
  w_hdl 1r3f-gp *
  page207_i112
#CELL
  mstr_discrete ir354xx *
  page207_i113
#ISCELL
  mstr_standard offpage *
  page207_i13
#ISCELL
  mstr_symbols pvccin_cpu1 *
  page207_i14
#ISCELL
  mstr_symbols gnd *
  page207_i17
#CELL
  dev_discrete cap_a *
  page207_i18
#ISCELL
  mstr_symbols gnd *
  page207_i19
#CELL
  mstr_discrete ir354xx *
  page207_i20
#ISCELL
  mstr_symbols gnd *
  page207_i23
#ISCELL
  mstr_symbols vcc_core *
  page207_i27
#CELL
  mstr_discrete cap *
  page207_i28
#ISCELL
  mstr_standard offpage *
  page207_i3
#CELL
  mstr_discrete cap *
  page207_i30
#CELL
  mstr_discrete cap *
  page207_i32
#CELL
  dev_discrete cap_a *
  page207_i33
#CELL
  mstr_discrete cap *
  page207_i34
#CELL
  mstr_discrete cap *
  page207_i36
#CELL
  mstr_discrete cap *
  page207_i38
#CELL
  mstr_discrete cap *
  page207_i40
#CELL
  dev_discrete cap_a *
  page207_i41
#CELL
  mstr_discrete cap *
  page207_i42
#CELL
  mstr_discrete cap *
  page207_i43
#CELL
  mstr_discrete cap *
  page207_i44
#ISCELL
  mstr_standard offpage *
  page207_i45
#CELL
  mstr_discrete cap *
  page207_i48
#ISCELL
  mstr_symbols gnd *
  page207_i49
#CELL
  mstr_discrete cap *
  page207_i50
#CELL
  mstr_discrete cap *
  page207_i51
#ISCELL
  mstr_standard offpage *
  page207_i52
#ISCELL
  mstr_symbols vcc_core *
  page207_i53
#CELL
  mstr_discrete cap *
  page207_i54
#ISCELL
  mstr_symbols gnd *
  page207_i55
#ISCELL
  mstr_symbols p5v_stby *
  page207_i56
#ISCELL
  mstr_symbols p5v_stby *
  page207_i57
#CELL
  dev_discrete cap_a *
  page207_i58
#CELL
  dev_discrete cap_a *
  page207_i59
#ISCELL
  mstr_standard offpage *
  page207_i62
#ISCELL
  mstr_standard offpage *
  page207_i64
#CELL
  mstr_discrete res *
  page207_i67
#CELL
  mstr_discrete res *
  page207_i68
#ISCELL
  mstr_symbols gnd *
  page207_i69
#ISCELL
  mstr_symbols pvccin_cpu1 *
  page207_i7
#ISCELL
  mstr_symbols gnd *
  page207_i70
#CELL
  dev_discrete cap_a *
  page207_i71
#ISCELL
  mstr_symbols gnd *
  page207_i72
#CELL
  mstr_discrete cap *
  page207_i74
#ISCELL
  mstr_symbols gnd *
  page207_i75
#ISCELL
  mstr_symbols gnd *
  page207_i78
#CELL
  dev_discrete cap_a *
  page207_i8
#ISCELL
  mstr_symbols gnd *
  page207_i80
#CELL
  dev_discrete cap_a *
  page207_i81
#CELL
  mstr_discrete cap *
  page207_i82
#ISCELL
  mstr_symbols gnd *
  page207_i83
#ISCELL
  mstr_symbols gnd *
  page207_i86
#ISCELL
  mstr_symbols gnd *
  page207_i9
#CELL
  mstr_discrete cap *
  page207_i95
#CELL
  mstr_discrete cap *
  page207_i96
#CELL
  mstr_discrete res *
  page207_i99
#ISCELL
  mstr_misc dns *
  *
#ISCELL
  mstr_symbols intel_corp_bpage *
  *
#ISCELL
  mstr_standard offpage *
  page208_i1
#ISCELL
  mstr_symbols gnd *
  page208_i10
#CELL
  mstr_discrete cap *
  page208_i104
#CELL
  mstr_discrete cap *
  page208_i105
#CELL
  mstr_discrete res *
  page208_i108
#CELL
  mstr_discrete res *
  page208_i109
#CELL
  mstr_discrete res *
  page208_i114
#CELL
  mstr_discrete res *
  page208_i115
#CELL
  w_hdl ind-120nh-30-gp *
  page208_i116
#CELL
  w_hdl ind-120nh-30-gp *
  page208_i117
#CELL
  w_hdl sc1u10v2kx-4-gp *
  page208_i118
#CELL
  w_hdl sc1u10v2kx-4-gp *
  page208_i119
#CELL
  mstr_discrete capp *
  page208_i12
#CELL
  w_hdl 1r3f-gp *
  page208_i120
#CELL
  w_hdl 1r3f-gp *
  page208_i121
#ISCELL
  mstr_symbols gnd *
  page208_i13
#CELL
  mstr_discrete capp *
  page208_i14
#ISCELL
  mstr_standard offpage *
  page208_i16
#ISCELL
  mstr_standard offpage *
  page208_i17
#ISCELL
  mstr_symbols pvccin_cpu1 *
  page208_i18
#ISCELL
  mstr_symbols gnd *
  page208_i21
#CELL
  dev_discrete cap_a *
  page208_i22
#ISCELL
  mstr_symbols gnd *
  page208_i23
#CELL
  mstr_discrete capp *
  page208_i24
#CELL
  mstr_discrete capp *
  page208_i25
#CELL
  mstr_discrete capp *
  page208_i26
#CELL
  mstr_discrete ir354xx *
  page208_i27
#CELL
  mstr_discrete capp *
  page208_i28
#ISCELL
  mstr_symbols pvccin_cpu1 *
  page208_i29
#ISCELL
  mstr_standard offpage *
  page208_i3
#CELL
  mstr_discrete capp *
  page208_i30
#ISCELL
  mstr_symbols gnd *
  page208_i33
#ISCELL
  mstr_symbols vcc_core *
  page208_i37
#CELL
  mstr_discrete cap *
  page208_i38
#CELL
  mstr_discrete cap *
  page208_i40
#CELL
  mstr_discrete cap *
  page208_i43
#CELL
  dev_discrete cap_a *
  page208_i44
#CELL
  mstr_discrete cap *
  page208_i45
#CELL
  mstr_discrete cap *
  page208_i46
#CELL
  mstr_discrete cap *
  page208_i48
#CELL
  mstr_discrete cap *
  page208_i50
#CELL
  dev_discrete cap_a *
  page208_i51
#CELL
  mstr_discrete cap *
  page208_i52
#CELL
  mstr_discrete cap *
  page208_i53
#CELL
  mstr_discrete cap *
  page208_i54
#CELL
  mstr_discrete cap *
  page208_i55
#ISCELL
  mstr_standard offpage *
  page208_i56
#ISCELL
  mstr_symbols gnd *
  page208_i57
#CELL
  mstr_discrete cap *
  page208_i58
#CELL
  mstr_discrete cap *
  page208_i59
#CELL
  mstr_discrete cap *
  page208_i60
#ISCELL
  mstr_standard offpage *
  page208_i61
#ISCELL
  mstr_symbols vcc_core *
  page208_i62
#ISCELL
  mstr_symbols gnd *
  page208_i63
#ISCELL
  mstr_symbols p5v_stby *
  page208_i64
#ISCELL
  mstr_symbols p5v_stby *
  page208_i65
#CELL
  dev_discrete cap_a *
  page208_i66
#CELL
  dev_discrete cap_a *
  page208_i67
#CELL
  mstr_discrete res *
  page208_i7
#ISCELL
  mstr_standard offpage *
  page208_i70
#CELL
  mstr_discrete ir354xx *
  page208_i71
#ISCELL
  mstr_standard offpage *
  page208_i72
#CELL
  mstr_discrete res *
  page208_i75
#CELL
  mstr_discrete res *
  page208_i76
#ISCELL
  mstr_symbols gnd *
  page208_i77
#ISCELL
  mstr_symbols gnd *
  page208_i78
#ISCELL
  mstr_symbols gnd *
  page208_i79
#ISCELL
  mstr_symbols pvccin_cpu1 *
  page208_i8
#CELL
  dev_discrete cap_a *
  page208_i80
#CELL
  mstr_discrete cap *
  page208_i82
#ISCELL
  mstr_symbols gnd *
  page208_i83
#ISCELL
  mstr_symbols gnd *
  page208_i85
#CELL
  dev_discrete cap_a *
  page208_i87
#ISCELL
  mstr_symbols gnd *
  page208_i88
#CELL
  dev_discrete cap_a *
  page208_i9
#CELL
  mstr_discrete cap *
  page208_i90
#ISCELL
  mstr_symbols gnd *
  page208_i91
#ISCELL
  mstr_symbols gnd *
  page208_i93
#ISCELL
  mstr_misc dns *
  *
#ISCELL
  mstr_symbols design_note *
  *
#ISCELL
  mstr_symbols intel_corp_bpage *
  *
#ISCELL
  mstr_standard offpage *
  page209_i1
#CELL
  mstr_discrete res *
  page209_i10
#CELL
  mstr_discrete res *
  page209_i11
#ISCELL
  mstr_symbols gnd *
  page209_i12
#ISCELL
  mstr_standard offpage *
  page209_i13
#ISCELL
  mstr_standard offpage *
  page209_i14
#CELL
  mstr_discrete res *
  page209_i15
#CELL
  mstr_discrete cap *
  page209_i16
#CELL
  dev_discrete cap_a *
  page209_i17
#CELL
  mstr_discrete cap *
  page209_i18
#ISCELL
  mstr_symbols pvccin_cpu1 *
  page209_i19
#ISCELL
  mstr_standard offpage *
  page209_i2
#CELL
  mstr_discrete cap *
  page209_i20
#CELL
  mstr_discrete cap *
  page209_i22
#ISCELL
  mstr_symbols vcc_core *
  page209_i23
#CELL
  mstr_discrete res *
  page209_i3
#ISCELL
  mstr_symbols gnd *
  page209_i34
#CELL
  mstr_discrete capp *
  page209_i35
#ISCELL
  mstr_symbols gnd *
  page209_i36
#CELL
  mstr_discrete capp *
  page209_i37
#CELL
  mstr_discrete capp *
  page209_i38
#ISCELL
  mstr_symbols gnd *
  page209_i4
#ISCELL
  mstr_symbols gnd *
  page209_i41
#CELL
  dev_discrete cap_a *
  page209_i42
#ISCELL
  mstr_symbols pvccin_cpu1 *
  page209_i43
#ISCELL
  mstr_standard offpage *
  page209_i44
#ISCELL
  mstr_symbols vcc_core *
  page209_i45
#ISCELL
  mstr_standard offpage *
  page209_i49
#CELL
  mstr_discrete cap *
  page209_i5
#ISCELL
  mstr_symbols p12v_stby *
  page209_i53
#ISCELL
  mstr_symbols p5v_stby *
  page209_i54
#CELL
  dev_discrete cap_a *
  page209_i55
#CELL
  mstr_discrete ir354xx *
  page209_i56
#ISCELL
  mstr_standard offpage *
  page209_i57
#ISCELL
  mstr_standard offpage *
  page209_i58
#CELL
  mstr_discrete res *
  page209_i59
#ISCELL
  mstr_symbols gnd *
  page209_i60
#CELL
  dev_discrete cap_a *
  page209_i62
#ISCELL
  mstr_symbols gnd *
  page209_i63
#ISCELL
  mstr_symbols gnd *
  page209_i65
#CELL
  mstr_discrete cap *
  page209_i67
#ISCELL
  mstr_symbols gnd *
  page209_i68
#CELL
  mstr_discrete cap *
  page209_i7
#CELL
  mstr_discrete cap *
  page209_i73
#CELL
  mstr_discrete res *
  page209_i75
#CELL
  mstr_discrete res *
  page209_i79
#CELL
  mstr_discrete cap *
  page209_i8
#CELL
  w_hdl ind-120nh-30-gp *
  page209_i80
#CELL
  w_hdl ind-80nh-1-gp *
  page209_i81
#CELL
  w_hdl sc1u10v2kx-4-gp *
  page209_i89
#CELL
  mstr_discrete res *
  page209_i9
#CELL
  w_hdl 1r3f-gp *
  page209_i90
#ISCELL
  mstr_misc dns *
  *
#ISCELL
  mstr_symbols design_note *
  *
#ISCELL
  mstr_symbols intel_corp_bpage *
  *
#ISCELL
  mstr_standard offpage *
  page210_i1
#CELL
  mstr_discrete capp *
  page210_i12
#ISCELL
  mstr_symbols gnd *
  page210_i13
#CELL
  mstr_discrete capp *
  page210_i14
#ISCELL
  mstr_symbols gnd *
  page210_i15
#ISCELL
  mstr_standard offpage *
  page210_i17
#ISCELL
  mstr_standard offpage *
  page210_i18
#ISCELL
  mstr_standard offpage *
  page210_i2
#ISCELL
  mstr_symbols vcc_core *
  page210_i21
#CELL
  mstr_discrete cap *
  page210_i22
#CELL
  mstr_discrete cap *
  page210_i24
#CELL
  mstr_discrete cap *
  page210_i26
#CELL
  dev_discrete cap_a *
  page210_i27
#CELL
  mstr_discrete cap *
  page210_i28
#CELL
  mstr_discrete res *
  page210_i29
#ISCELL
  mstr_symbols gnd *
  page210_i30
#CELL
  mstr_discrete res *
  page210_i31
#CELL
  mstr_discrete res *
  page210_i32
#CELL
  mstr_discrete res *
  page210_i33
#CELL
  mstr_discrete res *
  page210_i34
#CELL
  mstr_discrete cap *
  page210_i35
#CELL
  mstr_discrete cap *
  page210_i36
#CELL
  mstr_discrete cap *
  page210_i38
#ISCELL
  mstr_symbols gnd *
  page210_i39
#ISCELL
  mstr_standard offpage *
  page210_i40
#ISCELL
  mstr_standard offpage *
  page210_i41
#ISCELL
  mstr_symbols p5v_stby *
  page210_i42
#CELL
  dev_discrete cap_a *
  page210_i44
#CELL
  mstr_discrete res *
  page210_i45
#ISCELL
  mstr_symbols pvsa_cpu1 *
  page210_i46
#ISCELL
  mstr_symbols pvsa_cpu1 *
  page210_i47
#ISCELL
  mstr_standard offpage *
  page210_i50
#CELL
  mstr_discrete ir354xx *
  page210_i51
#CELL
  mstr_discrete res *
  page210_i52
#ISCELL
  mstr_symbols gnd *
  page210_i53
#ISCELL
  mstr_symbols gnd *
  page210_i54
#CELL
  dev_discrete cap_a *
  page210_i55
#ISCELL
  mstr_symbols gnd *
  page210_i58
#ISCELL
  mstr_standard offpage *
  page210_i6
#CELL
  mstr_discrete cap *
  page210_i60
#ISCELL
  mstr_symbols gnd *
  page210_i61
#CELL
  mstr_discrete cap *
  page210_i66
#CELL
  mstr_discrete res *
  page210_i68
#ISCELL
  mstr_symbols pvsa_cpu1 *
  page210_i7
#CELL
  mstr_discrete res *
  page210_i71
#CELL
  w_hdl ind-300nh-20-gp *
  page210_i72
#CELL
  w_hdl sc1u10v2kx-4-gp *
  page210_i73
#CELL
  w_hdl 1r3f-gp *
  page210_i74
#CELL
  dev_discrete cap_a *
  page210_i8
#ISCELL
  mstr_symbols gnd *
  page210_i9
#ISCELL
  mstr_misc dns *
  *
#ISCELL
  mstr_symbols design_note *
  *
#ISCELL
  mstr_symbols intel_corp_bpage *
  *
#CELL
  mstr_discrete res *
  page211_i100
#CELL
  mstr_discrete res *
  page211_i102
#CELL
  dev_discrete cap_a *
  page211_i103
#CELL
  dev_discrete cap_a *
  page211_i11
#ISCELL
  mstr_symbols gnd *
  page211_i12
#CELL
  dev_discrete cap_a *
  page211_i13
#ISCELL
  mstr_symbols gnd *
  page211_i14
#ISCELL
  mstr_standard offpage *
  page211_i15
#CELL
  mstr_discrete res *
  page211_i16
#ISCELL
  mstr_symbols pvccio_cpu0 *
  page211_i18
#ISCELL
  mstr_standard offpage *
  page211_i19
#ISCELL
  mstr_symbols gnd *
  page211_i2
#CELL
  dev_discrete cap_a *
  page211_i20
#ISCELL
  mstr_symbols gnd *
  page211_i21
#CELL
  dev_discrete cap_a *
  page211_i22
#ISCELL
  mstr_symbols gnd *
  page211_i23
#CELL
  mstr_discrete res *
  page211_i24
#ISCELL
  mstr_symbols p3v3_stby *
  page211_i25
#ISCELL
  mstr_standard offpage *
  page211_i26
#ISCELL
  mstr_symbols pvccio_cpu0 *
  page211_i27
#CELL
  mstr_discrete res *
  page211_i29
#ISCELL
  mstr_standard offpage *
  page211_i3
#ISCELL
  mstr_symbols vcc_core *
  page211_i30
#CELL
  mstr_discrete res *
  page211_i31
#CELL
  mstr_discrete res *
  page211_i32
#ISCELL
  mstr_symbols gnd *
  page211_i34
#ISCELL
  mstr_symbols gnd *
  page211_i35
#ISCELL
  mstr_standard offpage *
  page211_i36
#ISCELL
  mstr_standard offpage *
  page211_i37
#ISCELL
  mstr_standard offpage *
  page211_i39
#ISCELL
  mstr_standard offpage *
  page211_i40
#ISCELL
  mstr_standard offpage *
  page211_i42
#ISCELL
  mstr_standard offpage *
  page211_i43
#ISCELL
  mstr_standard offpage *
  page211_i48
#ISCELL
  mstr_standard offpage *
  page211_i49
#ISCELL
  mstr_symbols gnd *
  page211_i51
#CELL
  mstr_discrete res *
  page211_i52
#ISCELL
  mstr_symbols gnd *
  page211_i54
#CELL
  mstr_discrete res *
  page211_i56
#ISCELL
  mstr_standard offpage *
  page211_i57
#CELL
  mstr_discrete res *
  page211_i58
#ISCELL
  mstr_symbols p3v3_stby *
  page211_i59
#ISCELL
  mstr_standard offpage *
  page211_i6
#CELL
  mstr_discrete res *
  page211_i60
#CELL
  mstr_discrete res *
  page211_i61
#ISCELL
  mstr_standard offpage *
  page211_i62
#CELL
  mstr_discrete res *
  page211_i64
#CELL
  mstr_discrete cap *
  page211_i71
#ISCELL
  mstr_symbols gnd *
  page211_i72
#CELL
  mstr_discrete res *
  page211_i81
#ISCELL
  mstr_standard offpage *
  page211_i82
#CELL
  mstr_discrete cap *
  page211_i83
#ISCELL
  mstr_standard offpage *
  page211_i84
#CELL
  mstr_discrete res *
  page211_i87
#CELL
  mstr_discrete res *
  page211_i88
#CELL
  mstr_controller pxe1110b *
  page211_i93
#CELL
  w_hdl sc22p50v2jn-4gp *
  page211_i95
#CELL
  mstr_discrete res *
  page211_i96
#CELL
  mstr_discrete cap *
  page211_i97
#ISCELL
  mstr_symbols gnd *
  page211_i98
#CELL
  mstr_discrete res *
  page211_i99
#ISCELL
  mstr_misc dns *
  *
#ISCELL
  mstr_symbols design_note *
  *
#ISCELL
  mstr_symbols intel_corp_bpage *
  *
#CELL
  mstr_discrete ir354xx *
  page212_i101
#ISCELL
  mstr_symbols gnd *
  page212_i102
#CELL
  mstr_discrete res *
  page212_i103
#CELL
  mstr_misc shunt *
  page212_i104
#CELL
  mstr_misc shunt *
  page212_i105
#CELL
  dev_discrete cap_a *
  page212_i106
#ISCELL
  mstr_symbols gnd *
  page212_i107
#CELL
  mstr_discrete cap *
  page212_i109
#ISCELL
  mstr_symbols gnd *
  page212_i110
#ISCELL
  mstr_symbols gnd *
  page212_i113
#CELL
  mstr_discrete cap *
  page212_i118
#CELL
  mstr_discrete res *
  page212_i120
#CELL
  w_hdl sc22u16v5mx-4-gp *
  page212_i124
#ISCELL
  mstr_symbols gnd *
  page212_i125
#CELL
  w_hdl sc22u16v5mx-4-gp *
  page212_i126
#ISCELL
  mstr_symbols gnd *
  page212_i127
#ISCELL
  mstr_symbols gnd *
  page212_i128
#CELL
  w_hdl sc22u16v5mx-4-gp *
  page212_i129
#ISCELL
  mstr_symbols gnd *
  page212_i13
#CELL
  w_hdl sc22u16v5mx-4-gp *
  page212_i130
#ISCELL
  mstr_symbols gnd *
  page212_i131
#CELL
  w_hdl sc22u16v5mx-4-gp *
  page212_i132
#ISCELL
  mstr_symbols gnd *
  page212_i133
#CELL
  w_hdl sc22u16v5mx-4-gp *
  page212_i134
#ISCELL
  mstr_symbols gnd *
  page212_i135
#CELL
  w_hdl sc22u16v5mx-4-gp *
  page212_i136
#ISCELL
  mstr_symbols gnd *
  page212_i137
#CELL
  w_hdl sc22u16v5mx-4-gp *
  page212_i138
#ISCELL
  mstr_symbols gnd *
  page212_i139
#CELL
  mstr_discrete res *
  page212_i140
#CELL
  w_hdl ind-150nh-56-gp *
  page212_i141
#CELL
  w_hdl ind-100nh-35-gp *
  page212_i142
#CELL
  w_hdl sc1u10v2kx-4-gp *
  page212_i143
#CELL
  w_hdl 1r3f-gp *
  page212_i144
#CELL
  mstr_discrete capp *
  page212_i145
#CELL
  mstr_discrete capp *
  page212_i146
#CELL
  mstr_discrete capp *
  page212_i18
#ISCELL
  mstr_standard offpage *
  page212_i19
#ISCELL
  mstr_standard offpage *
  page212_i20
#ISCELL
  mstr_standard offpage *
  page212_i21
#ISCELL
  mstr_symbols pvccio_cpu0 *
  page212_i22
#CELL
  dev_discrete cap_a *
  page212_i23
#ISCELL
  mstr_symbols gnd *
  page212_i24
#ISCELL
  mstr_symbols gnd *
  page212_i29
#CELL
  mstr_discrete cap *
  page212_i33
#CELL
  mstr_discrete cap *
  page212_i36
#CELL
  mstr_discrete cap *
  page212_i37
#CELL
  dev_discrete cap_a *
  page212_i38
#CELL
  mstr_discrete cap *
  page212_i39
#CELL
  mstr_discrete cap *
  page212_i40
#CELL
  mstr_discrete cap *
  page212_i41
#CELL
  mstr_discrete cap *
  page212_i43
#ISCELL
  mstr_symbols gnd *
  page212_i44
#ISCELL
  mstr_standard offpage *
  page212_i45
#ISCELL
  mstr_symbols p12v_stby *
  page212_i57
#ISCELL
  mstr_symbols p5v_stby *
  page212_i58
#ISCELL
  mstr_standard offpage *
  page212_i59
#CELL
  dev_discrete cap_a *
  page212_i60
#ISCELL
  mstr_standard offpage *
  page212_i61
#CELL
  mstr_discrete res *
  page212_i68
#ISCELL
  mstr_symbols gnd *
  page212_i69
#ISCELL
  mstr_standard offpage *
  page212_i70
#CELL
  mstr_discrete res *
  page212_i74
#ISCELL
  mstr_symbols pvccio_cpu0 *
  page212_i75
#ISCELL
  mstr_standard offpage *
  page212_i76
#CELL
  dev_discrete cap_a *
  page212_i77
#CELL
  mstr_discrete res *
  page212_i78
#ISCELL
  mstr_symbols vcc_core *
  page212_i79
#ISCELL
  mstr_symbols vcc_core *
  page212_i80
#ISCELL
  mstr_symbols pvccio_cpu0 *
  page212_i82
#ISCELL
  mstr_misc dns *
  *
#ISCELL
  mstr_symbols design_note *
  *
#ISCELL
  mstr_symbols intel_corp_bpage *
  *
#ISCELL
  mstr_symbols p3v3_stby *
  page213_i1
#ISCELL
  mstr_symbols gnd *
  page213_i10
#ISCELL
  mstr_symbols gnd *
  page213_i100
#CELL
  mstr_discrete cap *
  page213_i101
#CELL
  mstr_discrete res *
  page213_i103
#CELL
  mstr_discrete res *
  page213_i104
#CELL
  dev_discrete cap_a *
  page213_i105
#CELL
  dev_discrete cap_a *
  page213_i11
#ISCELL
  mstr_symbols gnd *
  page213_i12
#CELL
  mstr_discrete res *
  page213_i13
#CELL
  mstr_discrete res *
  page213_i14
#CELL
  mstr_discrete res *
  page213_i15
#CELL
  mstr_discrete res *
  page213_i16
#CELL
  dev_discrete cap_a *
  page213_i17
#ISCELL
  mstr_symbols gnd *
  page213_i18
#ISCELL
  mstr_standard offpage *
  page213_i2
#ISCELL
  mstr_symbols gnd *
  page213_i21
#ISCELL
  mstr_symbols p3v3_stby *
  page213_i24
#CELL
  mstr_discrete res *
  page213_i25
#ISCELL
  mstr_symbols pvccio_cpu1 *
  page213_i26
#CELL
  mstr_discrete res *
  page213_i27
#ISCELL
  mstr_symbols pvccio_cpu1 *
  page213_i28
#ISCELL
  mstr_standard offpage *
  page213_i3
#CELL
  mstr_discrete res *
  page213_i30
#CELL
  mstr_discrete res *
  page213_i31
#CELL
  mstr_discrete res *
  page213_i32
#ISCELL
  mstr_standard offpage *
  page213_i34
#CELL
  dev_discrete cap_a *
  page213_i35
#ISCELL
  mstr_symbols gnd *
  page213_i36
#CELL
  mstr_discrete res *
  page213_i37
#ISCELL
  mstr_symbols gnd *
  page213_i44
#ISCELL
  mstr_symbols gnd *
  page213_i45
#CELL
  mstr_discrete res *
  page213_i46
#ISCELL
  mstr_symbols gnd *
  page213_i47
#ISCELL
  mstr_symbols gnd *
  page213_i49
#ISCELL
  mstr_standard offpage *
  page213_i5
#ISCELL
  mstr_standard offpage *
  page213_i50
#ISCELL
  mstr_standard offpage *
  page213_i51
#ISCELL
  mstr_standard offpage *
  page213_i52
#ISCELL
  mstr_standard offpage *
  page213_i53
#ISCELL
  mstr_standard offpage *
  page213_i54
#ISCELL
  mstr_standard offpage *
  page213_i55
#ISCELL
  mstr_standard offpage *
  page213_i57
#ISCELL
  mstr_standard offpage *
  page213_i58
#ISCELL
  mstr_standard offpage *
  page213_i61
#ISCELL
  mstr_standard offpage *
  page213_i62
#CELL
  mstr_discrete res *
  page213_i63
#CELL
  mstr_discrete cap *
  page213_i73
#ISCELL
  mstr_symbols gnd *
  page213_i74
#ISCELL
  mstr_standard offpage *
  page213_i8
#CELL
  mstr_discrete cap *
  page213_i83
#CELL
  mstr_discrete res *
  page213_i84
#ISCELL
  mstr_standard offpage *
  page213_i86
#ISCELL
  mstr_standard offpage *
  page213_i87
#CELL
  dev_discrete cap_a *
  page213_i9
#CELL
  mstr_discrete res *
  page213_i90
#CELL
  mstr_discrete res *
  page213_i91
#ISCELL
  mstr_symbols universal_power *
  page213_i92
#CELL
  mstr_controller pxe1110b *
  page213_i96
#CELL
  w_hdl sc22p50v2jn-4gp *
  page213_i98
#CELL
  mstr_discrete res *
  page213_i99
#ISCELL
  mstr_misc dns *
  *
#ISCELL
  mstr_symbols design_note *
  *
#ISCELL
  mstr_symbols intel_corp_bpage *
  *
#CELL
  mstr_discrete res *
  page214_i101
#ISCELL
  mstr_symbols gnd *
  page214_i102
#ISCELL
  mstr_standard offpage *
  page214_i103
#CELL
  mstr_discrete res *
  page214_i105
#ISCELL
  mstr_standard offpage *
  page214_i106
#ISCELL
  mstr_symbols pvccio_cpu1 *
  page214_i107
#CELL
  dev_discrete cap_a *
  page214_i108
#CELL
  mstr_discrete res *
  page214_i109
#CELL
  mstr_discrete ir354xx *
  page214_i126
#CELL
  mstr_discrete res *
  page214_i127
#ISCELL
  mstr_symbols gnd *
  page214_i128
#CELL
  mstr_misc shunt *
  page214_i129
#CELL
  mstr_misc shunt *
  page214_i130
#ISCELL
  mstr_symbols gnd *
  page214_i133
#CELL
  mstr_discrete cap *
  page214_i134
#ISCELL
  mstr_symbols gnd *
  page214_i135
#ISCELL
  mstr_symbols gnd *
  page214_i136
#CELL
  dev_discrete cap_a *
  page214_i137
#CELL
  mstr_discrete cap *
  page214_i143
#CELL
  mstr_discrete res *
  page214_i145
#CELL
  w_hdl sc22u16v5mx-4-gp *
  page214_i148
#CELL
  w_hdl sc22u16v5mx-4-gp *
  page214_i149
#ISCELL
  mstr_symbols gnd *
  page214_i150
#ISCELL
  mstr_symbols gnd *
  page214_i151
#CELL
  w_hdl sc22u16v5mx-4-gp *
  page214_i152
#ISCELL
  mstr_symbols gnd *
  page214_i153
#CELL
  w_hdl sc22u16v5mx-4-gp *
  page214_i154
#ISCELL
  mstr_symbols gnd *
  page214_i155
#CELL
  w_hdl sc22u16v5mx-4-gp *
  page214_i156
#ISCELL
  mstr_symbols gnd *
  page214_i157
#CELL
  w_hdl sc22u16v5mx-4-gp *
  page214_i158
#ISCELL
  mstr_symbols gnd *
  page214_i159
#CELL
  w_hdl sc22u16v5mx-4-gp *
  page214_i160
#CELL
  w_hdl sc22u16v5mx-4-gp *
  page214_i161
#ISCELL
  mstr_symbols gnd *
  page214_i162
#ISCELL
  mstr_symbols gnd *
  page214_i163
#CELL
  w_hdl sc22u16v5mx-4-gp *
  page214_i164
#ISCELL
  mstr_symbols gnd *
  page214_i165
#CELL
  w_hdl sc22u16v5mx-4-gp *
  page214_i166
#ISCELL
  mstr_symbols gnd *
  page214_i167
#CELL
  w_hdl sc22u16v5mx-4-gp *
  page214_i168
#CELL
  w_hdl sc22u16v5mx-4-gp *
  page214_i169
#ISCELL
  mstr_symbols gnd *
  page214_i170
#ISCELL
  mstr_symbols gnd *
  page214_i171
#ISCELL
  mstr_symbols universal_power *
  page214_i172
#CELL
  mstr_discrete res *
  page214_i173
#CELL
  w_hdl ind-150nh-56-gp *
  page214_i174
#CELL
  w_hdl sc1u10v2kx-4-gp *
  page214_i175
#CELL
  w_hdl 1r3f-gp *
  page214_i176
#CELL
  mstr_discrete capp *
  page214_i177
#CELL
  mstr_discrete capp *
  page214_i178
#CELL
  mstr_discrete capp *
  page214_i24
#ISCELL
  mstr_symbols pvccio_cpu1 *
  page214_i3
#ISCELL
  mstr_standard offpage *
  page214_i58
#ISCELL
  mstr_standard offpage *
  page214_i59
#ISCELL
  mstr_symbols gnd *
  page214_i6
#ISCELL
  mstr_standard offpage *
  page214_i60
#ISCELL
  mstr_symbols pvccio_cpu1 *
  page214_i64
#CELL
  dev_discrete cap_a *
  page214_i65
#ISCELL
  mstr_symbols gnd *
  page214_i66
#ISCELL
  mstr_symbols gnd *
  page214_i68
#CELL
  mstr_discrete cap *
  page214_i73
#CELL
  mstr_discrete cap *
  page214_i76
#CELL
  dev_discrete cap_a *
  page214_i77
#CELL
  mstr_discrete cap *
  page214_i78
#CELL
  mstr_discrete cap *
  page214_i79
#CELL
  mstr_discrete cap *
  page214_i80
#CELL
  mstr_discrete cap *
  page214_i81
#ISCELL
  mstr_standard offpage *
  page214_i82
#CELL
  mstr_discrete cap *
  page214_i83
#ISCELL
  mstr_symbols gnd *
  page214_i84
#ISCELL
  mstr_symbols p5v_stby *
  page214_i88
#ISCELL
  mstr_symbols universal_power *
  page214_i89
#ISCELL
  mstr_standard offpage *
  page214_i95
#CELL
  dev_discrete cap_a *
  page214_i96
#ISCELL
  mstr_standard offpage *
  page214_i97
#ISCELL
  mstr_misc dns *
  *
#ISCELL
  mstr_symbols design_note *
  *
#ISCELL
  mstr_symbols intel_corp_bpage *
  *
#ISCELL
  mstr_standard offpage *
  page215_i1
#ISCELL
  mstr_standard offpage *
  page215_i10
#ISCELL
  mstr_standard offpage *
  page215_i11
#CELL
  mstr_discrete res *
  page215_i12
#CELL
  mstr_discrete res *
  page215_i13
#CELL
  mstr_discrete cap *
  page215_i14
#CELL
  mstr_discrete res *
  page215_i15
#CELL
  w_hdl sc22p50v2jn-4gp *
  page215_i16
#ISCELL
  mstr_symbols pvccio_cpu0 *
  page215_i18
#ISCELL
  mstr_symbols gnd *
  page215_i19
#ISCELL
  mstr_standard offpage *
  page215_i2
#ISCELL
  mstr_symbols gnd *
  page215_i20
#CELL
  mstr_discrete cap *
  page215_i22
#ISCELL
  mstr_symbols gnd *
  page215_i23
#ISCELL
  mstr_symbols gnd *
  page215_i24
#CELL
  w_hdl sc22p50v2jn-4gp *
  page215_i26
#CELL
  mstr_discrete res *
  page215_i27
#CELL
  mstr_discrete res *
  page215_i28
#CELL
  mstr_discrete res *
  page215_i29
#ISCELL
  mstr_standard offpage *
  page215_i3
#ISCELL
  mstr_symbols p3v3_stby *
  page215_i30
#ISCELL
  mstr_symbols gnd *
  page215_i31
#ISCELL
  mstr_symbols gnd *
  page215_i32
#CELL
  mstr_discrete res *
  page215_i33
#CELL
  dev_discrete cap_a *
  page215_i34
#CELL
  dev_discrete cap_a *
  page215_i35
#ISCELL
  mstr_symbols gnd *
  page215_i36
#ISCELL
  mstr_symbols gnd *
  page215_i37
#CELL
  dev_discrete cap_a *
  page215_i38
#ISCELL
  mstr_symbols gnd *
  page215_i39
#ISCELL
  mstr_standard offpage *
  page215_i4
#CELL
  dev_discrete cap_a *
  page215_i40
#CELL
  mstr_discrete res *
  page215_i41
#ISCELL
  mstr_standard offpage *
  page215_i42
#ISCELL
  mstr_symbols gnd *
  page215_i43
#CELL
  mstr_discrete cap *
  page215_i44
#CELL
  mstr_discrete res *
  page215_i45
#CELL
  mstr_discrete res *
  page215_i49
#ISCELL
  mstr_standard offpage *
  page215_i5
#CELL
  mstr_discrete res *
  page215_i50
#CELL
  mstr_discrete res *
  page215_i51
#ISCELL
  mstr_symbols p3v3_stby *
  page215_i52
#CELL
  mstr_discrete res *
  page215_i53
#CELL
  mstr_discrete res *
  page215_i54
#ISCELL
  mstr_standard offpage *
  page215_i55
#CELL
  mstr_discrete res *
  page215_i56
#CELL
  mstr_discrete res *
  page215_i58
#ISCELL
  mstr_symbols pvccio_cpu0 *
  page215_i59
#ISCELL
  mstr_standard offpage *
  page215_i6
#ISCELL
  mstr_standard offpage *
  page215_i60
#ISCELL
  mstr_standard offpage *
  page215_i61
#ISCELL
  mstr_standard offpage *
  page215_i62
#ISCELL
  mstr_standard offpage *
  page215_i63
#ISCELL
  mstr_standard offpage *
  page215_i64
#ISCELL
  mstr_standard offpage *
  page215_i65
#ISCELL
  mstr_standard offpage *
  page215_i66
#ISCELL
  mstr_standard offpage *
  page215_i67
#ISCELL
  mstr_standard offpage *
  page215_i68
#CELL
  mstr_controller pxm1310b *
  page215_i69
#ISCELL
  mstr_standard offpage *
  page215_i7
#CELL
  mstr_discrete res *
  page215_i70
#CELL
  mstr_discrete res *
  page215_i72
#CELL
  mstr_discrete res *
  page215_i73
#CELL
  mstr_discrete res *
  page215_i74
#CELL
  mstr_discrete res *
  page215_i75
#ISCELL
  mstr_standard offpage *
  page215_i8
#ISCELL
  mstr_standard offpage *
  page215_i9
#ISCELL
  mstr_misc dns *
  *
#ISCELL
  mstr_symbols intel_corp_bpage *
  *
#ISCELL
  mstr_symbols pvddq_abc *
  page216_i1
#CELL
  mstr_discrete ir354xx *
  page216_i102
#CELL
  mstr_discrete ir354xx *
  page216_i103
#CELL
  mstr_discrete res *
  page216_i104
#ISCELL
  mstr_symbols gnd *
  page216_i105
#CELL
  mstr_discrete res *
  page216_i106
#ISCELL
  mstr_symbols gnd *
  page216_i107
#CELL
  dev_discrete cap_a *
  page216_i108
#ISCELL
  mstr_symbols gnd *
  page216_i109
#CELL
  dev_discrete cap_a *
  page216_i111
#ISCELL
  mstr_symbols gnd *
  page216_i112
#ISCELL
  mstr_symbols gnd *
  page216_i115
#ISCELL
  mstr_symbols gnd *
  page216_i117
#CELL
  mstr_discrete cap *
  page216_i118
#ISCELL
  mstr_symbols gnd *
  page216_i120
#CELL
  mstr_discrete cap *
  page216_i121
#ISCELL
  mstr_symbols gnd *
  page216_i122
#CELL
  mstr_discrete cap *
  page216_i128
#CELL
  mstr_discrete cap *
  page216_i135
#CELL
  mstr_discrete cap *
  page216_i136
#CELL
  mstr_discrete res *
  page216_i139
#CELL
  mstr_discrete res *
  page216_i140
#CELL
  mstr_discrete res *
  page216_i145
#CELL
  mstr_discrete res *
  page216_i146
#CELL
  w_hdl sc1u10v2kx-4-gp *
  page216_i149
#CELL
  w_hdl sc1u10v2kx-4-gp *
  page216_i150
#CELL
  w_hdl 1r3f-gp *
  page216_i151
#CELL
  w_hdl 1r3f-gp *
  page216_i152
#CELL
  w_hdl ind-120nh-30-gp *
  page216_i153
#CELL
  w_hdl ind-120nh-30-gp *
  page216_i155
#ISCELL
  mstr_symbols gnd *
  page216_i19
#ISCELL
  mstr_standard offpage *
  page216_i3
#ISCELL
  mstr_standard offpage *
  page216_i33
#ISCELL
  mstr_symbols gnd *
  page216_i35
#ISCELL
  mstr_standard offpage *
  page216_i4
#CELL
  mstr_discrete cap *
  page216_i44
#CELL
  mstr_discrete cap *
  page216_i45
#CELL
  mstr_discrete cap *
  page216_i46
#CELL
  mstr_discrete cap *
  page216_i47
#CELL
  mstr_discrete cap *
  page216_i48
#CELL
  mstr_discrete cap *
  page216_i50
#CELL
  dev_discrete cap_a *
  page216_i51
#CELL
  mstr_discrete cap *
  page216_i54
#ISCELL
  mstr_standard offpage *
  page216_i58
#CELL
  mstr_discrete cap *
  page216_i6
#ISCELL
  mstr_standard offpage *
  page216_i61
#ISCELL
  mstr_standard offpage *
  page216_i62
#ISCELL
  mstr_standard offpage *
  page216_i63
#ISCELL
  mstr_symbols pvddq_abc *
  page216_i64
#CELL
  mstr_discrete cap *
  page216_i68
#ISCELL
  mstr_symbols gnd *
  page216_i69
#ISCELL
  mstr_symbols gnd *
  page216_i7
#ISCELL
  mstr_symbols gnd *
  page216_i70
#CELL
  mstr_discrete cap *
  page216_i72
#CELL
  mstr_discrete cap *
  page216_i77
#CELL
  dev_discrete cap_a *
  page216_i78
#CELL
  mstr_discrete cap *
  page216_i79
#CELL
  mstr_discrete cap *
  page216_i80
#CELL
  mstr_discrete cap *
  page216_i81
#ISCELL
  mstr_standard offpage *
  page216_i82
#ISCELL
  mstr_symbols vcc_core *
  page216_i83
#CELL
  mstr_discrete cap *
  page216_i84
#ISCELL
  mstr_symbols gnd *
  page216_i85
#ISCELL
  mstr_symbols vcc_core *
  page216_i86
#ISCELL
  mstr_symbols p5v_stby *
  page216_i87
#ISCELL
  mstr_symbols p5v_stby *
  page216_i88
#ISCELL
  mstr_misc dns *
  *
#ISCELL
  mstr_symbols intel_corp_bpage *
  *
#ISCELL
  mstr_symbols pvddq_abc *
  page217_i109
#ISCELL
  mstr_symbols gnd *
  page217_i114
#ISCELL
  mstr_symbols vcc_core *
  page217_i120
#ISCELL
  mstr_symbols gnd *
  page217_i123
#CELL
  mstr_discrete capp *
  page217_i175
#ISCELL
  mstr_symbols p12v_stby *
  page217_i183
#ISCELL
  mstr_symbols gnd *
  page217_i187
#ISCELL
  mstr_symbols pvddq_abc *
  page217_i192
#ISCELL
  mstr_symbols pvddq_abc *
  page217_i201
#ISCELL
  mstr_symbols gnd *
  page217_i203
#CELL
  dev_discrete cap_a *
  page217_i205
#CELL
  dev_discrete cap_a *
  page217_i206
#CELL
  dev_discrete cap_a *
  page217_i207
#CELL
  dev_discrete cap_a *
  page217_i208
#CELL
  dev_discrete cap_a *
  page217_i209
#CELL
  dev_discrete cap_a *
  page217_i210
#CELL
  dev_discrete cap_a *
  page217_i211
#CELL
  dev_discrete cap_a *
  page217_i212
#CELL
  dev_discrete cap_a *
  page217_i213
#ISCELL
  mstr_symbols pvddq_abc *
  page217_i214
#ISCELL
  mstr_symbols gnd *
  page217_i215
#ISCELL
  mstr_symbols pvddq_abc *
  page217_i242
#ISCELL
  mstr_symbols gnd *
  page217_i248
#ISCELL
  mstr_symbols pvddq_abc *
  page217_i249
#ISCELL
  mstr_symbols gnd *
  page217_i251
#CELL
  mstr_misc shunt *
  page217_i259
#CELL
  mstr_misc shunt *
  page217_i260
#CELL
  w_hdl ind-100nh-35-gp *
  page217_i261
#ISCELL
  mstr_symbols pvddq_abc *
  page217_i264
#ISCELL
  mstr_symbols gnd *
  page217_i267
#CELL
  dev_discrete cap_a *
  page217_i269
#CELL
  dev_discrete cap_a *
  page217_i270
#CELL
  dev_discrete cap_a *
  page217_i271
#CELL
  dev_discrete cap_a *
  page217_i272
#ISCELL
  mstr_symbols pvddq_abc *
  page217_i273
#ISCELL
  mstr_symbols gnd *
  page217_i274
#ISCELL
  mstr_symbols gnd *
  page217_i277
#ISCELL
  mstr_symbols pvddq_abc *
  page217_i278
#CELL
  dev_discrete cap_a *
  page217_i279
#CELL
  dev_discrete cap_a *
  page217_i280
#CELL
  dev_discrete cap_a *
  page217_i281
#CELL
  dev_discrete cap_a *
  page217_i282
#CELL
  dev_discrete cap_a *
  page217_i283
#CELL
  dev_discrete cap_a *
  page217_i284
#CELL
  dev_discrete cap_a *
  page217_i285
#CELL
  dev_discrete cap_a *
  page217_i286
#CELL
  dev_discrete cap_a *
  page217_i287
#CELL
  dev_discrete cap_a *
  page217_i288
#CELL
  dev_discrete cap_a *
  page217_i289
#CELL
  dev_discrete cap_a *
  page217_i290
#CELL
  dev_discrete cap_a *
  page217_i291
#CELL
  dev_discrete cap_a *
  page217_i292
#CELL
  dev_discrete cap_a *
  page217_i293
#CELL
  dev_discrete cap_a *
  page217_i294
#CELL
  dev_discrete cap_a *
  page217_i295
#CELL
  dev_discrete cap_a *
  page217_i296
#CELL
  dev_discrete cap_a *
  page217_i297
#CELL
  dev_discrete cap_a *
  page217_i298
#CELL
  dev_discrete cap_a *
  page217_i299
#CELL
  dev_discrete cap_a *
  page217_i300
#CELL
  dev_discrete cap_a *
  page217_i301
#CELL
  dev_discrete cap_a *
  page217_i302
#CELL
  dev_discrete cap_a *
  page217_i303
#CELL
  dev_discrete cap_a *
  page217_i304
#CELL
  dev_discrete cap_a *
  page217_i305
#CELL
  dev_discrete cap_a *
  page217_i306
#CELL
  dev_discrete cap_a *
  page217_i307
#CELL
  dev_discrete cap_a *
  page217_i308
#CELL
  dev_discrete cap_a *
  page217_i309
#CELL
  dev_discrete cap_a *
  page217_i310
#CELL
  dev_discrete cap_a *
  page217_i311
#CELL
  dev_discrete cap_a *
  page217_i312
#CELL
  dev_discrete cap_a *
  page217_i313
#CELL
  dev_discrete cap_a *
  page217_i314
#CELL
  mstr_discrete cap *
  page217_i316
#CELL
  mstr_discrete cap *
  page217_i317
#CELL
  mstr_discrete cap *
  page217_i318
#CELL
  mstr_discrete cap *
  page217_i319
#CELL
  mstr_discrete cap *
  page217_i320
#CELL
  mstr_discrete cap *
  page217_i321
#CELL
  mstr_discrete cap *
  page217_i322
#CELL
  mstr_discrete cap *
  page217_i323
#CELL
  mstr_discrete cap *
  page217_i324
#CELL
  mstr_discrete cap *
  page217_i325
#CELL
  mstr_discrete cap *
  page217_i326
#CELL
  mstr_discrete cap *
  page217_i327
#CELL
  mstr_discrete cap *
  page217_i328
#CELL
  mstr_discrete cap *
  page217_i329
#CELL
  mstr_discrete res *
  page217_i58
#ISCELL
  mstr_symbols gnd *
  page217_i65
#ISCELL
  mstr_standard offpage *
  page217_i70
#ISCELL
  mstr_standard offpage *
  page217_i72
#ISCELL
  mstr_symbols pvddq_abc *
  page217_i73
#CELL
  mstr_discrete res *
  page217_i74
#CELL
  mstr_discrete capp *
  page217_i75
#CELL
  mstr_discrete capp *
  page217_i76
#CELL
  mstr_discrete capp *
  page217_i77
#CELL
  mstr_discrete capp *
  page217_i78
#ISCELL
  mstr_symbols pvddq_abc *
  page217_i80
#ISCELL
  mstr_symbols gnd *
  page217_i81
#ISCELL
  mstr_symbols pvddq_abc *
  page217_i93
#ISCELL
  mstr_symbols gnd *
  page217_i94
#ISCELL
  mstr_misc dns *
  *
#ISCELL
  mstr_symbols design_note *
  *
#ISCELL
  mstr_symbols intel_corp_bpage *
  *
#ISCELL
  mstr_symbols gnd *
  page218_i1
#ISCELL
  mstr_standard offpage *
  page218_i10
#ISCELL
  mstr_standard offpage *
  page218_i11
#ISCELL
  mstr_standard offpage *
  page218_i12
#CELL
  mstr_discrete res *
  page218_i13
#CELL
  mstr_discrete cap *
  page218_i14
#CELL
  mstr_discrete res *
  page218_i15
#CELL
  mstr_discrete cap *
  page218_i16
#CELL
  w_hdl sc22p50v2jn-4gp *
  page218_i17
#CELL
  mstr_discrete res *
  page218_i18
#CELL
  mstr_discrete res *
  page218_i19
#ISCELL
  mstr_standard offpage *
  page218_i2
#CELL
  w_hdl sc22p50v2jn-4gp *
  page218_i20
#CELL
  mstr_discrete res *
  page218_i21
#ISCELL
  mstr_symbols pvccio_cpu0 *
  page218_i23
#ISCELL
  mstr_symbols gnd *
  page218_i24
#ISCELL
  mstr_symbols gnd *
  page218_i25
#ISCELL
  mstr_symbols gnd *
  page218_i26
#ISCELL
  mstr_symbols gnd *
  page218_i27
#CELL
  dev_discrete cap_a *
  page218_i28
#ISCELL
  mstr_symbols gnd *
  page218_i29
#ISCELL
  mstr_standard offpage *
  page218_i3
#CELL
  dev_discrete cap_a *
  page218_i30
#ISCELL
  mstr_symbols gnd *
  page218_i33
#CELL
  mstr_discrete res *
  page218_i34
#CELL
  mstr_discrete res *
  page218_i35
#ISCELL
  mstr_symbols p3v3_stby *
  page218_i36
#ISCELL
  mstr_symbols gnd *
  page218_i37
#CELL
  dev_discrete cap_a *
  page218_i38
#ISCELL
  mstr_symbols gnd *
  page218_i39
#ISCELL
  mstr_standard offpage *
  page218_i4
#CELL
  dev_discrete cap_a *
  page218_i40
#CELL
  mstr_discrete cap *
  page218_i41
#ISCELL
  mstr_symbols gnd *
  page218_i42
#CELL
  mstr_discrete res *
  page218_i45
#CELL
  mstr_discrete res *
  page218_i46
#ISCELL
  mstr_standard offpage *
  page218_i48
#ISCELL
  mstr_standard offpage *
  page218_i49
#ISCELL
  mstr_standard offpage *
  page218_i5
#ISCELL
  mstr_standard offpage *
  page218_i50
#ISCELL
  mstr_standard offpage *
  page218_i51
#ISCELL
  mstr_standard offpage *
  page218_i52
#ISCELL
  mstr_standard offpage *
  page218_i53
#ISCELL
  mstr_standard offpage *
  page218_i54
#CELL
  mstr_discrete res *
  page218_i55
#CELL
  mstr_discrete res *
  page218_i56
#CELL
  mstr_discrete res *
  page218_i57
#CELL
  mstr_discrete res *
  page218_i58
#CELL
  mstr_discrete res *
  page218_i59
#ISCELL
  mstr_standard offpage *
  page218_i6
#CELL
  mstr_discrete res *
  page218_i60
#ISCELL
  mstr_standard offpage *
  page218_i61
#ISCELL
  mstr_symbols p3v3_stby *
  page218_i62
#ISCELL
  mstr_standard offpage *
  page218_i64
#ISCELL
  mstr_standard offpage *
  page218_i65
#ISCELL
  mstr_standard offpage *
  page218_i66
#CELL
  mstr_discrete res *
  page218_i67
#ISCELL
  mstr_symbols pvccio_cpu0 *
  page218_i68
#CELL
  mstr_controller pxm1310b *
  page218_i69
#ISCELL
  mstr_standard offpage *
  page218_i7
#CELL
  mstr_discrete res *
  page218_i70
#CELL
  mstr_discrete res *
  page218_i73
#CELL
  mstr_discrete res *
  page218_i74
#CELL
  mstr_discrete res *
  page218_i75
#CELL
  mstr_discrete res *
  page218_i76
#ISCELL
  mstr_standard offpage *
  page218_i8
#ISCELL
  mstr_standard offpage *
  page218_i9
#ISCELL
  mstr_misc dns *
  *
#ISCELL
  mstr_symbols intel_corp_bpage *
  *
#ISCELL
  mstr_symbols pvddq_def *
  page219_i1
#CELL
  mstr_discrete ir354xx *
  page219_i106
#CELL
  mstr_discrete ir354xx *
  page219_i107
#CELL
  mstr_discrete res *
  page219_i108
#ISCELL
  mstr_symbols gnd *
  page219_i109
#CELL
  mstr_discrete res *
  page219_i110
#ISCELL
  mstr_symbols gnd *
  page219_i111
#ISCELL
  mstr_symbols p5v_stby *
  page219_i112
#CELL
  dev_discrete cap_a *
  page219_i113
#ISCELL
  mstr_symbols gnd *
  page219_i114
#CELL
  dev_discrete cap_a *
  page219_i116
#ISCELL
  mstr_symbols gnd *
  page219_i117
#CELL
  mstr_discrete cap *
  page219_i119
#ISCELL
  mstr_symbols gnd *
  page219_i120
#ISCELL
  mstr_symbols gnd *
  page219_i122
#CELL
  mstr_discrete cap *
  page219_i124
#ISCELL
  mstr_symbols gnd *
  page219_i125
#ISCELL
  mstr_symbols gnd *
  page219_i128
#CELL
  mstr_discrete cap *
  page219_i137
#CELL
  mstr_discrete cap *
  page219_i138
#CELL
  mstr_discrete res *
  page219_i141
#CELL
  mstr_discrete res *
  page219_i142
#CELL
  mstr_discrete res *
  page219_i147
#CELL
  mstr_discrete res *
  page219_i148
#CELL
  w_hdl sc1u10v2kx-4-gp *
  page219_i151
#CELL
  w_hdl sc1u10v2kx-4-gp *
  page219_i152
#CELL
  w_hdl 1r3f-gp *
  page219_i153
#CELL
  w_hdl 1r3f-gp *
  page219_i154
#CELL
  w_hdl ind-120nh-30-gp *
  page219_i157
#CELL
  w_hdl ind-120nh-30-gp *
  page219_i158
#ISCELL
  mstr_symbols gnd *
  page219_i19
#ISCELL
  mstr_standard offpage *
  page219_i3
#ISCELL
  mstr_standard offpage *
  page219_i33
#ISCELL
  mstr_symbols gnd *
  page219_i35
#ISCELL
  mstr_standard offpage *
  page219_i4
#CELL
  mstr_discrete cap *
  page219_i44
#CELL
  mstr_discrete cap *
  page219_i45
#CELL
  mstr_discrete cap *
  page219_i46
#CELL
  mstr_discrete cap *
  page219_i47
#CELL
  mstr_discrete cap *
  page219_i48
#CELL
  mstr_discrete cap *
  page219_i50
#CELL
  dev_discrete cap_a *
  page219_i51
#CELL
  mstr_discrete cap *
  page219_i54
#ISCELL
  mstr_standard offpage *
  page219_i58
#ISCELL
  mstr_standard offpage *
  page219_i61
#ISCELL
  mstr_standard offpage *
  page219_i62
#ISCELL
  mstr_standard offpage *
  page219_i63
#ISCELL
  mstr_symbols pvddq_def *
  page219_i64
#CELL
  mstr_discrete cap *
  page219_i68
#ISCELL
  mstr_symbols gnd *
  page219_i69
#ISCELL
  mstr_symbols gnd *
  page219_i7
#ISCELL
  mstr_symbols gnd *
  page219_i70
#CELL
  mstr_discrete cap *
  page219_i72
#CELL
  mstr_discrete cap *
  page219_i75
#CELL
  mstr_discrete cap *
  page219_i77
#CELL
  dev_discrete cap_a *
  page219_i78
#CELL
  mstr_discrete cap *
  page219_i79
#CELL
  mstr_discrete cap *
  page219_i80
#CELL
  mstr_discrete cap *
  page219_i81
#ISCELL
  mstr_standard offpage *
  page219_i82
#ISCELL
  mstr_symbols vcc_core *
  page219_i83
#CELL
  mstr_discrete cap *
  page219_i84
#ISCELL
  mstr_symbols gnd *
  page219_i85
#ISCELL
  mstr_symbols vcc_core *
  page219_i86
#CELL
  mstr_discrete cap *
  page219_i87
#ISCELL
  mstr_symbols p5v_stby *
  page219_i89
#ISCELL
  mstr_misc dns *
  *
#ISCELL
  mstr_symbols intel_corp_bpage *
  *
#ISCELL
  mstr_symbols pvddq_def *
  page220_i109
#ISCELL
  mstr_symbols gnd *
  page220_i114
#ISCELL
  mstr_symbols vcc_core *
  page220_i120
#ISCELL
  mstr_symbols p12v_stby *
  page220_i176
#ISCELL
  mstr_symbols gnd *
  page220_i181
#ISCELL
  mstr_symbols pvddq_def *
  page220_i185
#ISCELL
  mstr_symbols pvddq_def *
  page220_i189
#ISCELL
  mstr_symbols gnd *
  page220_i191
#CELL
  dev_discrete cap_a *
  page220_i192
#CELL
  dev_discrete cap_a *
  page220_i193
#CELL
  dev_discrete cap_a *
  page220_i194
#CELL
  dev_discrete cap_a *
  page220_i195
#CELL
  dev_discrete cap_a *
  page220_i196
#CELL
  dev_discrete cap_a *
  page220_i197
#CELL
  dev_discrete cap_a *
  page220_i198
#CELL
  dev_discrete cap_a *
  page220_i199
#CELL
  dev_discrete cap_a *
  page220_i200
#ISCELL
  mstr_symbols pvddq_def *
  page220_i201
#ISCELL
  mstr_symbols gnd *
  page220_i202
#ISCELL
  mstr_symbols pvddq_def *
  page220_i218
#ISCELL
  mstr_symbols gnd *
  page220_i220
#ISCELL
  mstr_symbols pvddq_def *
  page220_i235
#ISCELL
  mstr_symbols gnd *
  page220_i238
#CELL
  mstr_misc shunt *
  page220_i239
#CELL
  mstr_misc shunt *
  page220_i240
#CELL
  w_hdl ind-100nh-35-gp *
  page220_i241
#ISCELL
  mstr_symbols gnd *
  page220_i245
#ISCELL
  mstr_symbols pvddq_def *
  page220_i248
#CELL
  dev_discrete cap_a *
  page220_i249
#CELL
  dev_discrete cap_a *
  page220_i250
#CELL
  dev_discrete cap_a *
  page220_i251
#CELL
  dev_discrete cap_a *
  page220_i252
#ISCELL
  mstr_symbols gnd *
  page220_i253
#ISCELL
  mstr_symbols pvddq_def *
  page220_i254
#ISCELL
  mstr_symbols gnd *
  page220_i255
#ISCELL
  mstr_symbols pvddq_def *
  page220_i257
#CELL
  dev_discrete cap_a *
  page220_i258
#CELL
  dev_discrete cap_a *
  page220_i259
#CELL
  dev_discrete cap_a *
  page220_i260
#CELL
  dev_discrete cap_a *
  page220_i261
#CELL
  dev_discrete cap_a *
  page220_i262
#CELL
  dev_discrete cap_a *
  page220_i263
#CELL
  dev_discrete cap_a *
  page220_i264
#CELL
  dev_discrete cap_a *
  page220_i265
#CELL
  dev_discrete cap_a *
  page220_i266
#CELL
  dev_discrete cap_a *
  page220_i267
#CELL
  dev_discrete cap_a *
  page220_i268
#CELL
  dev_discrete cap_a *
  page220_i269
#CELL
  dev_discrete cap_a *
  page220_i270
#CELL
  dev_discrete cap_a *
  page220_i271
#CELL
  dev_discrete cap_a *
  page220_i272
#CELL
  dev_discrete cap_a *
  page220_i273
#CELL
  dev_discrete cap_a *
  page220_i274
#CELL
  dev_discrete cap_a *
  page220_i275
#CELL
  dev_discrete cap_a *
  page220_i276
#CELL
  dev_discrete cap_a *
  page220_i277
#CELL
  dev_discrete cap_a *
  page220_i278
#CELL
  dev_discrete cap_a *
  page220_i279
#CELL
  dev_discrete cap_a *
  page220_i280
#CELL
  dev_discrete cap_a *
  page220_i281
#CELL
  dev_discrete cap_a *
  page220_i282
#CELL
  dev_discrete cap_a *
  page220_i283
#CELL
  dev_discrete cap_a *
  page220_i284
#CELL
  dev_discrete cap_a *
  page220_i285
#CELL
  dev_discrete cap_a *
  page220_i286
#CELL
  dev_discrete cap_a *
  page220_i287
#CELL
  dev_discrete cap_a *
  page220_i288
#CELL
  dev_discrete cap_a *
  page220_i289
#CELL
  dev_discrete cap_a *
  page220_i290
#CELL
  dev_discrete cap_a *
  page220_i291
#CELL
  dev_discrete cap_a *
  page220_i292
#CELL
  dev_discrete cap_a *
  page220_i293
#CELL
  w_hdl sc22u16v5mx-4-gp *
  page220_i298
#CELL
  w_hdl sc22u16v5mx-4-gp *
  page220_i299
#CELL
  w_hdl sc22u16v5mx-4-gp *
  page220_i300
#CELL
  w_hdl sc22u16v5mx-4-gp *
  page220_i301
#CELL
  w_hdl sc22u16v5mx-4-gp *
  page220_i302
#CELL
  w_hdl sc22u16v5mx-4-gp *
  page220_i303
#CELL
  w_hdl sc22u16v5mx-4-gp *
  page220_i304
#CELL
  w_hdl sc22u16v5mx-4-gp *
  page220_i305
#CELL
  w_hdl sc22u16v5mx-4-gp *
  page220_i306
#ISCELL
  mstr_symbols gnd *
  page220_i307
#CELL
  mstr_discrete cap *
  page220_i308
#CELL
  mstr_discrete cap *
  page220_i309
#CELL
  mstr_discrete cap *
  page220_i310
#CELL
  mstr_discrete cap *
  page220_i311
#CELL
  mstr_discrete cap *
  page220_i312
#CELL
  mstr_discrete cap *
  page220_i313
#CELL
  mstr_discrete cap *
  page220_i314
#CELL
  mstr_discrete cap *
  page220_i315
#CELL
  mstr_discrete cap *
  page220_i316
#CELL
  mstr_discrete cap *
  page220_i317
#CELL
  mstr_discrete cap *
  page220_i318
#CELL
  mstr_discrete cap *
  page220_i319
#CELL
  mstr_discrete cap *
  page220_i320
#CELL
  mstr_discrete cap *
  page220_i321
#CELL
  w_hdl se100u16vm-48-gp *
  page220_i324
#CELL
  mstr_discrete res *
  page220_i58
#ISCELL
  mstr_symbols gnd *
  page220_i65
#ISCELL
  mstr_standard offpage *
  page220_i70
#ISCELL
  mstr_standard offpage *
  page220_i72
#ISCELL
  mstr_symbols pvddq_def *
  page220_i73
#CELL
  mstr_discrete res *
  page220_i74
#CELL
  mstr_discrete capp *
  page220_i75
#CELL
  mstr_discrete capp *
  page220_i76
#CELL
  mstr_discrete capp *
  page220_i77
#CELL
  mstr_discrete capp *
  page220_i78
#ISCELL
  mstr_symbols pvddq_def *
  page220_i80
#ISCELL
  mstr_symbols gnd *
  page220_i81
#ISCELL
  mstr_symbols pvddq_def *
  page220_i93
#ISCELL
  mstr_symbols gnd *
  page220_i94
#ISCELL
  mstr_misc dns *
  *
#ISCELL
  mstr_misc prelim *
  *
#ISCELL
  mstr_symbols cad_note *
  *
#ISCELL
  mstr_symbols intel_corp_bpage *
  *
#ISCELL
  mstr_symbols gnd *
  page221_i1
#ISCELL
  mstr_symbols gnd *
  page221_i10
#CELL
  mstr_discrete cap *
  page221_i11
#ISCELL
  mstr_symbols gnd *
  page221_i12
#CELL
  mstr_discrete cap *
  page221_i13
#CELL
  mstr_discrete res *
  page221_i14
#CELL
  mstr_vreg mic5166 *
  page221_i15
#ISCELL
  mstr_symbols gnd *
  page221_i16
#ISCELL
  mstr_symbols gnd *
  page221_i17
#CELL
  mstr_discrete cap *
  page221_i18
#CELL
  mstr_discrete cap *
  page221_i19
#CELL
  mstr_discrete cap *
  page221_i2
#ISCELL
  mstr_symbols gnd *
  page221_i20
#ISCELL
  mstr_symbols gnd *
  page221_i21
#CELL
  mstr_discrete cap *
  page221_i22
#ISCELL
  mstr_symbols gnd *
  page221_i23
#CELL
  mstr_discrete cap *
  page221_i24
#CELL
  mstr_discrete res *
  page221_i25
#ISCELL
  mstr_symbols p3v3 *
  page221_i26
#ISCELL
  mstr_symbols pvtt_abc *
  page221_i28
#ISCELL
  mstr_standard offpage *
  page221_i3
#CELL
  mstr_discrete cap *
  page221_i30
#ISCELL
  mstr_symbols gnd *
  page221_i32
#CELL
  mstr_discrete res *
  page221_i33
#ISCELL
  mstr_symbols pvtt_abc *
  page221_i34
#ISCELL
  mstr_standard offpage *
  page221_i35
#ISCELL
  mstr_symbols gnd *
  page221_i36
#CELL
  mstr_discrete res *
  page221_i4
#CELL
  dev_discrete cap_a *
  page221_i40
#CELL
  mstr_discrete cap *
  page221_i44
#CELL
  mstr_discrete cap *
  page221_i45
#CELL
  mstr_discrete cap *
  page221_i46
#CELL
  mstr_discrete res *
  page221_i5
#CELL
  mstr_discrete res *
  page221_i6
#ISCELL
  mstr_symbols p3v3 *
  page221_i7
#ISCELL
  mstr_symbols pvddq_abc *
  page221_i8
#CELL
  mstr_misc shunt *
  page221_i9
#ISCELL
  mstr_misc dns *
  *
#ISCELL
  mstr_misc prelim *
  *
#ISCELL
  mstr_symbols cad_note *
  *
#ISCELL
  mstr_symbols intel_corp_bpage *
  *
#ISCELL
  mstr_symbols gnd *
  page222_i1
#CELL
  mstr_discrete res *
  page222_i10
#ISCELL
  mstr_symbols gnd *
  page222_i11
#CELL
  mstr_discrete cap *
  page222_i12
#CELL
  mstr_vreg mic5166 *
  page222_i13
#ISCELL
  mstr_symbols gnd *
  page222_i14
#CELL
  mstr_discrete cap *
  page222_i15
#ISCELL
  mstr_symbols gnd *
  page222_i16
#CELL
  mstr_discrete cap *
  page222_i17
#ISCELL
  mstr_symbols gnd *
  page222_i18
#ISCELL
  mstr_symbols gnd *
  page222_i19
#CELL
  mstr_discrete cap *
  page222_i2
#CELL
  mstr_discrete cap *
  page222_i20
#ISCELL
  mstr_symbols gnd *
  page222_i21
#CELL
  mstr_discrete cap *
  page222_i22
#CELL
  mstr_discrete res *
  page222_i23
#ISCELL
  mstr_symbols p3v3 *
  page222_i24
#ISCELL
  mstr_symbols pvtt_def *
  page222_i25
#CELL
  mstr_discrete cap *
  page222_i28
#ISCELL
  mstr_symbols gnd *
  page222_i29
#ISCELL
  mstr_standard offpage *
  page222_i3
#CELL
  mstr_misc shunt *
  page222_i30
#CELL
  mstr_discrete res *
  page222_i31
#ISCELL
  mstr_standard offpage *
  page222_i33
#ISCELL
  mstr_symbols pvtt_def *
  page222_i34
#ISCELL
  mstr_symbols gnd *
  page222_i35
#ISCELL
  mstr_symbols pvddq_def *
  page222_i37
#CELL
  mstr_discrete res *
  page222_i4
#CELL
  dev_discrete cap_a *
  page222_i41
#CELL
  mstr_discrete cap *
  page222_i44
#CELL
  mstr_discrete cap *
  page222_i45
#CELL
  mstr_discrete cap *
  page222_i46
#CELL
  mstr_discrete res *
  page222_i5
#CELL
  mstr_discrete res *
  page222_i6
#ISCELL
  mstr_symbols p3v3 *
  page222_i7
#ISCELL
  mstr_symbols gnd *
  page222_i8
#CELL
  mstr_discrete cap *
  page222_i9
#ISCELL
  mstr_misc dns *
  *
#ISCELL
  mstr_symbols design_note *
  *
#ISCELL
  mstr_symbols intel_corp_bpage *
  *
#ISCELL
  mstr_standard offpage *
  page223_i1
#ISCELL
  mstr_standard offpage *
  page223_i10
#ISCELL
  mstr_standard offpage *
  page223_i11
#CELL
  mstr_discrete cap *
  page223_i12
#CELL
  mstr_discrete res *
  page223_i13
#CELL
  mstr_discrete res *
  page223_i14
#CELL
  w_hdl sc22p50v2jn-4gp *
  page223_i15
#CELL
  mstr_discrete res *
  page223_i16
#CELL
  w_hdl sc22p50v2jn-4gp *
  page223_i17
#CELL
  mstr_discrete res *
  page223_i18
#CELL
  mstr_discrete res *
  page223_i19
#ISCELL
  mstr_standard offpage *
  page223_i2
#ISCELL
  mstr_symbols pvccio_cpu1 *
  page223_i21
#ISCELL
  mstr_symbols gnd *
  page223_i22
#ISCELL
  mstr_symbols gnd *
  page223_i23
#ISCELL
  mstr_symbols gnd *
  page223_i24
#ISCELL
  mstr_symbols gnd *
  page223_i25
#CELL
  mstr_discrete cap *
  page223_i27
#ISCELL
  mstr_symbols gnd *
  page223_i28
#ISCELL
  mstr_symbols gnd *
  page223_i29
#ISCELL
  mstr_standard offpage *
  page223_i3
#CELL
  mstr_discrete res *
  page223_i31
#CELL
  mstr_discrete res *
  page223_i32
#ISCELL
  mstr_symbols p3v3_stby *
  page223_i33
#ISCELL
  mstr_symbols gnd *
  page223_i34
#CELL
  dev_discrete cap_a *
  page223_i35
#CELL
  dev_discrete cap_a *
  page223_i36
#ISCELL
  mstr_symbols gnd *
  page223_i37
#ISCELL
  mstr_symbols gnd *
  page223_i38
#ISCELL
  mstr_symbols gnd *
  page223_i39
#ISCELL
  mstr_standard offpage *
  page223_i4
#CELL
  mstr_discrete cap *
  page223_i40
#CELL
  mstr_discrete res *
  page223_i41
#CELL
  dev_discrete cap_a *
  page223_i43
#CELL
  dev_discrete cap_a *
  page223_i44
#CELL
  mstr_discrete res *
  page223_i45
#CELL
  mstr_discrete res *
  page223_i48
#CELL
  mstr_discrete res *
  page223_i49
#ISCELL
  mstr_standard offpage *
  page223_i5
#CELL
  mstr_discrete res *
  page223_i50
#ISCELL
  mstr_standard offpage *
  page223_i51
#ISCELL
  mstr_symbols p3v3_stby *
  page223_i52
#CELL
  mstr_discrete res *
  page223_i53
#CELL
  mstr_discrete res *
  page223_i54
#CELL
  mstr_discrete res *
  page223_i55
#CELL
  mstr_discrete res *
  page223_i57
#ISCELL
  mstr_symbols pvccio_cpu1 *
  page223_i58
#ISCELL
  mstr_standard offpage *
  page223_i59
#ISCELL
  mstr_standard offpage *
  page223_i6
#ISCELL
  mstr_standard offpage *
  page223_i60
#ISCELL
  mstr_standard offpage *
  page223_i61
#ISCELL
  mstr_standard offpage *
  page223_i62
#ISCELL
  mstr_standard offpage *
  page223_i63
#ISCELL
  mstr_standard offpage *
  page223_i64
#ISCELL
  mstr_standard offpage *
  page223_i65
#ISCELL
  mstr_standard offpage *
  page223_i66
#ISCELL
  mstr_standard offpage *
  page223_i67
#ISCELL
  mstr_standard offpage *
  page223_i68
#CELL
  mstr_controller pxm1310b *
  page223_i69
#ISCELL
  mstr_standard offpage *
  page223_i7
#CELL
  mstr_discrete res *
  page223_i70
#CELL
  mstr_discrete res *
  page223_i73
#CELL
  mstr_discrete res *
  page223_i74
#CELL
  mstr_discrete res *
  page223_i75
#CELL
  mstr_discrete res *
  page223_i76
#ISCELL
  mstr_standard offpage *
  page223_i8
#ISCELL
  mstr_standard offpage *
  page223_i9
#ISCELL
  mstr_misc dns *
  *
#ISCELL
  mstr_symbols intel_corp_bpage *
  *
#ISCELL
  mstr_symbols pvddq_ghj *
  page224_i1
#CELL
  mstr_discrete ir354xx *
  page224_i110
#CELL
  mstr_discrete ir354xx *
  page224_i111
#CELL
  mstr_discrete res *
  page224_i112
#ISCELL
  mstr_symbols gnd *
  page224_i113
#CELL
  mstr_discrete res *
  page224_i114
#ISCELL
  mstr_symbols gnd *
  page224_i115
#CELL
  dev_discrete cap_a *
  page224_i117
#ISCELL
  mstr_symbols gnd *
  page224_i118
#ISCELL
  mstr_symbols gnd *
  page224_i120
#CELL
  mstr_discrete cap *
  page224_i122
#ISCELL
  mstr_symbols gnd *
  page224_i123
#CELL
  dev_discrete cap_a *
  page224_i124
#ISCELL
  mstr_symbols gnd *
  page224_i125
#ISCELL
  mstr_symbols gnd *
  page224_i128
#CELL
  mstr_discrete cap *
  page224_i130
#ISCELL
  mstr_symbols gnd *
  page224_i131
#CELL
  mstr_discrete cap *
  page224_i140
#CELL
  mstr_discrete cap *
  page224_i141
#CELL
  mstr_discrete res *
  page224_i144
#CELL
  mstr_discrete res *
  page224_i145
#CELL
  mstr_discrete res *
  page224_i150
#CELL
  mstr_discrete res *
  page224_i151
#CELL
  w_hdl sc1u10v2kx-4-gp *
  page224_i154
#CELL
  w_hdl sc1u10v2kx-4-gp *
  page224_i155
#CELL
  w_hdl 1r3f-gp *
  page224_i156
#CELL
  w_hdl 1r3f-gp *
  page224_i157
#CELL
  w_hdl ind-120nh-30-gp *
  page224_i160
#CELL
  w_hdl ind-120nh-30-gp *
  page224_i161
#ISCELL
  mstr_symbols gnd *
  page224_i19
#ISCELL
  mstr_standard offpage *
  page224_i3
#ISCELL
  mstr_standard offpage *
  page224_i33
#ISCELL
  mstr_symbols gnd *
  page224_i35
#ISCELL
  mstr_standard offpage *
  page224_i4
#CELL
  mstr_discrete cap *
  page224_i44
#CELL
  mstr_discrete cap *
  page224_i45
#CELL
  mstr_discrete cap *
  page224_i46
#CELL
  mstr_discrete cap *
  page224_i47
#CELL
  mstr_discrete cap *
  page224_i48
#CELL
  mstr_discrete cap *
  page224_i50
#CELL
  dev_discrete cap_a *
  page224_i51
#CELL
  mstr_discrete cap *
  page224_i54
#ISCELL
  mstr_standard offpage *
  page224_i58
#CELL
  mstr_discrete cap *
  page224_i6
#ISCELL
  mstr_standard offpage *
  page224_i61
#ISCELL
  mstr_standard offpage *
  page224_i62
#ISCELL
  mstr_standard offpage *
  page224_i63
#ISCELL
  mstr_symbols pvddq_ghj *
  page224_i64
#CELL
  mstr_discrete cap *
  page224_i68
#ISCELL
  mstr_symbols gnd *
  page224_i69
#ISCELL
  mstr_symbols gnd *
  page224_i7
#ISCELL
  mstr_symbols gnd *
  page224_i70
#CELL
  mstr_discrete cap *
  page224_i72
#CELL
  mstr_discrete cap *
  page224_i75
#CELL
  mstr_discrete cap *
  page224_i77
#CELL
  dev_discrete cap_a *
  page224_i78
#CELL
  mstr_discrete cap *
  page224_i79
#CELL
  mstr_discrete cap *
  page224_i80
#CELL
  mstr_discrete cap *
  page224_i81
#ISCELL
  mstr_standard offpage *
  page224_i82
#ISCELL
  mstr_symbols vcc_core *
  page224_i83
#CELL
  mstr_discrete cap *
  page224_i84
#ISCELL
  mstr_symbols gnd *
  page224_i85
#ISCELL
  mstr_symbols p5v_stby *
  page224_i87
#ISCELL
  mstr_symbols p5v_stby *
  page224_i88
#ISCELL
  mstr_symbols vcc_core *
  page224_i89
#ISCELL
  mstr_misc dns *
  *
#ISCELL
  mstr_symbols intel_corp_bpage *
  *
#ISCELL
  mstr_symbols pvddq_ghj *
  page225_i109
#ISCELL
  mstr_symbols gnd *
  page225_i114
#ISCELL
  mstr_symbols vcc_core *
  page225_i120
#ISCELL
  mstr_symbols gnd *
  page225_i123
#ISCELL
  mstr_symbols p12v_stby *
  page225_i176
#ISCELL
  mstr_symbols gnd *
  page225_i182
#ISCELL
  mstr_symbols pvddq_ghj *
  page225_i185
#ISCELL
  mstr_symbols pvddq_ghj *
  page225_i189
#ISCELL
  mstr_symbols gnd *
  page225_i191
#CELL
  dev_discrete cap_a *
  page225_i196
#CELL
  dev_discrete cap_a *
  page225_i197
#CELL
  dev_discrete cap_a *
  page225_i198
#CELL
  dev_discrete cap_a *
  page225_i199
#CELL
  dev_discrete cap_a *
  page225_i200
#CELL
  dev_discrete cap_a *
  page225_i201
#CELL
  dev_discrete cap_a *
  page225_i202
#CELL
  dev_discrete cap_a *
  page225_i203
#CELL
  dev_discrete cap_a *
  page225_i204
#ISCELL
  mstr_symbols pvddq_ghj *
  page225_i205
#ISCELL
  mstr_symbols gnd *
  page225_i206
#ISCELL
  mstr_symbols pvddq_ghj *
  page225_i222
#ISCELL
  mstr_symbols gnd *
  page225_i224
#ISCELL
  mstr_symbols pvddq_ghj *
  page225_i240
#ISCELL
  mstr_symbols gnd *
  page225_i242
#CELL
  mstr_misc shunt *
  page225_i243
#CELL
  mstr_misc shunt *
  page225_i244
#CELL
  w_hdl sc22u16v5mx-4-gp *
  page225_i246
#CELL
  w_hdl sc22u16v5mx-4-gp *
  page225_i247
#CELL
  w_hdl sc22u16v5mx-4-gp *
  page225_i249
#CELL
  w_hdl sc22u16v5mx-4-gp *
  page225_i250
#CELL
  w_hdl sc22u16v5mx-4-gp *
  page225_i251
#CELL
  w_hdl ind-100nh-35-gp *
  page225_i253
#ISCELL
  mstr_symbols pvddq_ghj *
  page225_i257
#ISCELL
  mstr_symbols gnd *
  page225_i258
#CELL
  dev_discrete cap_a *
  page225_i261
#CELL
  dev_discrete cap_a *
  page225_i262
#CELL
  dev_discrete cap_a *
  page225_i263
#CELL
  dev_discrete cap_a *
  page225_i264
#ISCELL
  mstr_symbols gnd *
  page225_i265
#ISCELL
  mstr_symbols pvddq_ghj *
  page225_i266
#ISCELL
  mstr_symbols gnd *
  page225_i267
#ISCELL
  mstr_symbols pvddq_ghj *
  page225_i269
#CELL
  dev_discrete cap_a *
  page225_i270
#CELL
  dev_discrete cap_a *
  page225_i271
#CELL
  dev_discrete cap_a *
  page225_i272
#CELL
  dev_discrete cap_a *
  page225_i273
#CELL
  dev_discrete cap_a *
  page225_i274
#CELL
  dev_discrete cap_a *
  page225_i275
#CELL
  dev_discrete cap_a *
  page225_i276
#CELL
  dev_discrete cap_a *
  page225_i277
#CELL
  dev_discrete cap_a *
  page225_i278
#CELL
  dev_discrete cap_a *
  page225_i279
#CELL
  dev_discrete cap_a *
  page225_i280
#CELL
  dev_discrete cap_a *
  page225_i281
#CELL
  dev_discrete cap_a *
  page225_i282
#CELL
  dev_discrete cap_a *
  page225_i283
#CELL
  dev_discrete cap_a *
  page225_i284
#CELL
  dev_discrete cap_a *
  page225_i285
#CELL
  dev_discrete cap_a *
  page225_i286
#CELL
  dev_discrete cap_a *
  page225_i287
#CELL
  dev_discrete cap_a *
  page225_i288
#CELL
  dev_discrete cap_a *
  page225_i289
#CELL
  dev_discrete cap_a *
  page225_i290
#CELL
  dev_discrete cap_a *
  page225_i291
#CELL
  dev_discrete cap_a *
  page225_i292
#CELL
  dev_discrete cap_a *
  page225_i293
#CELL
  dev_discrete cap_a *
  page225_i294
#CELL
  dev_discrete cap_a *
  page225_i295
#CELL
  dev_discrete cap_a *
  page225_i296
#CELL
  dev_discrete cap_a *
  page225_i297
#CELL
  dev_discrete cap_a *
  page225_i298
#CELL
  dev_discrete cap_a *
  page225_i299
#CELL
  dev_discrete cap_a *
  page225_i300
#CELL
  dev_discrete cap_a *
  page225_i301
#CELL
  dev_discrete cap_a *
  page225_i302
#CELL
  dev_discrete cap_a *
  page225_i303
#CELL
  dev_discrete cap_a *
  page225_i304
#CELL
  dev_discrete cap_a *
  page225_i305
#CELL
  mstr_discrete cap *
  page225_i307
#CELL
  mstr_discrete cap *
  page225_i308
#CELL
  mstr_discrete cap *
  page225_i309
#CELL
  mstr_discrete cap *
  page225_i310
#CELL
  mstr_discrete cap *
  page225_i311
#CELL
  mstr_discrete cap *
  page225_i312
#CELL
  mstr_discrete cap *
  page225_i313
#CELL
  mstr_discrete cap *
  page225_i314
#CELL
  mstr_discrete cap *
  page225_i315
#CELL
  mstr_discrete cap *
  page225_i316
#CELL
  mstr_discrete cap *
  page225_i317
#CELL
  mstr_discrete cap *
  page225_i318
#CELL
  mstr_discrete cap *
  page225_i319
#CELL
  mstr_discrete cap *
  page225_i320
#CELL
  w_hdl st270u2d5vbm-gp *
  page225_i327
#CELL
  w_hdl st270u2d5vbm-gp *
  page225_i328
#CELL
  w_hdl st270u2d5vbm-gp *
  page225_i329
#CELL
  mstr_discrete res *
  page225_i58
#ISCELL
  mstr_symbols gnd *
  page225_i65
#ISCELL
  mstr_standard offpage *
  page225_i70
#ISCELL
  mstr_standard offpage *
  page225_i72
#ISCELL
  mstr_symbols pvddq_ghj *
  page225_i73
#CELL
  mstr_discrete res *
  page225_i74
#CELL
  mstr_discrete capp *
  page225_i75
#CELL
  mstr_discrete capp *
  page225_i76
#CELL
  mstr_discrete capp *
  page225_i77
#CELL
  mstr_discrete capp *
  page225_i78
#ISCELL
  mstr_symbols pvddq_ghj *
  page225_i80
#ISCELL
  mstr_symbols gnd *
  page225_i81
#ISCELL
  mstr_symbols pvddq_ghj *
  page225_i93
#ISCELL
  mstr_symbols gnd *
  page225_i94
#ISCELL
  mstr_misc dns *
  *
#ISCELL
  mstr_symbols design_note *
  *
#ISCELL
  mstr_symbols intel_corp_bpage *
  *
#ISCELL
  mstr_standard offpage *
  page226_i1
#ISCELL
  mstr_standard offpage *
  page226_i10
#ISCELL
  mstr_standard offpage *
  page226_i11
#CELL
  mstr_discrete cap *
  page226_i12
#CELL
  mstr_discrete res *
  page226_i13
#CELL
  mstr_discrete res *
  page226_i14
#CELL
  w_hdl sc22p50v2jn-4gp *
  page226_i15
#CELL
  mstr_discrete res *
  page226_i16
#CELL
  w_hdl sc22p50v2jn-4gp *
  page226_i17
#CELL
  mstr_discrete res *
  page226_i18
#CELL
  mstr_discrete res *
  page226_i19
#ISCELL
  mstr_standard offpage *
  page226_i2
#ISCELL
  mstr_symbols pvccio_cpu1 *
  page226_i21
#ISCELL
  mstr_symbols gnd *
  page226_i22
#CELL
  mstr_discrete cap *
  page226_i23
#ISCELL
  mstr_symbols gnd *
  page226_i24
#ISCELL
  mstr_symbols gnd *
  page226_i25
#ISCELL
  mstr_symbols gnd *
  page226_i26
#ISCELL
  mstr_symbols gnd *
  page226_i28
#ISCELL
  mstr_symbols gnd *
  page226_i29
#ISCELL
  mstr_standard offpage *
  page226_i3
#ISCELL
  mstr_symbols gnd *
  page226_i31
#CELL
  dev_discrete cap_a *
  page226_i32
#ISCELL
  mstr_symbols gnd *
  page226_i33
#CELL
  mstr_discrete res *
  page226_i34
#ISCELL
  mstr_symbols p3v3_stby *
  page226_i35
#CELL
  mstr_discrete res *
  page226_i36
#ISCELL
  mstr_symbols gnd *
  page226_i37
#CELL
  dev_discrete cap_a *
  page226_i38
#ISCELL
  mstr_symbols gnd *
  page226_i39
#ISCELL
  mstr_standard offpage *
  page226_i4
#CELL
  mstr_discrete cap *
  page226_i40
#CELL
  mstr_discrete res *
  page226_i41
#CELL
  dev_discrete cap_a *
  page226_i44
#CELL
  dev_discrete cap_a *
  page226_i45
#CELL
  mstr_discrete res *
  page226_i46
#CELL
  mstr_discrete res *
  page226_i48
#CELL
  mstr_discrete res *
  page226_i49
#ISCELL
  mstr_standard offpage *
  page226_i5
#CELL
  mstr_discrete res *
  page226_i50
#ISCELL
  mstr_standard offpage *
  page226_i51
#ISCELL
  mstr_symbols p3v3_stby *
  page226_i52
#CELL
  mstr_discrete res *
  page226_i53
#CELL
  mstr_discrete res *
  page226_i54
#CELL
  mstr_discrete res *
  page226_i55
#CELL
  mstr_discrete res *
  page226_i57
#ISCELL
  mstr_symbols pvccio_cpu1 *
  page226_i58
#ISCELL
  mstr_standard offpage *
  page226_i59
#ISCELL
  mstr_standard offpage *
  page226_i6
#ISCELL
  mstr_standard offpage *
  page226_i60
#ISCELL
  mstr_standard offpage *
  page226_i61
#ISCELL
  mstr_standard offpage *
  page226_i62
#ISCELL
  mstr_standard offpage *
  page226_i63
#ISCELL
  mstr_standard offpage *
  page226_i64
#ISCELL
  mstr_standard offpage *
  page226_i65
#ISCELL
  mstr_standard offpage *
  page226_i66
#ISCELL
  mstr_standard offpage *
  page226_i67
#ISCELL
  mstr_standard offpage *
  page226_i68
#CELL
  mstr_controller pxm1310b *
  page226_i69
#ISCELL
  mstr_standard offpage *
  page226_i7
#CELL
  mstr_discrete res *
  page226_i70
#CELL
  mstr_discrete res *
  page226_i72
#CELL
  mstr_discrete res *
  page226_i73
#CELL
  mstr_discrete res *
  page226_i74
#CELL
  mstr_discrete res *
  page226_i75
#ISCELL
  mstr_standard offpage *
  page226_i8
#ISCELL
  mstr_standard offpage *
  page226_i9
#ISCELL
  mstr_misc dns *
  *
#ISCELL
  mstr_symbols intel_corp_bpage *
  *
#ISCELL
  mstr_symbols pvddq_klm *
  page227_i1
#CELL
  mstr_discrete ir354xx *
  page227_i101
#CELL
  mstr_discrete ir354xx *
  page227_i102
#CELL
  mstr_discrete res *
  page227_i103
#ISCELL
  mstr_symbols gnd *
  page227_i104
#CELL
  mstr_discrete res *
  page227_i105
#ISCELL
  mstr_symbols gnd *
  page227_i106
#ISCELL
  mstr_symbols p5v_stby *
  page227_i107
#CELL
  dev_discrete cap_a *
  page227_i109
#ISCELL
  mstr_symbols gnd *
  page227_i110
#ISCELL
  mstr_symbols gnd *
  page227_i113
#CELL
  mstr_discrete cap *
  page227_i114
#ISCELL
  mstr_symbols gnd *
  page227_i115
#ISCELL
  mstr_symbols gnd *
  page227_i117
#CELL
  mstr_discrete cap *
  page227_i119
#ISCELL
  mstr_symbols gnd *
  page227_i120
#CELL
  dev_discrete cap_a *
  page227_i122
#ISCELL
  mstr_symbols gnd *
  page227_i123
#CELL
  mstr_discrete cap *
  page227_i134
#CELL
  mstr_discrete cap *
  page227_i135
#CELL
  mstr_discrete res *
  page227_i138
#CELL
  mstr_discrete res *
  page227_i139
#CELL
  w_hdl sc1u10v2kx-4-gp *
  page227_i147
#CELL
  w_hdl sc1u10v2kx-4-gp *
  page227_i148
#CELL
  w_hdl 1r3f-gp *
  page227_i149
#CELL
  w_hdl 1r3f-gp *
  page227_i150
#CELL
  w_hdl ind-120nh-30-gp *
  page227_i152
#CELL
  w_hdl ind-120nh-30-gp *
  page227_i153
#CELL
  mstr_discrete res *
  page227_i154
#CELL
  mstr_discrete res *
  page227_i155
#ISCELL
  mstr_symbols gnd *
  page227_i19
#ISCELL
  mstr_standard offpage *
  page227_i3
#ISCELL
  mstr_standard offpage *
  page227_i33
#ISCELL
  mstr_symbols gnd *
  page227_i35
#ISCELL
  mstr_standard offpage *
  page227_i4
#CELL
  mstr_discrete cap *
  page227_i44
#CELL
  mstr_discrete cap *
  page227_i45
#CELL
  mstr_discrete cap *
  page227_i46
#CELL
  mstr_discrete cap *
  page227_i47
#CELL
  mstr_discrete cap *
  page227_i48
#CELL
  mstr_discrete cap *
  page227_i50
#CELL
  dev_discrete cap_a *
  page227_i51
#CELL
  mstr_discrete cap *
  page227_i54
#ISCELL
  mstr_standard offpage *
  page227_i58
#CELL
  mstr_discrete cap *
  page227_i6
#ISCELL
  mstr_standard offpage *
  page227_i61
#ISCELL
  mstr_standard offpage *
  page227_i62
#ISCELL
  mstr_standard offpage *
  page227_i63
#ISCELL
  mstr_symbols pvddq_klm *
  page227_i64
#CELL
  mstr_discrete cap *
  page227_i68
#ISCELL
  mstr_symbols gnd *
  page227_i69
#ISCELL
  mstr_symbols gnd *
  page227_i7
#ISCELL
  mstr_symbols gnd *
  page227_i70
#CELL
  mstr_discrete cap *
  page227_i72
#CELL
  mstr_discrete cap *
  page227_i75
#CELL
  mstr_discrete cap *
  page227_i77
#CELL
  dev_discrete cap_a *
  page227_i78
#CELL
  mstr_discrete cap *
  page227_i79
#CELL
  mstr_discrete cap *
  page227_i80
#CELL
  mstr_discrete cap *
  page227_i81
#ISCELL
  mstr_standard offpage *
  page227_i82
#ISCELL
  mstr_symbols vcc_core *
  page227_i83
#CELL
  mstr_discrete cap *
  page227_i84
#ISCELL
  mstr_symbols gnd *
  page227_i85
#ISCELL
  mstr_symbols vcc_core *
  page227_i86
#ISCELL
  mstr_symbols p5v_stby *
  page227_i88
#ISCELL
  mstr_misc dns *
  *
#ISCELL
  mstr_symbols intel_corp_bpage *
  *
#ISCELL
  mstr_symbols pvddq_klm *
  page228_i109
#ISCELL
  mstr_symbols gnd *
  page228_i114
#ISCELL
  mstr_symbols vcc_core *
  page228_i120
#ISCELL
  mstr_symbols gnd *
  page228_i123
#CELL
  mstr_discrete capp *
  page228_i175
#ISCELL
  mstr_symbols p12v_stby *
  page228_i182
#ISCELL
  mstr_symbols gnd *
  page228_i189
#ISCELL
  mstr_symbols pvddq_klm *
  page228_i191
#ISCELL
  mstr_symbols pvddq_klm *
  page228_i195
#ISCELL
  mstr_symbols gnd *
  page228_i197
#CELL
  dev_discrete cap_a *
  page228_i198
#CELL
  dev_discrete cap_a *
  page228_i199
#CELL
  dev_discrete cap_a *
  page228_i200
#CELL
  dev_discrete cap_a *
  page228_i201
#CELL
  dev_discrete cap_a *
  page228_i202
#CELL
  dev_discrete cap_a *
  page228_i203
#CELL
  dev_discrete cap_a *
  page228_i204
#CELL
  dev_discrete cap_a *
  page228_i205
#CELL
  dev_discrete cap_a *
  page228_i206
#ISCELL
  mstr_symbols pvddq_klm *
  page228_i207
#ISCELL
  mstr_symbols gnd *
  page228_i208
#ISCELL
  mstr_symbols pvddq_klm *
  page228_i224
#ISCELL
  mstr_symbols gnd *
  page228_i226
#ISCELL
  mstr_symbols pvddq_klm *
  page228_i242
#ISCELL
  mstr_symbols gnd *
  page228_i244
#CELL
  mstr_misc shunt *
  page228_i245
#CELL
  mstr_misc shunt *
  page228_i246
#CELL
  w_hdl ind-100nh-35-gp *
  page228_i247
#ISCELL
  mstr_symbols pvddq_klm *
  page228_i252
#ISCELL
  mstr_symbols gnd *
  page228_i253
#CELL
  dev_discrete cap_a *
  page228_i255
#CELL
  dev_discrete cap_a *
  page228_i256
#CELL
  dev_discrete cap_a *
  page228_i257
#CELL
  dev_discrete cap_a *
  page228_i258
#ISCELL
  mstr_symbols gnd *
  page228_i259
#ISCELL
  mstr_symbols pvddq_klm *
  page228_i260
#ISCELL
  mstr_symbols gnd *
  page228_i262
#ISCELL
  mstr_symbols pvddq_klm *
  page228_i263
#CELL
  dev_discrete cap_a *
  page228_i264
#CELL
  dev_discrete cap_a *
  page228_i265
#CELL
  dev_discrete cap_a *
  page228_i266
#CELL
  dev_discrete cap_a *
  page228_i267
#CELL
  dev_discrete cap_a *
  page228_i268
#CELL
  dev_discrete cap_a *
  page228_i269
#CELL
  dev_discrete cap_a *
  page228_i270
#CELL
  dev_discrete cap_a *
  page228_i271
#CELL
  dev_discrete cap_a *
  page228_i272
#CELL
  dev_discrete cap_a *
  page228_i273
#CELL
  dev_discrete cap_a *
  page228_i274
#CELL
  dev_discrete cap_a *
  page228_i275
#CELL
  dev_discrete cap_a *
  page228_i276
#CELL
  dev_discrete cap_a *
  page228_i277
#CELL
  dev_discrete cap_a *
  page228_i278
#CELL
  dev_discrete cap_a *
  page228_i279
#CELL
  dev_discrete cap_a *
  page228_i280
#CELL
  dev_discrete cap_a *
  page228_i281
#CELL
  dev_discrete cap_a *
  page228_i282
#CELL
  dev_discrete cap_a *
  page228_i283
#CELL
  dev_discrete cap_a *
  page228_i284
#CELL
  dev_discrete cap_a *
  page228_i285
#CELL
  dev_discrete cap_a *
  page228_i286
#CELL
  dev_discrete cap_a *
  page228_i287
#CELL
  dev_discrete cap_a *
  page228_i288
#CELL
  dev_discrete cap_a *
  page228_i289
#CELL
  dev_discrete cap_a *
  page228_i290
#CELL
  dev_discrete cap_a *
  page228_i291
#CELL
  dev_discrete cap_a *
  page228_i292
#CELL
  dev_discrete cap_a *
  page228_i293
#CELL
  dev_discrete cap_a *
  page228_i294
#CELL
  dev_discrete cap_a *
  page228_i295
#CELL
  dev_discrete cap_a *
  page228_i296
#CELL
  dev_discrete cap_a *
  page228_i297
#CELL
  dev_discrete cap_a *
  page228_i298
#CELL
  dev_discrete cap_a *
  page228_i299
#CELL
  mstr_discrete cap *
  page228_i301
#CELL
  mstr_discrete cap *
  page228_i302
#CELL
  mstr_discrete cap *
  page228_i303
#CELL
  mstr_discrete cap *
  page228_i304
#CELL
  mstr_discrete cap *
  page228_i305
#CELL
  mstr_discrete cap *
  page228_i306
#CELL
  mstr_discrete cap *
  page228_i307
#CELL
  mstr_discrete cap *
  page228_i308
#CELL
  mstr_discrete cap *
  page228_i309
#CELL
  mstr_discrete cap *
  page228_i310
#CELL
  mstr_discrete cap *
  page228_i311
#CELL
  mstr_discrete cap *
  page228_i312
#CELL
  mstr_discrete cap *
  page228_i313
#CELL
  mstr_discrete cap *
  page228_i314
#CELL
  mstr_discrete res *
  page228_i58
#ISCELL
  mstr_symbols gnd *
  page228_i65
#ISCELL
  mstr_standard offpage *
  page228_i70
#ISCELL
  mstr_standard offpage *
  page228_i72
#ISCELL
  mstr_symbols pvddq_klm *
  page228_i73
#CELL
  mstr_discrete res *
  page228_i74
#CELL
  mstr_discrete capp *
  page228_i75
#CELL
  mstr_discrete capp *
  page228_i76
#CELL
  mstr_discrete capp *
  page228_i77
#CELL
  mstr_discrete capp *
  page228_i78
#ISCELL
  mstr_symbols pvddq_klm *
  page228_i80
#ISCELL
  mstr_symbols gnd *
  page228_i81
#ISCELL
  mstr_symbols pvddq_klm *
  page228_i93
#ISCELL
  mstr_symbols gnd *
  page228_i94
#ISCELL
  mstr_misc dns *
  *
#ISCELL
  mstr_misc prelim *
  *
#ISCELL
  mstr_symbols cad_note *
  *
#ISCELL
  mstr_symbols intel_corp_bpage *
  *
#ISCELL
  mstr_symbols gnd *
  page229_i1
#ISCELL
  mstr_symbols gnd *
  page229_i10
#CELL
  mstr_discrete cap *
  page229_i11
#CELL
  mstr_misc shunt *
  page229_i12
#ISCELL
  mstr_symbols gnd *
  page229_i13
#CELL
  mstr_discrete cap *
  page229_i14
#ISCELL
  mstr_symbols gnd *
  page229_i15
#CELL
  mstr_discrete cap *
  page229_i16
#ISCELL
  mstr_symbols gnd *
  page229_i17
#CELL
  mstr_discrete cap *
  page229_i18
#ISCELL
  mstr_symbols gnd *
  page229_i19
#CELL
  mstr_discrete cap *
  page229_i2
#ISCELL
  mstr_symbols gnd *
  page229_i20
#CELL
  mstr_discrete cap *
  page229_i21
#ISCELL
  mstr_symbols gnd *
  page229_i22
#CELL
  mstr_discrete cap *
  page229_i23
#CELL
  mstr_discrete res *
  page229_i24
#ISCELL
  mstr_symbols gnd *
  page229_i25
#CELL
  mstr_discrete cap *
  page229_i26
#ISCELL
  mstr_symbols p3v3 *
  page229_i27
#CELL
  dev_discrete cap_a *
  page229_i28
#ISCELL
  mstr_symbols pvtt_ghj *
  page229_i29
#ISCELL
  mstr_standard offpage *
  page229_i3
#CELL
  mstr_discrete res *
  page229_i32
#ISCELL
  mstr_standard offpage *
  page229_i33
#ISCELL
  mstr_symbols pvtt_ghj *
  page229_i34
#ISCELL
  mstr_symbols gnd *
  page229_i35
#CELL
  mstr_vreg mic5166 *
  page229_i37
#CELL
  mstr_discrete res *
  page229_i4
#CELL
  mstr_discrete cap *
  page229_i41
#CELL
  mstr_discrete cap *
  page229_i42
#CELL
  mstr_discrete cap *
  page229_i43
#CELL
  mstr_discrete res *
  page229_i5
#CELL
  mstr_discrete res *
  page229_i6
#ISCELL
  mstr_symbols p3v3 *
  page229_i7
#ISCELL
  mstr_symbols pvddq_ghj *
  page229_i8
#CELL
  mstr_discrete res *
  page229_i9
#ISCELL
  mstr_misc dns *
  *
#ISCELL
  mstr_misc prelim *
  *
#ISCELL
  mstr_symbols cad_note *
  *
#ISCELL
  mstr_symbols intel_corp_bpage *
  *
#ISCELL
  mstr_symbols gnd *
  page230_i1
#CELL
  mstr_discrete cap *
  page230_i10
#ISCELL
  mstr_symbols gnd *
  page230_i11
#CELL
  mstr_discrete cap *
  page230_i12
#CELL
  mstr_discrete res *
  page230_i13
#ISCELL
  mstr_symbols gnd *
  page230_i14
#ISCELL
  mstr_symbols gnd *
  page230_i15
#ISCELL
  mstr_symbols gnd *
  page230_i16
#CELL
  mstr_discrete cap *
  page230_i17
#ISCELL
  mstr_symbols gnd *
  page230_i18
#ISCELL
  mstr_symbols gnd *
  page230_i19
#CELL
  mstr_discrete cap *
  page230_i2
#CELL
  mstr_discrete cap *
  page230_i20
#CELL
  mstr_discrete res *
  page230_i21
#ISCELL
  mstr_symbols gnd *
  page230_i22
#CELL
  mstr_discrete cap *
  page230_i23
#CELL
  dev_discrete cap_a *
  page230_i24
#ISCELL
  mstr_symbols pvtt_klm *
  page230_i25
#ISCELL
  mstr_symbols p3v3 *
  page230_i26
#ISCELL
  mstr_symbols gnd *
  page230_i27
#ISCELL
  mstr_standard offpage *
  page230_i3
#CELL
  mstr_misc shunt *
  page230_i30
#CELL
  mstr_discrete res *
  page230_i32
#ISCELL
  mstr_standard offpage *
  page230_i33
#ISCELL
  mstr_symbols pvtt_klm *
  page230_i34
#CELL
  mstr_discrete cap *
  page230_i35
#CELL
  mstr_discrete cap *
  page230_i36
#CELL
  mstr_vreg mic5166 *
  page230_i37
#CELL
  mstr_discrete res *
  page230_i4
#CELL
  mstr_discrete cap *
  page230_i41
#CELL
  mstr_discrete cap *
  page230_i42
#CELL
  mstr_discrete cap *
  page230_i43
#CELL
  mstr_discrete res *
  page230_i5
#CELL
  mstr_discrete res *
  page230_i6
#ISCELL
  mstr_symbols p3v3 *
  page230_i7
#ISCELL
  mstr_symbols pvddq_klm *
  page230_i8
#ISCELL
  mstr_symbols gnd *
  page230_i9
#ISCELL
  mstr_misc dns *
  *
#ISCELL
  mstr_symbols cad_note *
  *
#ISCELL
  mstr_symbols intel_corp_bpage *
  *
#CELL
  mstr_discrete cap *
  page231_i122
#ISCELL
  mstr_symbols pvpp_abc *
  page231_i123
#CELL
  mstr_discrete cap *
  page231_i124
#CELL
  mstr_discrete cap *
  page231_i125
#CELL
  mstr_discrete cap *
  page231_i126
#ISCELL
  mstr_symbols gnd *
  page231_i127
#CELL
  mstr_discrete cap *
  page231_i128
#CELL
  mstr_discrete cap *
  page231_i129
#CELL
  mstr_discrete cap *
  page231_i130
#CELL
  mstr_discrete cap *
  page231_i131
#ISCELL
  mstr_symbols agnd_scsi *
  page231_i132
#CELL
  mstr_discrete res *
  page231_i134
#ISCELL
  mstr_standard offpage *
  page231_i135
#CELL
  mstr_discrete res *
  page231_i136
#CELL
  mstr_discrete cap *
  page231_i140
#ISCELL
  mstr_symbols gnd *
  page231_i141
#CELL
  mstr_discrete cap *
  page231_i142
#CELL
  mstr_discrete res *
  page231_i143
#CELL
  mstr_discrete cap *
  page231_i145
#CELL
  mstr_discrete cap *
  page231_i146
#ISCELL
  mstr_symbols gnd *
  page231_i147
#CELL
  mstr_discrete cap *
  page231_i148
#CELL
  mstr_discrete cap *
  page231_i149
#CELL
  mstr_discrete cap *
  page231_i159
#ISCELL
  mstr_symbols gnd *
  page231_i160
#CELL
  mstr_discrete cap *
  page231_i161
#CELL
  mstr_discrete ferrite *
  page231_i162
#ISCELL
  mstr_symbols p12v_stby *
  page231_i163
#ISCELL
  mstr_symbols agnd_scsi *
  page231_i165
#CELL
  mstr_discrete res *
  page231_i167
#CELL
  mstr_discrete res *
  page231_i168
#ISCELL
  mstr_symbols gnd *
  page231_i169
#CELL
  mstr_discrete res *
  page231_i170
#ISCELL
  mstr_symbols agnd_scsi *
  page231_i171
#ISCELL
  mstr_symbols gnd *
  page231_i173
#CELL
  mstr_discrete res *
  page231_i174
#CELL
  mstr_discrete cap *
  page231_i175
#ISCELL
  mstr_symbols gnd *
  page231_i176
#CELL
  mstr_discrete res *
  page231_i177
#CELL
  mstr_discrete inductor *
  page231_i178
#ISCELL
  mstr_symbols gnd *
  page231_i179
#CELL
  mstr_discrete capp *
  page231_i180
#ISCELL
  mstr_symbols gnd *
  page231_i183
#CELL
  mstr_discrete cap *
  page231_i184
#ISCELL
  mstr_symbols gnd *
  page231_i185
#CELL
  mstr_discrete cap *
  page231_i186
#ISCELL
  mstr_symbols pvpp_abc *
  page231_i187
#ISCELL
  mstr_standard offpage *
  page231_i188
#ISCELL
  mstr_symbols agnd_scsi *
  page231_i189
#ISCELL
  mstr_symbols agnd_scsi *
  page231_i190
#ISCELL
  mstr_symbols p3v3_stby *
  page231_i192
#CELL
  mstr_vreg ncp3232l *
  page231_i193
#CELL
  mstr_discrete cap *
  page231_i194
#ISCELL
  mstr_symbols agnd_scsi *
  page231_i195
#ISCELL
  mstr_symbols gnd *
  page231_i196
#CELL
  mstr_discrete cap *
  page231_i199
#CELL
  mstr_discrete cap *
  page231_i200
#CELL
  mstr_discrete res *
  page231_i201
#CELL
  mstr_discrete cap *
  page231_i202
#ISCELL
  mstr_symbols agnd_scsi *
  page231_i203
#ISCELL
  mstr_symbols agnd_scsi *
  page231_i204
#CELL
  dev_discrete cap_a *
  page231_i205
#ISCELL
  mstr_symbols gnd *
  page231_i206
#CELL
  mstr_discrete res *
  page231_i208
#CELL
  mstr_discrete cap *
  page231_i209
#CELL
  mstr_discrete cap *
  page231_i210
#CELL
  mstr_discrete cap *
  page231_i211
#ISCELL
  mstr_symbols gnd *
  page231_i212
#ISCELL
  mstr_symbols gnd *
  page231_i213
#ISCELL
  mstr_symbols gnd *
  page231_i214
#CELL
  mstr_discrete cap *
  page231_i215
#ISCELL
  mstr_symbols gnd *
  page231_i216
#CELL
  mstr_discrete capp *
  page231_i217
#CELL
  mstr_discrete res *
  page231_i218
#CELL
  mstr_discrete cap *
  page231_i219
#CELL
  mstr_discrete res *
  page231_i220
#ISCELL
  mstr_symbols gnd *
  page231_i222
#CELL
  w_hdl sc22u16v5mx-4-gp *
  page231_i225
#CELL
  w_hdl sc22u16v5mx-4-gp *
  page231_i226
#ISCELL
  mstr_symbols gnd *
  page231_i228
#CELL
  mstr_discrete res *
  page231_i229
#CELL
  mstr_discrete res *
  page231_i230
#ISCELL
  mstr_misc dns *
  *
#ISCELL
  mstr_symbols intel_corp_bpage *
  *
#CELL
  mstr_discrete cap *
  page232_i102
#ISCELL
  mstr_symbols pvpp_def *
  page232_i103
#CELL
  mstr_discrete cap *
  page232_i104
#CELL
  mstr_discrete cap *
  page232_i105
#CELL
  mstr_discrete cap *
  page232_i106
#CELL
  mstr_discrete cap *
  page232_i108
#CELL
  mstr_discrete cap *
  page232_i109
#CELL
  mstr_discrete cap *
  page232_i110
#CELL
  mstr_discrete cap *
  page232_i111
#CELL
  mstr_discrete cap *
  page232_i125
#CELL
  mstr_discrete cap *
  page232_i126
#ISCELL
  mstr_symbols gnd *
  page232_i127
#CELL
  mstr_discrete cap *
  page232_i128
#CELL
  mstr_discrete cap *
  page232_i129
#ISCELL
  mstr_symbols gnd *
  page232_i149
#CELL
  mstr_discrete res *
  page232_i150
#ISCELL
  mstr_symbols agnd_scsi *
  page232_i151
#ISCELL
  mstr_symbols pvpp_def *
  page232_i167
#ISCELL
  mstr_standard offpage *
  page232_i181
#CELL
  mstr_discrete cap *
  page232_i185
#CELL
  mstr_discrete cap *
  page232_i197
#ISCELL
  mstr_symbols gnd *
  page232_i198
#ISCELL
  mstr_symbols p12v_stby *
  page232_i199
#CELL
  mstr_discrete ferrite *
  page232_i200
#CELL
  mstr_discrete cap *
  page232_i207
#ISCELL
  mstr_symbols gnd *
  page232_i208
#CELL
  mstr_discrete cap *
  page232_i209
#CELL
  mstr_discrete res *
  page232_i210
#ISCELL
  mstr_symbols p3v3_stby *
  page232_i211
#ISCELL
  mstr_standard offpage *
  page232_i212
#CELL
  mstr_vreg ncp3232l *
  page232_i214
#ISCELL
  mstr_symbols gnd *
  page232_i215
#CELL
  mstr_discrete res *
  page232_i218
#ISCELL
  mstr_symbols gnd *
  page232_i219
#CELL
  mstr_discrete cap *
  page232_i220
#ISCELL
  mstr_symbols gnd *
  page232_i226
#CELL
  mstr_discrete res *
  page232_i227
#ISCELL
  mstr_symbols gnd *
  page232_i228
#CELL
  mstr_discrete capp *
  page232_i229
#ISCELL
  mstr_symbols gnd *
  page232_i235
#CELL
  mstr_discrete cap *
  page232_i236
#ISCELL
  mstr_symbols gnd *
  page232_i237
#CELL
  mstr_discrete cap *
  page232_i238
#CELL
  mstr_discrete inductor *
  page232_i239
#CELL
  mstr_discrete cap *
  page232_i241
#ISCELL
  mstr_symbols agnd_scsi *
  page232_i247
#ISCELL
  mstr_symbols agnd_scsi *
  page232_i248
#ISCELL
  mstr_symbols agnd_scsi *
  page232_i249
#ISCELL
  mstr_symbols agnd_scsi *
  page232_i250
#ISCELL
  mstr_symbols agnd_scsi *
  page232_i251
#CELL
  dev_discrete cap_a *
  page232_i252
#CELL
  mstr_discrete cap *
  page232_i253
#ISCELL
  mstr_symbols agnd_scsi *
  page232_i254
#ISCELL
  mstr_symbols gnd *
  page232_i255
#CELL
  mstr_discrete res *
  page232_i257
#CELL
  mstr_discrete cap *
  page232_i259
#CELL
  mstr_discrete cap *
  page232_i260
#CELL
  mstr_discrete cap *
  page232_i261
#CELL
  mstr_discrete cap *
  page232_i262
#ISCELL
  mstr_symbols gnd *
  page232_i263
#ISCELL
  mstr_symbols gnd *
  page232_i264
#ISCELL
  mstr_symbols gnd *
  page232_i265
#ISCELL
  mstr_symbols gnd *
  page232_i266
#CELL
  mstr_discrete capp *
  page232_i267
#CELL
  mstr_discrete res *
  page232_i298
#CELL
  mstr_discrete res *
  page232_i299
#CELL
  mstr_discrete res *
  page232_i300
#CELL
  mstr_discrete cap *
  page232_i301
#CELL
  mstr_discrete cap *
  page232_i302
#CELL
  mstr_discrete res *
  page232_i303
#CELL
  mstr_discrete cap *
  page232_i306
#CELL
  mstr_discrete res *
  page232_i307
#ISCELL
  mstr_symbols agnd_scsi *
  page232_i308
#CELL
  w_hdl sc22u16v5mx-4-gp *
  page232_i309
#ISCELL
  mstr_symbols gnd *
  page232_i310
#CELL
  w_hdl sc22u16v5mx-4-gp *
  page232_i311
#ISCELL
  mstr_symbols gnd *
  page232_i312
#CELL
  mstr_discrete res *
  page232_i313
#CELL
  mstr_discrete res *
  page232_i314
#CELL
  mstr_discrete res *
  page232_i315
#ISCELL
  mstr_misc dns *
  *
#ISCELL
  mstr_symbols intel_corp_bpage *
  *
#CELL
  mstr_discrete cap *
  page233_i109
#ISCELL
  mstr_symbols pvpp_ghj *
  page233_i110
#CELL
  mstr_discrete cap *
  page233_i111
#CELL
  mstr_discrete cap *
  page233_i112
#CELL
  mstr_discrete cap *
  page233_i113
#CELL
  mstr_discrete cap *
  page233_i115
#CELL
  mstr_discrete cap *
  page233_i116
#CELL
  mstr_discrete cap *
  page233_i117
#CELL
  mstr_discrete cap *
  page233_i118
#CELL
  mstr_discrete cap *
  page233_i132
#CELL
  mstr_discrete cap *
  page233_i133
#ISCELL
  mstr_symbols gnd *
  page233_i134
#CELL
  mstr_discrete cap *
  page233_i135
#CELL
  mstr_discrete cap *
  page233_i136
#ISCELL
  mstr_symbols gnd *
  page233_i156
#CELL
  mstr_discrete res *
  page233_i157
#ISCELL
  mstr_symbols agnd_scsi *
  page233_i158
#ISCELL
  mstr_symbols pvpp_ghj *
  page233_i174
#ISCELL
  mstr_symbols gnd *
  page233_i180
#ISCELL
  mstr_standard offpage *
  page233_i181
#CELL
  mstr_discrete res *
  page233_i182
#CELL
  mstr_discrete cap *
  page233_i183
#CELL
  mstr_discrete res *
  page233_i185
#ISCELL
  mstr_symbols p3v3_stby *
  page233_i186
#CELL
  mstr_discrete cap *
  page233_i187
#CELL
  mstr_discrete cap *
  page233_i194
#ISCELL
  mstr_symbols gnd *
  page233_i195
#CELL
  mstr_discrete cap *
  page233_i196
#ISCELL
  mstr_symbols p12v_stby *
  page233_i197
#CELL
  mstr_discrete ferrite *
  page233_i198
#ISCELL
  mstr_symbols gnd *
  page233_i200
#CELL
  mstr_discrete cap *
  page233_i201
#ISCELL
  mstr_standard offpage *
  page233_i202
#ISCELL
  mstr_symbols gnd *
  page233_i203
#ISCELL
  mstr_symbols gnd *
  page233_i207
#CELL
  mstr_discrete res *
  page233_i208
#CELL
  mstr_discrete cap *
  page233_i209
#ISCELL
  mstr_symbols gnd *
  page233_i210
#CELL
  mstr_discrete res *
  page233_i211
#ISCELL
  mstr_symbols gnd *
  page233_i216
#CELL
  mstr_discrete capp *
  page233_i217
#ISCELL
  mstr_symbols gnd *
  page233_i220
#CELL
  mstr_discrete cap *
  page233_i221
#ISCELL
  mstr_symbols gnd *
  page233_i222
#CELL
  mstr_discrete cap *
  page233_i223
#CELL
  mstr_discrete cap *
  page233_i224
#CELL
  mstr_vreg ncp3232l *
  page233_i225
#ISCELL
  mstr_symbols agnd_scsi *
  page233_i226
#ISCELL
  mstr_symbols agnd_scsi *
  page233_i227
#ISCELL
  mstr_symbols agnd_scsi *
  page233_i228
#ISCELL
  mstr_symbols agnd_scsi *
  page233_i229
#ISCELL
  mstr_symbols agnd_scsi *
  page233_i230
#CELL
  dev_discrete cap_a *
  page233_i242
#ISCELL
  mstr_symbols gnd *
  page233_i243
#ISCELL
  mstr_symbols agnd_scsi *
  page233_i244
#ISCELL
  mstr_symbols gnd *
  page233_i246
#CELL
  mstr_discrete res *
  page233_i247
#CELL
  mstr_discrete cap *
  page233_i248
#ISCELL
  mstr_symbols gnd *
  page233_i249
#ISCELL
  mstr_symbols gnd *
  page233_i250
#ISCELL
  mstr_symbols gnd *
  page233_i251
#ISCELL
  mstr_symbols gnd *
  page233_i252
#CELL
  mstr_discrete cap *
  page233_i253
#CELL
  mstr_discrete cap *
  page233_i254
#CELL
  mstr_discrete cap *
  page233_i255
#CELL
  mstr_discrete capp *
  page233_i256
#CELL
  mstr_discrete res *
  page233_i266
#CELL
  mstr_discrete cap *
  page233_i267
#CELL
  mstr_discrete res *
  page233_i270
#CELL
  mstr_discrete res *
  page233_i271
#CELL
  mstr_discrete res *
  page233_i272
#CELL
  mstr_discrete cap *
  page233_i273
#CELL
  mstr_discrete cap *
  page233_i274
#CELL
  mstr_discrete res *
  page233_i275
#ISCELL
  mstr_symbols agnd_scsi *
  page233_i276
#CELL
  mstr_discrete inductor *
  page233_i277
#CELL
  w_hdl sc22u16v5mx-4-gp *
  page233_i278
#ISCELL
  mstr_symbols gnd *
  page233_i279
#CELL
  w_hdl sc22u16v5mx-4-gp *
  page233_i280
#ISCELL
  mstr_symbols gnd *
  page233_i281
#CELL
  mstr_discrete res *
  page233_i282
#CELL
  mstr_discrete res *
  page233_i283
#CELL
  mstr_discrete res *
  page233_i284
#ISCELL
  mstr_misc dns *
  *
#ISCELL
  mstr_symbols intel_corp_bpage *
  *
#ISCELL
  mstr_standard offpage *
  page234_i118
#CELL
  mstr_discrete cap *
  page234_i129
#ISCELL
  mstr_symbols gnd *
  page234_i138
#CELL
  mstr_discrete cap *
  page234_i139
#ISCELL
  mstr_symbols p3v3_stby *
  page234_i142
#CELL
  mstr_discrete res *
  page234_i143
#CELL
  mstr_discrete cap *
  page234_i144
#CELL
  mstr_discrete cap *
  page234_i146
#ISCELL
  mstr_symbols gnd *
  page234_i151
#CELL
  mstr_discrete cap *
  page234_i152
#ISCELL
  mstr_symbols p12v_stby *
  page234_i153
#CELL
  mstr_discrete ferrite *
  page234_i154
#ISCELL
  mstr_standard offpage *
  page234_i156
#ISCELL
  mstr_symbols gnd *
  page234_i157
#ISCELL
  mstr_symbols gnd *
  page234_i161
#CELL
  mstr_discrete res *
  page234_i162
#CELL
  mstr_discrete cap *
  page234_i163
#CELL
  mstr_discrete inductor *
  page234_i164
#ISCELL
  mstr_symbols gnd *
  page234_i165
#ISCELL
  mstr_symbols gnd *
  page234_i166
#CELL
  mstr_discrete capp *
  page234_i167
#ISCELL
  mstr_symbols gnd *
  page234_i175
#CELL
  mstr_discrete cap *
  page234_i177
#ISCELL
  mstr_symbols gnd *
  page234_i178
#ISCELL
  mstr_symbols gnd *
  page234_i179
#CELL
  mstr_discrete cap *
  page234_i180
#CELL
  mstr_discrete cap *
  page234_i182
#CELL
  mstr_discrete res *
  page234_i183
#CELL
  mstr_vreg ncp3232l *
  page234_i184
#ISCELL
  mstr_symbols pvpp_klm *
  page234_i185
#ISCELL
  mstr_symbols agnd_scsi *
  page234_i187
#ISCELL
  mstr_symbols agnd_scsi *
  page234_i188
#ISCELL
  mstr_symbols agnd_scsi *
  page234_i189
#ISCELL
  mstr_symbols agnd_scsi *
  page234_i190
#ISCELL
  mstr_symbols agnd_scsi *
  page234_i191
#ISCELL
  mstr_symbols gnd *
  page234_i198
#CELL
  dev_discrete cap_a *
  page234_i199
#ISCELL
  mstr_symbols agnd_scsi *
  page234_i200
#CELL
  mstr_discrete res *
  page234_i201
#CELL
  mstr_discrete cap *
  page234_i202
#CELL
  mstr_discrete cap *
  page234_i203
#CELL
  mstr_discrete cap *
  page234_i204
#CELL
  mstr_discrete cap *
  page234_i205
#ISCELL
  mstr_symbols gnd *
  page234_i206
#ISCELL
  mstr_symbols gnd *
  page234_i207
#ISCELL
  mstr_symbols gnd *
  page234_i208
#ISCELL
  mstr_symbols gnd *
  page234_i209
#CELL
  mstr_discrete capp *
  page234_i210
#CELL
  mstr_discrete cap *
  page234_i211
#CELL
  mstr_discrete cap *
  page234_i212
#CELL
  mstr_discrete res *
  page234_i213
#CELL
  mstr_discrete res *
  page234_i214
#CELL
  mstr_discrete res *
  page234_i215
#CELL
  mstr_discrete cap *
  page234_i218
#CELL
  mstr_discrete res *
  page234_i219
#CELL
  mstr_discrete res *
  page234_i220
#ISCELL
  mstr_symbols agnd_scsi *
  page234_i221
#CELL
  w_hdl sc22u16v5mx-4-gp *
  page234_i222
#CELL
  w_hdl sc22u16v5mx-4-gp *
  page234_i223
#ISCELL
  mstr_symbols gnd *
  page234_i224
#ISCELL
  mstr_symbols gnd *
  page234_i225
#CELL
  mstr_discrete res *
  page234_i226
#CELL
  mstr_discrete res *
  page234_i227
#CELL
  mstr_discrete res *
  page234_i228
#ISCELL
  mstr_symbols gnd *
  page234_i27
#ISCELL
  mstr_symbols agnd_scsi *
  page234_i28
#CELL
  mstr_discrete res *
  page234_i29
#CELL
  mstr_discrete cap *
  page234_i84
#ISCELL
  mstr_symbols gnd *
  page234_i85
#CELL
  mstr_discrete cap *
  page234_i86
#CELL
  mstr_discrete cap *
  page234_i87
#CELL
  mstr_discrete cap *
  page234_i88
#CELL
  mstr_discrete cap *
  page234_i89
#CELL
  mstr_discrete cap *
  page234_i90
#CELL
  mstr_discrete cap *
  page234_i91
#CELL
  mstr_discrete cap *
  page234_i92
#CELL
  mstr_discrete cap *
  page234_i93
#CELL
  mstr_discrete cap *
  page234_i94
#CELL
  mstr_discrete cap *
  page234_i95
#ISCELL
  mstr_symbols pvpp_klm *
  page234_i96
#CELL
  mstr_discrete cap *
  page234_i97
#ISCELL
  mstr_misc dns *
  *
#ISCELL
  mstr_symbols design_note *
  *
#ISCELL
  mstr_symbols intel_corp_bpage *
  *
#ISCELL
  mstr_symbols p3v3_stby *
  page235_i135
#ISCELL
  mstr_standard offpage *
  page235_i136
#ISCELL
  mstr_standard offpage *
  page235_i139
#ISCELL
  mstr_standard offpage *
  page235_i142
#CELL
  dev_discrete cap_a *
  page235_i143
#ISCELL
  mstr_symbols gnd *
  page235_i144
#CELL
  dev_discrete cap_a *
  page235_i145
#ISCELL
  mstr_symbols gnd *
  page235_i146
#CELL
  mstr_discrete res *
  page235_i147
#CELL
  mstr_discrete res *
  page235_i148
#CELL
  mstr_discrete res *
  page235_i149
#CELL
  dev_discrete cap_a *
  page235_i151
#ISCELL
  mstr_symbols gnd *
  page235_i152
#CELL
  mstr_discrete cap *
  page235_i153
#CELL
  mstr_discrete res *
  page235_i154
#ISCELL
  mstr_symbols gnd *
  page235_i155
#ISCELL
  mstr_standard offpage *
  page235_i156
#ISCELL
  mstr_standard offpage *
  page235_i157
#ISCELL
  mstr_symbols p3v3_stby *
  page235_i158
#CELL
  mstr_discrete res *
  page235_i159
#CELL
  mstr_discrete res *
  page235_i165
#CELL
  mstr_discrete res *
  page235_i166
#ISCELL
  mstr_standard offpage *
  page235_i168
#CELL
  dev_discrete cap_a *
  page235_i169
#ISCELL
  mstr_symbols gnd *
  page235_i170
#ISCELL
  mstr_symbols gnd *
  page235_i178
#ISCELL
  mstr_symbols gnd *
  page235_i181
#ISCELL
  mstr_symbols gnd *
  page235_i183
#ISCELL
  mstr_standard offpage *
  page235_i185
#ISCELL
  mstr_standard offpage *
  page235_i186
#ISCELL
  mstr_standard offpage *
  page235_i187
#ISCELL
  mstr_standard offpage *
  page235_i188
#ISCELL
  mstr_standard offpage *
  page235_i189
#ISCELL
  mstr_standard offpage *
  page235_i191
#ISCELL
  mstr_standard offpage *
  page235_i194
#ISCELL
  mstr_standard offpage *
  page235_i195
#ISCELL
  mstr_standard offpage *
  page235_i198
#ISCELL
  mstr_standard offpage *
  page235_i199
#ISCELL
  mstr_standard offpage *
  page235_i200
#CELL
  mstr_discrete cap *
  page235_i209
#CELL
  mstr_discrete res *
  page235_i210
#ISCELL
  mstr_standard offpage *
  page235_i211
#ISCELL
  mstr_standard offpage *
  page235_i212
#ISCELL
  mstr_standard offpage *
  page235_i215
#CELL
  mstr_discrete res *
  page235_i216
#CELL
  mstr_discrete res *
  page235_i217
#CELL
  mstr_discrete cap *
  page235_i218
#ISCELL
  mstr_symbols gnd *
  page235_i219
#CELL
  mstr_discrete res *
  page235_i221
#CELL
  mstr_discrete res *
  page235_i222
#ISCELL
  mstr_symbols vcc_core *
  page235_i228
#CELL
  mstr_controller pxe1110b *
  page235_i229
#ISCELL
  mstr_standard offpage *
  page235_i232
#ISCELL
  mstr_standard offpage *
  page235_i234
#CELL
  w_hdl sc22p50v2jn-4gp *
  page235_i239
#CELL
  w_hdl sc22p50v2jn-4gp *
  page235_i240
#CELL
  mstr_discrete res *
  page235_i241
#CELL
  mstr_discrete res *
  page235_i242
#ISCELL
  mstr_symbols gnd *
  page235_i243
#CELL
  mstr_discrete cap *
  page235_i244
#ISCELL
  mstr_symbols gnd *
  page235_i245
#CELL
  mstr_discrete cap *
  page235_i246
#CELL
  mstr_discrete res *
  page235_i247
#CELL
  mstr_discrete res *
  page235_i248
#CELL
  mstr_discrete res *
  page235_i249
#CELL
  mstr_discrete res *
  page235_i252
#CELL
  mstr_discrete res *
  page235_i253
#CELL
  mstr_discrete res *
  page235_i254
#CELL
  dev_discrete cap_a *
  page235_i255
#ISCELL
  mstr_misc dns *
  *
#ISCELL
  mstr_symbols intel_corp_bpage *
  *
#ISCELL
  mstr_standard offpage *
  page236_i1
#ISCELL
  mstr_symbols gnd *
  page236_i11
#CELL
  mstr_discrete ir354xx *
  page236_i116
#CELL
  mstr_discrete ir354xx *
  page236_i117
#CELL
  mstr_discrete res *
  page236_i118
#ISCELL
  mstr_symbols gnd *
  page236_i119
#CELL
  mstr_discrete res *
  page236_i120
#ISCELL
  mstr_symbols gnd *
  page236_i121
#ISCELL
  mstr_symbols p5v_stby *
  page236_i122
#CELL
  dev_discrete cap_a *
  page236_i124
#ISCELL
  mstr_symbols gnd *
  page236_i125
#ISCELL
  mstr_symbols gnd *
  page236_i126
#CELL
  dev_discrete cap_a *
  page236_i127
#ISCELL
  mstr_symbols gnd *
  page236_i130
#ISCELL
  mstr_symbols gnd *
  page236_i133
#CELL
  mstr_discrete cap *
  page236_i134
#ISCELL
  mstr_symbols gnd *
  page236_i135
#CELL
  mstr_discrete cap *
  page236_i136
#ISCELL
  mstr_symbols gnd *
  page236_i139
#CELL
  mstr_discrete cap *
  page236_i149
#CELL
  mstr_discrete cap *
  page236_i150
#CELL
  mstr_discrete res *
  page236_i153
#CELL
  mstr_discrete res *
  page236_i154
#CELL
  w_hdl sc22u16v5mx-4-gp *
  page236_i159
#CELL
  mstr_discrete cap *
  page236_i16
#CELL
  w_hdl sc22u16v5mx-4-gp *
  page236_i160
#CELL
  w_hdl sc22u16v5mx-4-gp *
  page236_i161
#CELL
  w_hdl sc22u16v5mx-4-gp *
  page236_i162
#CELL
  w_hdl sc22u16v5mx-4-gp *
  page236_i163
#ISCELL
  mstr_symbols gnd *
  page236_i164
#CELL
  w_hdl sc22u16v5mx-4-gp *
  page236_i165
#ISCELL
  mstr_symbols gnd *
  page236_i166
#ISCELL
  mstr_symbols gnd *
  page236_i167
#ISCELL
  mstr_symbols gnd *
  page236_i168
#ISCELL
  mstr_symbols gnd *
  page236_i169
#ISCELL
  mstr_symbols gnd *
  page236_i170
#CELL
  w_hdl sc22u16v5mx-4-gp *
  page236_i171
#CELL
  w_hdl sc22u16v5mx-4-gp *
  page236_i172
#ISCELL
  mstr_symbols gnd *
  page236_i173
#ISCELL
  mstr_symbols gnd *
  page236_i174
#CELL
  mstr_discrete res *
  page236_i175
#CELL
  mstr_discrete res *
  page236_i177
#CELL
  w_hdl ind-300nh-20-gp *
  page236_i178
#CELL
  w_hdl ind-300nh-20-gp *
  page236_i179
#CELL
  w_hdl sc1u10v2kx-4-gp *
  page236_i180
#CELL
  w_hdl sc1u10v2kx-4-gp *
  page236_i181
#CELL
  w_hdl 1r3f-gp *
  page236_i182
#CELL
  w_hdl 1r3f-gp *
  page236_i183
#CELL
  mstr_discrete cap *
  page236_i19
#ISCELL
  mstr_standard offpage *
  page236_i2
#CELL
  dev_discrete cap_a *
  page236_i20
#CELL
  mstr_discrete cap *
  page236_i21
#CELL
  mstr_discrete cap *
  page236_i22
#CELL
  mstr_discrete cap *
  page236_i23
#CELL
  mstr_discrete cap *
  page236_i24
#ISCELL
  mstr_standard offpage *
  page236_i25
#CELL
  mstr_discrete cap *
  page236_i26
#ISCELL
  mstr_symbols gnd *
  page236_i27
#ISCELL
  mstr_symbols gnd *
  page236_i28
#CELL
  mstr_discrete cap *
  page236_i29
#ISCELL
  mstr_standard offpage *
  page236_i3
#ISCELL
  mstr_standard offpage *
  page236_i30
#CELL
  mstr_discrete cap *
  page236_i31
#CELL
  mstr_discrete cap *
  page236_i32
#CELL
  mstr_discrete cap *
  page236_i33
#CELL
  mstr_discrete cap *
  page236_i34
#CELL
  dev_discrete cap_a *
  page236_i35
#CELL
  mstr_discrete cap *
  page236_i36
#CELL
  mstr_discrete cap *
  page236_i39
#ISCELL
  mstr_symbols p5v_stby *
  page236_i42
#ISCELL
  mstr_symbols gnd *
  page236_i44
#CELL
  mstr_discrete cap *
  page236_i46
#ISCELL
  mstr_symbols gnd *
  page236_i47
#ISCELL
  mstr_symbols p1v05_pch_stby *
  page236_i48
#ISCELL
  mstr_standard offpage *
  page236_i52
#ISCELL
  mstr_standard offpage *
  page236_i53
#ISCELL
  mstr_standard offpage *
  page236_i54
#ISCELL
  mstr_symbols p1v05_pch_stby *
  page236_i55
#CELL
  mstr_discrete res *
  page236_i56
#CELL
  mstr_discrete res *
  page236_i57
#ISCELL
  mstr_symbols gnd *
  page236_i58
#CELL
  mstr_discrete res *
  page236_i59
#ISCELL
  mstr_standard offpage *
  page236_i60
#ISCELL
  mstr_standard offpage *
  page236_i61
#ISCELL
  mstr_symbols pvnn_pch_stby *
  page236_i7
#CELL
  mstr_discrete capp *
  page236_i71
#CELL
  mstr_discrete capp *
  page236_i73
#CELL
  mstr_discrete capp *
  page236_i74
#CELL
  mstr_discrete capp *
  page236_i75
#CELL
  mstr_discrete capp *
  page236_i76
#CELL
  mstr_discrete capp *
  page236_i77
#CELL
  mstr_discrete capp *
  page236_i78
#CELL
  mstr_discrete capp *
  page236_i79
#ISCELL
  mstr_symbols gnd *
  page236_i8
#ISCELL
  mstr_symbols gnd *
  page236_i82
#ISCELL
  mstr_standard offpage *
  page236_i85
#ISCELL
  mstr_standard offpage *
  page236_i86
#ISCELL
  mstr_symbols pvnn_pch_stby *
  page236_i87
#ISCELL
  mstr_standard offpage *
  page236_i88
#ISCELL
  mstr_standard offpage *
  page236_i89
#CELL
  mstr_discrete cap *
  page236_i9
#CELL
  mstr_discrete res *
  page236_i90
#CELL
  mstr_discrete res *
  page236_i92
#CELL
  mstr_discrete res *
  page236_i93
#CELL
  mstr_discrete res *
  page236_i94
#ISCELL
  mstr_symbols vcc_core *
  page236_i95
#ISCELL
  mstr_symbols vcc_core *
  page236_i96
#ISCELL
  mstr_symbols vcc_core *
  page236_i97
#ISCELL
  mstr_misc dns *
  *
#ISCELL
  mstr_symbols design_note *
  *
#ISCELL
  mstr_symbols intel_corp_bpage *
  *
#ISCELL
  mstr_standard offpage *
  page237_i1
#CELL
  mstr_discrete cap *
  page237_i12
#CELL
  mstr_discrete cap *
  page237_i13
#ISCELL
  mstr_symbols gnd *
  page237_i14
#CELL
  mstr_discrete res *
  page237_i15
#CELL
  mstr_discrete cap *
  page237_i29
#CELL
  mstr_discrete res *
  page237_i3
#ISCELL
  mstr_symbols gnd *
  page237_i30
#CELL
  mstr_discrete cap *
  page237_i31
#ISCELL
  mstr_symbols gnd *
  page237_i32
#ISCELL
  mstr_symbols p1v8_pch_stby *
  page237_i4
#CELL
  mstr_discrete cap *
  page237_i5
#CELL
  mstr_discrete cap *
  page237_i55
#ISCELL
  mstr_standard offpage *
  page237_i58
#ISCELL
  mstr_symbols gnd *
  page237_i6
#ISCELL
  mstr_symbols p3v3_stby *
  page237_i65
#ISCELL
  mstr_symbols gnd *
  page237_i71
#CELL
  mstr_discrete cap *
  page237_i77
#CELL
  mstr_discrete cap *
  page237_i79
#CELL
  mstr_discrete res *
  page237_i80
#CELL
  mstr_discrete res *
  page237_i81
#ISCELL
  mstr_symbols p3v3_stby *
  page237_i85
#CELL
  mstr_vreg rt9059 *
  page237_i86
#CELL
  mstr_discrete res *
  page237_i90
#ISCELL
  mstr_symbols gnd *
  page237_i91
#ISCELL
  mstr_symbols gnd *
  page237_i92
#ISCELL
  mstr_misc dns *
  *
#ISCELL
  mstr_symbols cad_note *
  *
#ISCELL
  mstr_symbols design_note *
  *
#ISCELL
  mstr_symbols intel_corp_bpage *
  *
#ISCELL
  mstr_standard offpage *
  page238_i1
#ISCELL
  mstr_symbols gnd *
  page238_i13
#CELL
  mstr_discrete res *
  page238_i14
#ISCELL
  mstr_symbols gnd *
  page238_i15
#CELL
  mstr_discrete cap *
  page238_i19
#ISCELL
  mstr_symbols gnd *
  page238_i20
#CELL
  mstr_discrete res *
  page238_i21
#ISCELL
  mstr_symbols p3v3_stby *
  page238_i22
#CELL
  mstr_discrete cap *
  page238_i23
#ISCELL
  mstr_standard offpage *
  page238_i25
#ISCELL
  mstr_symbols gnd *
  page238_i27
#ISCELL
  mstr_symbols gnd *
  page238_i3
#CELL
  mstr_discrete cap *
  page238_i30
#CELL
  mstr_discrete cap *
  page238_i39
#ISCELL
  mstr_symbols gnd *
  page238_i4
#CELL
  mstr_vreg rt9059 *
  page238_i40
#CELL
  mstr_discrete res *
  page238_i41
#ISCELL
  mstr_symbols p3v3_stby *
  page238_i42
#ISCELL
  w_power w_vcc_circle *
  page238_i43
#ISCELL
  mstr_symbols p3v3_stby *
  page238_i44
#CELL
  w_hdl 4k42r2f-gp *
  page238_i45
#CELL
  mstr_discrete cap *
  page238_i46
#ISCELL
  mstr_symbols gnd *
  page238_i47
#CELL
  mstr_discrete cap *
  page238_i5
#CELL
  dev_discrete cap_a *
  page238_i50
#ISCELL
  mstr_symbols gnd *
  page238_i6
#CELL
  mstr_discrete cap *
  page238_i7
#ISCELL
  mstr_misc dns *
  *
#ISCELL
  mstr_symbols cad_note *
  *
#ISCELL
  mstr_symbols design_note *
  *
#ISCELL
  mstr_symbols intel_corp_bpage *
  *
#CELL
  mstr_discrete res *
  page239_i100
#CELL
  mstr_discrete res *
  page239_i101
#CELL
  w_hdl 21k5r2f-gp *
  page239_i102
#CELL
  mstr_discrete cap *
  page239_i104
#ISCELL
  mstr_symbols gnd *
  page239_i105
#CELL
  dev_discrete cap_a *
  page239_i111
#CELL
  mstr_discrete cap *
  page239_i12
#ISCELL
  mstr_symbols gnd *
  page239_i16
#CELL
  mstr_discrete cap *
  page239_i22
#CELL
  mstr_discrete cap *
  page239_i30
#ISCELL
  mstr_standard offpage *
  page239_i33
#ISCELL
  mstr_symbols p3v3_stby *
  page239_i35
#ISCELL
  mstr_symbols gnd *
  page239_i38
#ISCELL
  mstr_symbols gnd *
  page239_i39
#CELL
  mstr_discrete cap *
  page239_i4
#ISCELL
  mstr_standard offpage *
  page239_i42
#ISCELL
  mstr_symbols gnd *
  page239_i5
#CELL
  mstr_discrete res *
  page239_i6
#ISCELL
  mstr_symbols gnd *
  page239_i62
#ISCELL
  mstr_symbols p3v3_stby *
  page239_i67
#ISCELL
  mstr_symbols gnd *
  page239_i69
#CELL
  mstr_discrete cap *
  page239_i7
#CELL
  mstr_vreg rt9059 *
  page239_i70
#CELL
  dev_discrete cap_a *
  page239_i71
#CELL
  mstr_discrete res *
  page239_i72
#CELL
  mstr_vreg rt9059 *
  page239_i73
#ISCELL
  mstr_symbols gnd *
  page239_i74
#ISCELL
  mstr_symbols p3v3_stby *
  page239_i75
#ISCELL
  mstr_standard offpage *
  page239_i76
#CELL
  mstr_discrete res *
  page239_i77
#ISCELL
  mstr_symbols p3v3_stby *
  page239_i78
#CELL
  mstr_discrete res *
  page239_i79
#CELL
  mstr_discrete cap *
  page239_i81
#ISCELL
  mstr_symbols gnd *
  page239_i82
#CELL
  mstr_discrete cap *
  page239_i83
#CELL
  mstr_discrete cap *
  page239_i84
#ISCELL
  mstr_symbols gnd *
  page239_i85
#ISCELL
  mstr_symbols gnd *
  page239_i88
#ISCELL
  mstr_symbols gnd *
  page239_i89
#ISCELL
  mstr_symbols gnd *
  page239_i9
#CELL
  dev_discrete cap_a *
  page239_i90
#CELL
  mstr_discrete cap *
  page239_i91
#CELL
  mstr_discrete cap *
  page239_i92
#ISCELL
  mstr_symbols gnd *
  page239_i93
#ISCELL
  mstr_standard offpage *
  page239_i94
#ISCELL
  mstr_symbols gnd *
  page239_i95
#ISCELL
  w_power w_vcc_circle *
  page239_i96
#ISCELL
  w_power w_vcc_circle *
  page239_i97
#CELL
  w_hdl 5k1r2f-2-gp *
  page239_i98
#ISCELL
  mstr_misc dns *
  *
#ISCELL
  mstr_symbols design_note *
  *
#ISCELL
  mstr_symbols intel_corp_bpage *
  *
#ISCELL
  mstr_standard offpage *
  page240_i107
#ISCELL
  mstr_symbols gnd *
  page240_i110
#CELL
  mstr_discrete res *
  page240_i111
#CELL
  mstr_discrete cap *
  page240_i113
#ISCELL
  mstr_symbols p5v_stby *
  page240_i114
#ISCELL
  mstr_symbols gnd *
  page240_i115
#CELL
  mstr_discrete cap *
  page240_i116
#CELL
  mstr_discrete res *
  page240_i117
#CELL
  mstr_vreg rt8240 *
  page240_i125
#ISCELL
  mstr_standard offpage *
  page240_i126
#CELL
  mstr_discrete res *
  page240_i127
#ISCELL
  mstr_symbols gnd *
  page240_i128
#CELL
  mstr_discrete cap *
  page240_i129
#ISCELL
  mstr_symbols p3v3_stby *
  page240_i130
#ISCELL
  mstr_symbols p12v_stby *
  page240_i131
#CELL
  mstr_discrete cap *
  page240_i137
#ISCELL
  mstr_symbols gnd *
  page240_i138
#CELL
  mstr_discrete cap *
  page240_i139
#CELL
  mstr_discrete res *
  page240_i140
#CELL
  mstr_discrete res *
  page240_i142
#CELL
  mstr_discrete res *
  page240_i143
#CELL
  mstr_discrete res *
  page240_i144
#ISCELL
  mstr_symbols gnd *
  page240_i145
#CELL
  mstr_discrete res *
  page240_i146
#ISCELL
  mstr_symbols gnd *
  page240_i147
#CELL
  mstr_discrete res *
  page240_i148
#ISCELL
  mstr_symbols gnd *
  page240_i149
#ISCELL
  mstr_symbols gnd *
  page240_i151
#CELL
  mstr_discrete res *
  page240_i152
#ISCELL
  mstr_symbols gnd *
  page240_i153
#ISCELL
  mstr_symbols gnd *
  page240_i156
#ISCELL
  mstr_symbols gnd *
  page240_i157
#CELL
  mstr_discrete cap *
  page240_i158
#ISCELL
  mstr_symbols gnd *
  page240_i159
#CELL
  mstr_discrete cap *
  page240_i160
#CELL
  mstr_discrete cap *
  page240_i163
#ISCELL
  mstr_symbols agnd_scsi *
  page240_i164
#ISCELL
  mstr_symbols agnd_scsi *
  page240_i165
#ISCELL
  mstr_symbols agnd_scsi *
  page240_i166
#ISCELL
  mstr_symbols agnd_scsi *
  page240_i167
#ISCELL
  mstr_symbols agnd_scsi *
  page240_i168
#ISCELL
  mstr_symbols agnd_scsi *
  page240_i169
#CELL
  mstr_discrete csd87384m *
  page240_i170
#CELL
  mstr_discrete res *
  page240_i171
#CELL
  mstr_discrete cap *
  page240_i174
#ISCELL
  mstr_symbols gnd *
  page240_i175
#CELL
  mstr_discrete res *
  page240_i176
#CELL
  mstr_discrete res *
  page240_i177
#ISCELL
  mstr_symbols p3v3_stby *
  page240_i178
#ISCELL
  mstr_symbols gnd *
  page240_i179
#ISCELL
  mstr_symbols gnd *
  page240_i180
#CELL
  w_hdl sc22u16v5mx-4-gp *
  page240_i181
#CELL
  w_hdl sc22u16v5mx-4-gp *
  page240_i182
#CELL
  w_hdl sc22u16v5mx-4-gp *
  page240_i183
#ISCELL
  mstr_symbols gnd *
  page240_i184
#ISCELL
  mstr_symbols gnd *
  page240_i185
#CELL
  w_hdl sc22u16v5mx-4-gp *
  page240_i186
#CELL
  w_hdl ind-1uh-361-gp *
  page240_i188
#CELL
  w_hdl st470u6d3vdm-7-gp *
  page240_i189
#CELL
  w_hdl st470u6d3vdm-7-gp *
  page240_i190
#CELL
  w_hdl sc4d7u16v3kx-gp *
  page240_i191
#CELL
  w_hdl blm31sn500sn1l-gp *
  page240_i193
#CELL
  mstr_discrete res *
  page240_i195
#ISCELL
  mstr_symbols p3v3_stby *
  page240_i85
#ISCELL
  mstr_misc dns *
  *
#ISCELL
  mstr_symbols cad_note *
  *
#ISCELL
  mstr_symbols design_note *
  *
#ISCELL
  mstr_symbols intel_corp_bpage *
  *
#ISCELL
  mstr_standard offpage *
  page241_i1
#CELL
  w_hdl st220u10vdm-lgp *
  page241_i100
#CELL
  w_hdl sc22u16v5mx-4-gp *
  page241_i103
#CELL
  w_hdl sc22u16v5mx-4-gp *
  page241_i104
#CELL
  mstr_discrete res *
  page241_i11
#CELL
  mstr_discrete cap *
  page241_i12
#CELL
  mstr_discrete cap *
  page241_i14
#ISCELL
  mstr_symbols gnd *
  page241_i16
#CELL
  mstr_discrete res *
  page241_i18
#ISCELL
  mstr_symbols gnd *
  page241_i19
#CELL
  mstr_discrete cap *
  page241_i30
#ISCELL
  mstr_symbols gnd *
  page241_i31
#ISCELL
  mstr_symbols gnd *
  page241_i32
#CELL
  mstr_discrete res *
  page241_i37
#CELL
  mstr_discrete cap *
  page241_i39
#ISCELL
  mstr_symbols gnd *
  page241_i4
#ISCELL
  mstr_symbols gnd *
  page241_i40
#CELL
  mstr_discrete cap *
  page241_i41
#ISCELL
  mstr_standard offpage *
  page241_i48
#CELL
  mstr_discrete res *
  page241_i50
#CELL
  mstr_discrete res *
  page241_i51
#ISCELL
  mstr_symbols gnd *
  page241_i52
#CELL
  mstr_discrete cap *
  page241_i53
#CELL
  mstr_discrete res *
  page241_i54
#ISCELL
  mstr_symbols gnd *
  page241_i55
#CELL
  mstr_discrete cap *
  page241_i57
#CELL
  mstr_discrete res *
  page241_i58
#ISCELL
  mstr_symbols gnd *
  page241_i59
#CELL
  mstr_discrete cap *
  page241_i63
#ISCELL
  mstr_symbols gnd *
  page241_i64
#ISCELL
  mstr_symbols p5v_stby *
  page241_i69
#ISCELL
  mstr_symbols p12v_stby *
  page241_i71
#CELL
  mstr_discrete res *
  page241_i78
#CELL
  mstr_discrete ferrite *
  page241_i82
#CELL
  mstr_vreg tps54821 *
  page241_i83
#ISCELL
  mstr_symbols p5v_stby *
  page241_i85
#ISCELL
  mstr_symbols gnd *
  page241_i86
#CELL
  mstr_discrete res *
  page241_i89
#CELL
  mstr_discrete res *
  page241_i9
#CELL
  mstr_discrete inductor *
  page241_i90
#CELL
  mstr_discrete res *
  page241_i91
#CELL
  w_hdl sc22u16v5mx-4-gp *
  page241_i92
#ISCELL
  mstr_symbols gnd *
  page241_i93
#ISCELL
  mstr_symbols gnd *
  page241_i94
#CELL
  w_hdl sc22u16v5mx-4-gp *
  page241_i95
#CELL
  w_hdl sc22u16v5mx-4-gp *
  page241_i96
#ISCELL
  mstr_symbols gnd *
  page241_i97
#CELL
  w_hdl sc22u16v5mx-4-gp *
  page241_i98
#ISCELL
  mstr_symbols gnd *
  page241_i99
#ISCELL
  mstr_symbols intel_corp_bpage *
  *
#ISCELL
  mstr_symbols gnd *
  page242_i1
#ISCELL
  mstr_symbols gnd *
  page242_i10
#ISCELL
  mstr_symbols pvddq_abc *
  page242_i26
#ISCELL
  mstr_symbols gnd *
  page242_i27
#ISCELL
  mstr_symbols pvddq_def *
  page242_i29
#ISCELL
  mstr_symbols pvddq_abc *
  page242_i3
#ISCELL
  mstr_symbols gnd *
  page242_i33
#ISCELL
  mstr_symbols pvddq_def *
  page242_i35
#ISCELL
  mstr_symbols gnd *
  page242_i36
#ISCELL
  mstr_symbols pvddq_def *
  page242_i50
#CELL
  dev_discrete cap_a *
  page242_i53
#CELL
  dev_discrete cap_a *
  page242_i54
#CELL
  dev_discrete cap_a *
  page242_i55
#CELL
  dev_discrete cap_a *
  page242_i56
#CELL
  dev_discrete cap_a *
  page242_i57
#CELL
  dev_discrete cap_a *
  page242_i58
#CELL
  dev_discrete cap_a *
  page242_i59
#CELL
  dev_discrete cap_a *
  page242_i60
#CELL
  dev_discrete cap_a *
  page242_i61
#CELL
  dev_discrete cap_a *
  page242_i62
#CELL
  dev_discrete cap_a *
  page242_i63
#CELL
  dev_discrete cap_a *
  page242_i64
#CELL
  dev_discrete cap_a *
  page242_i65
#CELL
  dev_discrete cap_a *
  page242_i66
#CELL
  dev_discrete cap_a *
  page242_i67
#CELL
  dev_discrete cap_a *
  page242_i68
#CELL
  dev_discrete cap_a *
  page242_i69
#ISCELL
  mstr_symbols gnd *
  page242_i7
#CELL
  dev_discrete cap_a *
  page242_i70
#CELL
  dev_discrete cap_a *
  page242_i71
#CELL
  dev_discrete cap_a *
  page242_i72
#CELL
  dev_discrete cap_a *
  page242_i73
#CELL
  dev_discrete cap_a *
  page242_i74
#CELL
  dev_discrete cap_a *
  page242_i75
#CELL
  dev_discrete cap_a *
  page242_i76
#CELL
  dev_discrete cap_a *
  page242_i77
#CELL
  dev_discrete cap_a *
  page242_i78
#CELL
  dev_discrete cap_a *
  page242_i79
#CELL
  dev_discrete cap_a *
  page242_i80
#CELL
  dev_discrete cap_a *
  page242_i81
#CELL
  dev_discrete cap_a *
  page242_i82
#CELL
  dev_discrete cap_a *
  page242_i83
#CELL
  dev_discrete cap_a *
  page242_i84
#CELL
  dev_discrete cap_a *
  page242_i85
#CELL
  dev_discrete cap_a *
  page242_i86
#CELL
  dev_discrete cap_a *
  page242_i87
#CELL
  dev_discrete cap_a *
  page242_i88
#CELL
  mstr_discrete cap *
  page242_i89
#ISCELL
  mstr_symbols pvddq_abc *
  page242_i9
#CELL
  mstr_discrete cap *
  page242_i90
#CELL
  mstr_discrete cap *
  page242_i91
#CELL
  mstr_discrete cap *
  page242_i92
#ISCELL
  mstr_symbols intel_corp_bpage *
  *
#ISCELL
  mstr_symbols gnd *
  page243_i1
#ISCELL
  mstr_symbols gnd *
  page243_i11
#ISCELL
  mstr_symbols pvddq_ghj *
  page243_i26
#ISCELL
  mstr_symbols gnd *
  page243_i27
#ISCELL
  mstr_symbols pvddq_klm *
  page243_i29
#ISCELL
  mstr_symbols pvddq_ghj *
  page243_i3
#ISCELL
  mstr_symbols gnd *
  page243_i34
#ISCELL
  mstr_symbols pvddq_klm *
  page243_i36
#ISCELL
  mstr_symbols gnd *
  page243_i38
#ISCELL
  mstr_symbols pvddq_klm *
  page243_i51
#CELL
  dev_discrete cap_a *
  page243_i53
#CELL
  dev_discrete cap_a *
  page243_i54
#CELL
  dev_discrete cap_a *
  page243_i55
#CELL
  dev_discrete cap_a *
  page243_i56
#CELL
  dev_discrete cap_a *
  page243_i57
#CELL
  dev_discrete cap_a *
  page243_i58
#CELL
  dev_discrete cap_a *
  page243_i59
#ISCELL
  mstr_symbols gnd *
  page243_i6
#CELL
  dev_discrete cap_a *
  page243_i60
#CELL
  dev_discrete cap_a *
  page243_i61
#CELL
  dev_discrete cap_a *
  page243_i62
#CELL
  dev_discrete cap_a *
  page243_i63
#CELL
  dev_discrete cap_a *
  page243_i64
#CELL
  dev_discrete cap_a *
  page243_i65
#CELL
  dev_discrete cap_a *
  page243_i66
#CELL
  dev_discrete cap_a *
  page243_i67
#CELL
  dev_discrete cap_a *
  page243_i68
#CELL
  dev_discrete cap_a *
  page243_i69
#CELL
  dev_discrete cap_a *
  page243_i70
#CELL
  dev_discrete cap_a *
  page243_i71
#CELL
  dev_discrete cap_a *
  page243_i72
#CELL
  dev_discrete cap_a *
  page243_i73
#CELL
  dev_discrete cap_a *
  page243_i74
#CELL
  dev_discrete cap_a *
  page243_i75
#CELL
  dev_discrete cap_a *
  page243_i76
#CELL
  dev_discrete cap_a *
  page243_i77
#CELL
  dev_discrete cap_a *
  page243_i78
#CELL
  dev_discrete cap_a *
  page243_i79
#ISCELL
  mstr_symbols pvddq_ghj *
  page243_i8
#CELL
  dev_discrete cap_a *
  page243_i80
#CELL
  dev_discrete cap_a *
  page243_i81
#CELL
  dev_discrete cap_a *
  page243_i82
#CELL
  dev_discrete cap_a *
  page243_i83
#CELL
  dev_discrete cap_a *
  page243_i84
#CELL
  dev_discrete cap_a *
  page243_i85
#CELL
  dev_discrete cap_a *
  page243_i86
#CELL
  dev_discrete cap_a *
  page243_i87
#CELL
  dev_discrete cap_a *
  page243_i88
#CELL
  mstr_discrete cap *
  page243_i89
#CELL
  mstr_discrete cap *
  page243_i90
#CELL
  mstr_discrete cap *
  page243_i91
#CELL
  mstr_discrete cap *
  page243_i92
#ISCELL
  mstr_symbols intel_corp_bpage *
  *
#ISCELL
  mstr_standard tap *
  page244_i1
#ISCELL
  mstr_standard offpage *
  page244_i10
#ISCELL
  mstr_standard tap *
  page244_i100
#ISCELL
  mstr_standard tap *
  page244_i101
#ISCELL
  mstr_standard tap *
  page244_i102
#CELL
  mstr_discrete res *
  page244_i103
#ISCELL
  mstr_standard offpage *
  page244_i104
#ISCELL
  mstr_standard tap *
  page244_i11
#CELL
  mstr_discrete cap *
  page244_i12
#ISCELL
  mstr_standard tap *
  page244_i13
#ISCELL
  mstr_standard tap *
  page244_i14
#ISCELL
  mstr_standard tap *
  page244_i15
#ISCELL
  mstr_standard tap *
  page244_i16
#CELL
  mstr_discrete cap *
  page244_i17
#ISCELL
  mstr_standard tap *
  page244_i18
#ISCELL
  mstr_standard tap *
  page244_i19
#CELL
  mstr_discrete cap *
  page244_i2
#ISCELL
  mstr_standard tap *
  page244_i20
#ISCELL
  mstr_standard tap *
  page244_i21
#ISCELL
  mstr_standard tap *
  page244_i22
#CELL
  mstr_discrete cap *
  page244_i23
#CELL
  mstr_discrete cap *
  page244_i24
#ISCELL
  mstr_standard tap *
  page244_i25
#ISCELL
  mstr_standard tap *
  page244_i26
#ISCELL
  mstr_standard tap *
  page244_i27
#CELL
  mstr_discrete cap *
  page244_i28
#CELL
  mstr_discrete cap *
  page244_i29
#ISCELL
  mstr_standard tap *
  page244_i3
#CELL
  mstr_discrete cap *
  page244_i30
#ISCELL
  mstr_standard tap *
  page244_i31
#ISCELL
  mstr_standard tap *
  page244_i32
#ISCELL
  mstr_standard tap *
  page244_i33
#ISCELL
  mstr_standard tap *
  page244_i34
#CELL
  mstr_discrete cap *
  page244_i35
#ISCELL
  mstr_standard tap *
  page244_i36
#ISCELL
  mstr_standard offpage *
  page244_i37
#ISCELL
  mstr_standard tap *
  page244_i38
#CELL
  mstr_discrete res *
  page244_i39
#ISCELL
  mstr_standard tap *
  page244_i4
#ISCELL
  mstr_standard tap *
  page244_i40
#CELL
  mstr_discrete cap *
  page244_i41
#ISCELL
  mstr_standard tap *
  page244_i42
#ISCELL
  mstr_standard tap *
  page244_i43
#ISCELL
  mstr_standard tap *
  page244_i44
#ISCELL
  mstr_standard tap *
  page244_i45
#ISCELL
  mstr_standard tap *
  page244_i46
#CELL
  mstr_discrete cap *
  page244_i47
#ISCELL
  mstr_standard tap *
  page244_i48
#ISCELL
  mstr_standard offpage *
  page244_i49
#CELL
  mstr_discrete cap *
  page244_i5
#CELL
  mstr_discrete cap *
  page244_i50
#CELL
  mstr_discrete cap *
  page244_i51
#CELL
  mstr_discrete cap *
  page244_i52
#ISCELL
  mstr_standard tap *
  page244_i53
#ISCELL
  mstr_standard tap *
  page244_i54
#ISCELL
  mstr_standard tap *
  page244_i55
#ISCELL
  mstr_standard offpage *
  page244_i56
#ISCELL
  mstr_standard tap *
  page244_i57
#CELL
  mstr_discrete res *
  page244_i58
#ISCELL
  mstr_standard tap *
  page244_i59
#ISCELL
  mstr_standard tap *
  page244_i6
#ISCELL
  mstr_standard tap *
  page244_i60
#ISCELL
  mstr_standard tap *
  page244_i61
#ISCELL
  mstr_standard tap *
  page244_i62
#ISCELL
  mstr_standard offpage *
  page244_i63
#CELL
  mstr_discrete res *
  page244_i64
#CELL
  mstr_discrete res *
  page244_i65
#CELL
  mstr_discrete res *
  page244_i66
#ISCELL
  mstr_standard tap *
  page244_i67
#ISCELL
  mstr_standard tap *
  page244_i68
#ISCELL
  mstr_standard tap *
  page244_i69
#ISCELL
  mstr_standard tap *
  page244_i7
#ISCELL
  mstr_standard tap *
  page244_i70
#ISCELL
  mstr_standard tap *
  page244_i71
#CELL
  mstr_discrete res *
  page244_i72
#ISCELL
  mstr_standard tap *
  page244_i73
#CELL
  mstr_discrete res *
  page244_i74
#ISCELL
  mstr_standard tap *
  page244_i75
#ISCELL
  mstr_standard tap *
  page244_i76
#CELL
  mstr_discrete res *
  page244_i77
#ISCELL
  mstr_standard tap *
  page244_i78
#ISCELL
  mstr_standard offpage *
  page244_i79
#CELL
  mstr_discrete cap *
  page244_i8
#CELL
  mstr_discrete res *
  page244_i80
#ISCELL
  mstr_standard tap *
  page244_i81
#ISCELL
  mstr_standard tap *
  page244_i82
#ISCELL
  mstr_standard tap *
  page244_i83
#ISCELL
  mstr_standard tap *
  page244_i84
#ISCELL
  mstr_standard tap *
  page244_i85
#CELL
  mstr_discrete res *
  page244_i86
#ISCELL
  mstr_standard tap *
  page244_i87
#ISCELL
  mstr_standard tap *
  page244_i88
#ISCELL
  mstr_standard tap *
  page244_i89
#ISCELL
  mstr_standard offpage *
  page244_i9
#ISCELL
  mstr_standard tap *
  page244_i90
#ISCELL
  mstr_standard tap *
  page244_i91
#ISCELL
  mstr_standard tap *
  page244_i92
#CELL
  mstr_discrete res *
  page244_i93
#CELL
  mstr_discrete res *
  page244_i94
#ISCELL
  mstr_standard tap *
  page244_i95
#ISCELL
  mstr_standard tap *
  page244_i96
#CELL
  mstr_discrete res *
  page244_i97
#CELL
  mstr_discrete res *
  page244_i98
#CELL
  mstr_discrete res *
  page244_i99
#ISCELL
  mstr_symbols intel_corp_bpage *
  *
#ISCELL
  mstr_standard tap *
  page245_i10
#ISCELL
  mstr_standard tap *
  page245_i11
#ISCELL
  mstr_standard tap *
  page245_i12
#ISCELL
  mstr_standard tap *
  page245_i13
#ISCELL
  mstr_standard tap *
  page245_i14
#ISCELL
  mstr_standard tap *
  page245_i15
#ISCELL
  mstr_standard tap *
  page245_i16
#ISCELL
  mstr_standard tap *
  page245_i17
#ISCELL
  mstr_standard tap *
  page245_i18
#ISCELL
  mstr_symbols gnd *
  page245_i19
#ISCELL
  mstr_symbols gnd *
  page245_i20
#ISCELL
  mstr_standard offpage *
  page245_i21
#ISCELL
  mstr_standard offpage *
  page245_i22
#ISCELL
  mstr_symbols gnd *
  page245_i25
#ISCELL
  mstr_symbols gnd *
  page245_i27
#ISCELL
  mstr_standard tap *
  page245_i29
#ISCELL
  mstr_standard tap *
  page245_i30
#ISCELL
  mstr_standard tap *
  page245_i31
#ISCELL
  mstr_standard tap *
  page245_i32
#ISCELL
  mstr_standard tap *
  page245_i33
#ISCELL
  mstr_standard tap *
  page245_i34
#ISCELL
  mstr_standard tap *
  page245_i35
#ISCELL
  mstr_standard tap *
  page245_i36
#ISCELL
  mstr_standard tap *
  page245_i37
#ISCELL
  mstr_standard tap *
  page245_i38
#ISCELL
  mstr_standard tap *
  page245_i39
#ISCELL
  mstr_standard tap *
  page245_i40
#ISCELL
  mstr_standard tap *
  page245_i41
#ISCELL
  mstr_standard tap *
  page245_i42
#ISCELL
  mstr_standard tap *
  page245_i43
#ISCELL
  mstr_standard tap *
  page245_i44
#ISCELL
  mstr_standard offpage *
  page245_i45
#ISCELL
  mstr_standard offpage *
  page245_i46
#CELL
  w_hdl smc-conn60a-22-gp *
  page245_i48
#ISCELL
  mstr_standard tap *
  page245_i5
#ISCELL
  mstr_standard tap *
  page245_i52
#ISCELL
  mstr_standard tap *
  page245_i53
#ISCELL
  mstr_standard offpage *
  page245_i54
#ISCELL
  mstr_standard offpage *
  page245_i55
#CELL
  mstr_discrete res *
  page245_i56
#CELL
  mstr_discrete res *
  page245_i57
#CELL
  mstr_discrete res *
  page245_i58
#CELL
  mstr_discrete res *
  page245_i59
#ISCELL
  mstr_standard tap *
  page245_i6
#CELL
  mstr_discrete res *
  page245_i60
#ISCELL
  mstr_standard offpage *
  page245_i61
#CELL
  mstr_ttl 74cbtlv1g125 *
  page245_i64
#CELL
  mstr_analog nc7sb3157 *
  page245_i66
#ISCELL
  mstr_symbols p3v3_stby *
  page245_i67
#ISCELL
  mstr_standard tap *
  page245_i7
#CELL
  dev_discrete cap_a *
  page245_i71
#ISCELL
  mstr_symbols gnd *
  page245_i72
#CELL
  dev_discrete cap_a *
  page245_i74
#ISCELL
  mstr_symbols gnd *
  page245_i75
#ISCELL
  mstr_standard offpage *
  page245_i77
#CELL
  mstr_discrete res *
  page245_i78
#ISCELL
  mstr_symbols p3v3_stby *
  page245_i79
#ISCELL
  mstr_standard tap *
  page245_i8
#ISCELL
  mstr_standard offpage *
  page245_i80
#ISCELL
  mstr_standard offpage *
  page245_i81
#ISCELL
  mstr_standard offpage *
  page245_i82
#ISCELL
  mstr_standard offpage *
  page245_i83
#ISCELL
  mstr_standard tap *
  page245_i9
#ISCELL
  mstr_misc dns *
  *
#ISCELL
  mstr_symbols bom_note *
  *
#ISCELL
  mstr_symbols cad_note *
  *
#ISCELL
  mstr_symbols intel_corp_bpage *
  *
#ISCELL
  mstr_standard offpage *
  page246_i1
#CELL
  mstr_discrete res *
  page246_i11
#CELL
  mstr_discrete res *
  page246_i12
#ISCELL
  mstr_symbols gnd *
  page246_i13
#ISCELL
  mstr_symbols gnd *
  page246_i14
#CELL
  mstr_memory w25q256 *
  page246_i17
#ISCELL
  mstr_standard offpage *
  page246_i18
#CELL
  w_hdl 82kr2f-1-gp *
  page246_i19
#ISCELL
  mstr_standard offpage *
  page246_i2
#CELL
  mstr_discrete res *
  page246_i20
#CELL
  dev_discrete cap_a *
  page246_i21
#CELL
  dev_discrete cap_a *
  page246_i22
#ISCELL
  mstr_standard offpage *
  page246_i3
#ISCELL
  mstr_standard offpage *
  page246_i4
#ISCELL
  mstr_symbols p3v3_stby *
  page246_i6
#ISCELL
  mstr_symbols gnd *
  page246_i7
#CELL
  mstr_discrete res *
  page246_i9
#ISCELL
  mstr_misc dns *
  *
#ISCELL
  mstr_symbols cad_note *
  *
#ISCELL
  mstr_symbols design_note *
  *
#ISCELL
  mstr_symbols intel_corp_bpage *
  *
#CELL
  mstr_discrete res *
  page247_i1
#CELL
  mstr_discrete res *
  page247_i100
#CELL
  mstr_discrete res *
  page247_i101
#ISCELL
  mstr_symbols p3v3_stby *
  page247_i102
#ISCELL
  mstr_symbols gnd *
  page247_i104
#CELL
  dev_discrete cap_a *
  page247_i105
#CELL
  dev_discrete cap_a *
  page247_i107
#ISCELL
  mstr_symbols gnd *
  page247_i108
#ISCELL
  mstr_symbols p3v3_stby *
  page247_i109
#ISCELL
  mstr_symbols p3v3_stby *
  page247_i111
#CELL
  mstr_discrete res *
  page247_i112
#CELL
  w_hdl tca9517dgkr-gp *
  page247_i118
#ISCELL
  mstr_symbols gnd *
  page247_i119
#ISCELL
  mstr_symbols p3v3_stby *
  page247_i12
#CELL
  w_hdl tca9555pwr-gp *
  page247_i120
#ISCELL
  mstr_symbols gnd *
  page247_i121
#ISCELL
  mstr_standard offpage *
  page247_i122
#ISCELL
  mstr_standard offpage *
  page247_i123
#ISCELL
  mstr_standard offpage *
  page247_i124
#ISCELL
  mstr_standard offpage *
  page247_i125
#ISCELL
  mstr_standard offpage *
  page247_i126
#ISCELL
  mstr_standard offpage *
  page247_i128
#ISCELL
  mstr_symbols gnd *
  page247_i13
#ISCELL
  mstr_standard offpage *
  page247_i138
#ISCELL
  mstr_standard offpage *
  page247_i139
#ISCELL
  mstr_standard offpage *
  page247_i140
#ISCELL
  mstr_standard offpage *
  page247_i141
#ISCELL
  mstr_standard offpage *
  page247_i142
#ISCELL
  mstr_standard offpage *
  page247_i143
#ISCELL
  mstr_standard offpage *
  page247_i144
#ISCELL
  mstr_standard offpage *
  page247_i145
#ISCELL
  mstr_standard offpage *
  page247_i146
#ISCELL
  mstr_standard offpage *
  page247_i147
#ISCELL
  mstr_symbols p3v3_stby *
  page247_i148
#ISCELL
  mstr_symbols gnd *
  page247_i150
#CELL
  dev_discrete cap_a *
  page247_i151
#ISCELL
  mstr_standard offpage *
  page247_i152
#ISCELL
  mstr_standard offpage *
  page247_i153
#ISCELL
  mstr_standard offpage *
  page247_i154
#ISCELL
  mstr_symbols p3v3_stby *
  page247_i156
#CELL
  mstr_discrete diode *
  page247_i157
#CELL
  mstr_discrete diode *
  page247_i158
#CELL
  mstr_discrete res *
  page247_i159
#CELL
  mstr_discrete res *
  page247_i160
#CELL
  mstr_discrete res *
  page247_i161
#CELL
  mstr_discrete res *
  page247_i162
#CELL
  mstr_discrete res *
  page247_i163
#CELL
  mstr_discrete res *
  page247_i164
#CELL
  mstr_discrete res *
  page247_i165
#ISCELL
  mstr_symbols gnd *
  page247_i4
#ISCELL
  mstr_symbols p3v3_stby *
  page247_i6
#ISCELL
  mstr_symbols gnd *
  page247_i7
#ISCELL
  mstr_standard offpage *
  page247_i74
#ISCELL
  mstr_standard offpage *
  page247_i75
#ISCELL
  mstr_standard offpage *
  page247_i79
#ISCELL
  mstr_standard offpage *
  page247_i80
#ISCELL
  mstr_symbols p3v3_stby *
  page247_i83
#ISCELL
  mstr_standard offpage *
  page247_i84
#CELL
  dev_discrete cap_a *
  page247_i85
#ISCELL
  mstr_symbols gnd *
  page247_i86
#CELL
  mstr_discrete res *
  page247_i87
#ISCELL
  mstr_symbols p3v3_stby *
  page247_i88
#CELL
  mstr_memory at24c64 *
  page247_i89
#CELL
  mstr_discrete res *
  page247_i90
#ISCELL
  mstr_symbols gnd *
  page247_i91
#CELL
  mstr_discrete res *
  page247_i92
#ISCELL
  mstr_symbols gnd *
  page247_i93
#CELL
  mstr_discrete res *
  page247_i94
#ISCELL
  mstr_standard offpage *
  page247_i95
#ISCELL
  mstr_standard offpage *
  page247_i96
#CELL
  mstr_discrete res *
  page247_i98
#CELL
  mstr_discrete res *
  page247_i99
#ISCELL
  mstr_symbols cad_note *
  *
#ISCELL
  mstr_symbols design_note *
  *
#ISCELL
  mstr_symbols intel_corp_bpage *
  *
#ISCELL
  mstr_standard offpage *
  page248_i10
#CELL
  mstr_ttl ttl1g08 *
  page248_i11
#ISCELL
  mstr_standard offpage *
  page248_i12
#CELL
  dev_discrete cap_a *
  page248_i13
#ISCELL
  mstr_symbols gnd *
  page248_i15
#ISCELL
  mstr_symbols p3v3 *
  page248_i16
#CELL
  dev_discrete cap_a *
  page248_i17
#ISCELL
  mstr_symbols gnd *
  page248_i18
#CELL
  mstr_ttl ttl1g08 *
  page248_i19
#ISCELL
  mstr_standard offpage *
  page248_i20
#ISCELL
  mstr_standard offpage *
  page248_i21
#ISCELL
  mstr_standard offpage *
  page248_i22
#ISCELL
  mstr_standard offpage *
  page248_i23
#CELL
  mstr_discrete res *
  page248_i24
#CELL
  mstr_discrete res *
  page248_i25
#CELL
  mstr_discrete res *
  page248_i26
#CELL
  mstr_discrete res *
  page248_i27
#ISCELL
  mstr_symbols gnd *
  page248_i29
#CELL
  dev_discrete cap_a *
  page248_i30
#ISCELL
  mstr_symbols gnd *
  page248_i31
#CELL
  dev_discrete cap_a *
  page248_i32
#CELL
  mstr_discrete res *
  page248_i34
#CELL
  mstr_discrete res *
  page248_i35
#ISCELL
  mstr_symbols p3v3_stby *
  page248_i36
#CELL
  mstr_discrete res *
  page248_i37
#CELL
  mstr_discrete res *
  page248_i38
#ISCELL
  mstr_symbols p3v3_stby *
  page248_i40
#ISCELL
  mstr_standard offpage *
  page248_i44
#ISCELL
  mstr_standard offpage *
  page248_i45
#ISCELL
  mstr_symbols pvccio_cpu0 *
  page248_i47
#ISCELL
  mstr_symbols pvccio_cpu0 *
  page248_i48
#CELL
  w_hdl tca9517dgkr-gp *
  page248_i49
#ISCELL
  mstr_symbols gnd *
  page248_i50
#ISCELL
  mstr_standard offpage *
  page248_i51
#ISCELL
  mstr_standard offpage *
  page248_i52
#ISCELL
  mstr_symbols p3v3 *
  page248_i9
#ISCELL
  mstr_misc dns *
  *
#ISCELL
  mstr_symbols intel_corp_bpage *
  *
#ISCELL
  mstr_standard offpage *
  page249_i1
#ISCELL
  mstr_symbols gnd *
  page249_i10
#ISCELL
  mstr_symbols gnd *
  page249_i11
#ISCELL
  mstr_symbols gnd *
  page249_i14
#CELL
  w_hdl lmv331idckrg4-gp *
  page249_i15
#ISCELL
  mstr_symbols p3v3_stby *
  page249_i16
#CELL
  mstr_discrete res *
  page249_i2
#ISCELL
  mstr_symbols gnd *
  page249_i20
#ISCELL
  mstr_standard offpage *
  page249_i22
#ISCELL
  mstr_symbols p3v3_stby *
  page249_i24
#CELL
  mstr_discrete npn *
  page249_i29
#ISCELL
  mstr_symbols gnd *
  page249_i3
#CELL
  mstr_discrete fet_n *
  page249_i30
#CELL
  w_hdl 47kr2f-gp *
  page249_i31
#CELL
  mstr_discrete res *
  page249_i34
#ISCELL
  mstr_symbols p5v_stby *
  page249_i35
#CELL
  mstr_discrete res *
  page249_i36
#CELL
  dev_discrete cap_a *
  page249_i37
#CELL
  mstr_discrete res *
  page249_i48
#CELL
  mstr_discrete npn *
  page249_i49
#ISCELL
  mstr_standard offpage *
  page249_i5
#ISCELL
  mstr_symbols gnd *
  page249_i50
#ISCELL
  mstr_standard offpage *
  page249_i51
#CELL
  w_hdl sc1u16v3kx-2gp *
  page249_i52
#CELL
  mstr_discrete diode *
  page249_i55
#CELL
  mstr_discrete res *
  page249_i56
#CELL
  dev_discrete cap_a *
  page249_i57
#CELL
  mstr_discrete res *
  page249_i58
#ISCELL
  mstr_symbols gnd *
  page249_i6
#CELL
  mstr_discrete res *
  page249_i7
#CELL
  mstr_discrete res *
  page249_i8
#ISCELL
  mstr_symbols p3v3_stby *
  page249_i9
#ISCELL
  mstr_symbols intel_corp_bpage *
  *
#ISCELL
  mstr_standard offpage *
  page250_i1
#ISCELL
  mstr_standard offpage *
  page250_i10
#ISCELL
  mstr_standard offpage *
  page250_i11
#CELL
  mstr_discrete fet_n_dual *
  page250_i12
#ISCELL
  mstr_standard offpage *
  page250_i13
#ISCELL
  mstr_standard offpage *
  page250_i14
#ISCELL
  mstr_standard offpage *
  page250_i15
#ISCELL
  mstr_symbols gnd *
  page250_i16
#ISCELL
  mstr_symbols p3v3_stby *
  page250_i17
#CELL
  w_hdl 1mr2f-l-gp *
  page250_i18
#ISCELL
  mstr_symbols gnd *
  page250_i19
#CELL
  w_hdl 1mr2f-l-gp *
  page250_i2
#ISCELL
  mstr_symbols p3v3_stby *
  page250_i21
#CELL
  mstr_discrete res *
  page250_i22
#ISCELL
  mstr_symbols gnd *
  page250_i23
#CELL
  mstr_discrete fet_n_dual *
  page250_i24
#ISCELL
  mstr_standard offpage *
  page250_i25
#ISCELL
  mstr_symbols p3v3_stby *
  page250_i26
#CELL
  w_hdl 1mr2f-l-gp *
  page250_i27
#ISCELL
  mstr_standard offpage *
  page250_i28
#CELL
  mstr_discrete fet_n *
  page250_i29
#CELL
  mstr_discrete fet_n_dual *
  page250_i3
#ISCELL
  mstr_symbols gnd *
  page250_i4
#ISCELL
  mstr_symbols p3v3_stby *
  page250_i5
#CELL
  mstr_discrete res *
  page250_i6
#ISCELL
  mstr_symbols p3v3_stby *
  page250_i7
#CELL
  mstr_discrete fet_n_dual *
  page250_i8
#ISCELL
  mstr_symbols gnd *
  page250_i9
#ISCELL
  mstr_misc dns *
  *
#ISCELL
  mstr_symbols cad_note *
  *
#ISCELL
  mstr_symbols intel_corp_bpage *
  *
#CELL
  dev_discrete cap_a *
  page251_i1
#CELL
  mstr_discrete diode *
  page251_i10
#CELL
  mstr_discrete res *
  page251_i11
#CELL
  mstr_discrete diode *
  page251_i12
#CELL
  mstr_discrete res *
  page251_i13
#CELL
  mstr_discrete res *
  page251_i14
#CELL
  mstr_discrete res *
  page251_i15
#CELL
  dev_discrete cap_a *
  page251_i16
#ISCELL
  mstr_symbols gnd *
  page251_i17
#ISCELL
  mstr_standard offpage *
  page251_i18
#CELL
  mstr_ttl ttl1g07_a *
  page251_i19
#ISCELL
  mstr_symbols p3v3_stby *
  page251_i20
#CELL
  dev_discrete cap_a *
  page251_i21
#ISCELL
  mstr_symbols gnd *
  page251_i22
#ISCELL
  mstr_standard offpage *
  page251_i23
#CELL
  mstr_conn conn6_c74770005 *
  page251_i25
#CELL
  mstr_discrete diode *
  page251_i26
#CELL
  mstr_discrete res *
  page251_i27
#ISCELL
  mstr_standard offpage *
  page251_i28
#CELL
  dev_discrete cap_a *
  page251_i29
#CELL
  mstr_discrete cap *
  page251_i3
#ISCELL
  mstr_symbols gnd *
  page251_i30
#CELL
  mstr_discrete res *
  page251_i31
#ISCELL
  mstr_symbols p3v3_stby *
  page251_i32
#ISCELL
  mstr_symbols gnd *
  page251_i4
#CELL
  mstr_discrete res *
  page251_i5
#ISCELL
  mstr_symbols p12v_fan *
  page251_i6
#ISCELL
  mstr_symbols p3v3_stby *
  page251_i7
#ISCELL
  mstr_symbols gnd *
  page251_i8
#ISCELL
  mstr_symbols p5v_stby *
  page251_i9
#ISCELL
  mstr_symbols intel_corp_bpage *
  *
#ISCELL
  mstr_symbols gnd *
  page255_i10
#CELL
  mstr_discrete cap *
  page255_i11
#CELL
  w_hdl u74ahct1g125g-al5-r-gp-u *
  page255_i111
#CELL
  w_hdl u74ahct1g125g-al5-r-gp-u *
  page255_i112
#ISCELL
  mstr_symbols gnd *
  page255_i113
#ISCELL
  mstr_symbols gnd *
  page255_i114
#ISCELL
  mstr_symbols gnd *
  page255_i115
#ISCELL
  mstr_symbols gnd *
  page255_i116
#ISCELL
  w_power w_vcc_circle *
  page255_i117
#CELL
  dev_discrete cap_a *
  page255_i118
#ISCELL
  mstr_symbols gnd *
  page255_i119
#CELL
  mstr_discrete cap *
  page255_i12
#CELL
  w_hdl rb551v30-gp *
  page255_i128
#CELL
  mstr_discrete diodeac_dual_array *
  page255_i129
#ISCELL
  mstr_standard offpage *
  page255_i13
#ISCELL
  mstr_symbols gnd *
  page255_i130
#CELL
  mstr_discrete diodeac_dual_array *
  page255_i131
#ISCELL
  mstr_symbols gnd *
  page255_i132
#ISCELL
  mstr_symbols gnd *
  page255_i133
#CELL
  dev_discrete cap_a *
  page255_i134
#ISCELL
  w_power w_vcc_circle *
  page255_i135
#CELL
  w_hdl smc-con13-gp *
  page255_i136
#ISCELL
  mstr_symbols gnd *
  page255_i137
#ISCELL
  mstr_symbols gnd *
  page255_i138
#ISCELL
  mstr_symbols gnd *
  page255_i139
#ISCELL
  mstr_standard offpage *
  page255_i14
#ISCELL
  mstr_symbols gnd *
  page255_i140
#ISCELL
  mstr_symbols gnd *
  page255_i141
#ISCELL
  mstr_symbols gnd *
  page255_i142
#ISCELL
  mstr_symbols gnd *
  page255_i144
#ISCELL
  mstr_symbols p5v *
  page255_i145
#ISCELL
  mstr_standard offpage *
  page255_i15
#CELL
  mstr_discrete cap *
  page255_i16
#ISCELL
  mstr_symbols gnd *
  page255_i17
#CELL
  mstr_discrete cap *
  page255_i18
#ISCELL
  mstr_symbols gnd *
  page255_i19
#ISCELL
  mstr_symbols gnd *
  page255_i20
#CELL
  mstr_discrete cap *
  page255_i21
#CELL
  mstr_discrete res *
  page255_i22
#ISCELL
  mstr_symbols gnd *
  page255_i23
#CELL
  mstr_discrete res *
  page255_i24
#ISCELL
  mstr_symbols gnd *
  page255_i25
#CELL
  mstr_discrete res *
  page255_i26
#ISCELL
  mstr_symbols gnd *
  page255_i27
#ISCELL
  mstr_symbols p3v3 *
  page255_i29
#CELL
  mstr_discrete res *
  page255_i30
#CELL
  mstr_discrete res *
  page255_i31
#ISCELL
  w_power w_vcc_circle *
  page255_i32
#ISCELL
  mstr_standard offpage *
  page255_i33
#CELL
  mstr_discrete res *
  page255_i34
#CELL
  mstr_discrete cap *
  page255_i35
#ISCELL
  mstr_symbols gnd *
  page255_i36
#CELL
  mstr_discrete res *
  page255_i38
#CELL
  mstr_discrete cap *
  page255_i39
#ISCELL
  mstr_symbols gnd *
  page255_i40
#ISCELL
  w_power w_vcc_circle *
  page255_i41
#ISCELL
  mstr_symbols p3v3 *
  page255_i42
#CELL
  mstr_discrete res *
  page255_i43
#CELL
  mstr_discrete res *
  page255_i44
#ISCELL
  mstr_standard offpage *
  page255_i46
#CELL
  mstr_discrete res *
  page255_i49
#ISCELL
  mstr_standard offpage *
  page255_i54
#ISCELL
  mstr_standard offpage *
  page255_i55
#CELL
  mstr_discrete res *
  page255_i59
#CELL
  mstr_discrete cap *
  page255_i60
#ISCELL
  mstr_symbols gnd *
  page255_i61
#CELL
  mstr_discrete cap *
  page255_i62
#ISCELL
  mstr_symbols gnd *
  page255_i63
#CELL
  mstr_discrete cap *
  page255_i7
#ISCELL
  w_power w_vcc_circle *
  page255_i72
#CELL
  dev_discrete cap_a *
  page255_i74
#ISCELL
  mstr_symbols gnd *
  page255_i75
#CELL
  w_hdl ind-68nh-15-gp *
  page255_i76
#CELL
  w_hdl ind-68nh-15-gp *
  page255_i77
#CELL
  w_hdl ind-68nh-15-gp *
  page255_i78
#ISCELL
  mstr_symbols gnd *
  page255_i8
#CELL
  w_hdl polysw-d5a6v-2-gp-u *
  page255_i89
#ISCELL
  mstr_symbols gnd *
  page255_i9
#ISCELL
  w_power w_vcc_circle *
  page255_i91
#CELL
  mstr_discrete fet_n_dual *
  page255_i95
#CELL
  mstr_discrete fet_n_dual *
  page255_i96
#ISCELL
  mstr_misc dns *
  *
#ISCELL
  mstr_symbols cad_note *
  *
#ISCELL
  mstr_symbols intel_corp_bpage *
  *
#CELL
  mstr_discrete choke_4pin *
  page253_i11
#CELL
  mstr_discrete res *
  page253_i12
#CELL
  mstr_discrete res *
  page253_i13
#CELL
  mstr_discrete res *
  page253_i14
#CELL
  mstr_discrete res *
  page253_i15
#CELL
  mstr_discrete choke_4pin *
  page253_i16
#CELL
  dev_discrete cap_a *
  page253_i19
#CELL
  dev_discrete cap_a *
  page253_i20
#ISCELL
  mstr_standard offpage *
  page253_i22
#ISCELL
  mstr_standard offpage *
  page253_i23
#ISCELL
  mstr_standard offpage *
  page253_i24
#ISCELL
  mstr_standard offpage *
  page253_i25
#CELL
  w_hdl skt-usb32-8-gp *
  page253_i26
#ISCELL
  mstr_symbols gnd *
  page253_i27
#ISCELL
  mstr_symbols p5v_stby *
  page253_i29
#CELL
  w_hdl sc22u16v5mx-4-gp *
  page253_i35
#CELL
  w_hdl sc22u16v5mx-4-gp *
  page253_i36
#CELL
  w_hdl sc22u16v5mx-4-gp *
  page253_i37
#CELL
  w_hdl sc22u16v5mx-4-gp *
  page253_i38
#CELL
  w_hdl sc22u16v5mx-4-gp *
  page253_i40
#CELL
  w_hdl sc22u16v5mx-4-gp *
  page253_i41
#CELL
  w_hdl sc22u16v5mx-4-gp *
  page253_i42
#ISCELL
  mstr_symbols gnd *
  page253_i43
#CELL
  w_hdl polysw-1d1a6v-2-gp-u *
  page253_i44
#CELL
  mstr_discrete diodeac_dual_array *
  page253_i5
#ISCELL
  mstr_symbols gnd *
  page253_i9
#ISCELL
  mstr_symbols cad_note *
  *
#ISCELL
  mstr_symbols intel_corp_bpage *
  *
#CELL
  mstr_discrete res *
  page269_i10
#CELL
  mstr_discrete res *
  page269_i11
#CELL
  mstr_discrete res *
  page269_i12
#CELL
  mstr_discrete res *
  page269_i13
#ISCELL
  mstr_symbols gnd *
  page269_i14
#ISCELL
  mstr_symbols p3v3_stby *
  page269_i15
#ISCELL
  mstr_standard offpage *
  page269_i16
#ISCELL
  mstr_standard offpage *
  page269_i17
#CELL
  mstr_discrete res *
  page269_i18
#CELL
  mstr_discrete res *
  page269_i19
#CELL
  mstr_discrete res *
  page269_i20
#CELL
  mstr_discrete res *
  page269_i21
#CELL
  mstr_discrete res *
  page269_i22
#ISCELL
  mstr_symbols gnd *
  page269_i23
#CELL
  mstr_discrete res *
  page269_i24
#ISCELL
  mstr_symbols p3v3_stby *
  page269_i25
#CELL
  dev_discrete cap_a *
  page269_i26
#ISCELL
  mstr_symbols gnd *
  page269_i27
#ISCELL
  mstr_symbols p1v05_pch_stby *
  page269_i28
#ISCELL
  mstr_symbols gnd *
  page269_i29
#ISCELL
  mstr_symbols gnd *
  page269_i31
#CELL
  mstr_discrete cap *
  page269_i32
#CELL
  mstr_ttl ttl3126 *
  page269_i33
#ISCELL
  mstr_standard offpage *
  page269_i39
#CELL
  mstr_discrete res *
  page269_i4
#ISCELL
  mstr_standard offpage *
  page269_i40
#ISCELL
  mstr_standard offpage *
  page269_i41
#ISCELL
  mstr_standard offpage *
  page269_i45
#ISCELL
  mstr_standard offpage *
  page269_i46
#ISCELL
  mstr_standard offpage *
  page269_i47
#ISCELL
  mstr_standard offpage *
  page269_i48
#CELL
  mstr_digital gtl2014 *
  page269_i49
#ISCELL
  mstr_standard offpage *
  page269_i50
#ISCELL
  mstr_standard offpage *
  page269_i51
#ISCELL
  mstr_standard offpage *
  page269_i52
#CELL
  w_hdl max4564eka-gp *
  page269_i53
#ISCELL
  mstr_symbols gnd *
  page269_i54
#CELL
  dev_discrete cap_a *
  page269_i56
#ISCELL
  mstr_symbols gnd *
  page269_i57
#ISCELL
  mstr_symbols p3v3_stby *
  page269_i58
#ISCELL
  mstr_standard offpage *
  page269_i59
#ISCELL
  mstr_symbols p3v3_stby *
  page269_i60
#CELL
  mstr_ttl ttl1g08 *
  page269_i61
#CELL
  dev_discrete cap_a *
  page269_i62
#ISCELL
  mstr_symbols gnd *
  page269_i63
#ISCELL
  mstr_symbols p3v3_stby *
  page269_i64
#ISCELL
  mstr_standard offpage *
  page269_i65
#ISCELL
  mstr_standard offpage *
  page269_i66
#ISCELL
  mstr_standard offpage *
  page269_i67
#ISCELL
  mstr_symbols gnd *
  page269_i68
#ISCELL
  mstr_standard offpage *
  page269_i69
#ISCELL
  mstr_standard offpage *
  page269_i70
#CELL
  w_hdl blm15ag121sn-1gp *
  page269_i71
#CELL
  w_hdl blm15ag121sn-1gp *
  page269_i72
#CELL
  w_hdl blm15ag121sn-1gp *
  page269_i73
#CELL
  w_hdl blm15ag121sn-1gp *
  page269_i74
#CELL
  w_hdl blm15ag121sn-1gp *
  page269_i75
#CELL
  mstr_ttl ttl1g126_a *
  page269_i76
#ISCELL
  mstr_standard offpage *
  page269_i77
#ISCELL
  mstr_symbols gnd *
  page269_i78
#CELL
  dev_discrete cap_a *
  page269_i79
#ISCELL
  mstr_symbols p3v3_stby *
  page269_i80
#ISCELL
  mstr_standard offpage *
  page269_i81
#ISCELL
  mstr_symbols cad_note *
  *
#ISCELL
  mstr_symbols intel_corp_bpage *
  *
#ISCELL
  mstr_standard offpage *
  page268_i1
#ISCELL
  mstr_symbols gnd *
  page268_i10
#ISCELL
  mstr_symbols p3v3_stby *
  page268_i11
#CELL
  mstr_ttl ttl1g07_a *
  page268_i12
#CELL
  mstr_ttl ttl1g07_a *
  page268_i13
#CELL
  mstr_discrete res *
  page268_i14
#ISCELL
  mstr_symbols gnd *
  page268_i15
#ISCELL
  mstr_symbols gnd *
  page268_i16
#CELL
  mstr_discrete res *
  page268_i17
#ISCELL
  mstr_standard offpage *
  page268_i18
#ISCELL
  mstr_standard offpage *
  page268_i19
#CELL
  mstr_discrete res *
  page268_i2
#ISCELL
  mstr_symbols gnd *
  page268_i20
#ISCELL
  mstr_symbols gnd *
  page268_i21
#ISCELL
  mstr_symbols p3v3_stby *
  page268_i22
#CELL
  mstr_discrete cap *
  page268_i23
#ISCELL
  mstr_symbols gnd *
  page268_i25
#CELL
  mstr_discrete res *
  page268_i26
#CELL
  dev_discrete cap_a *
  page268_i27
#CELL
  mstr_discrete res *
  page268_i28
#CELL
  mstr_discrete res *
  page268_i29
#ISCELL
  mstr_symbols p3v3_stby *
  page268_i3
#ISCELL
  mstr_symbols p1v05_pch_stby *
  page268_i30
#ISCELL
  mstr_standard offpage *
  page268_i31
#ISCELL
  mstr_symbols gnd *
  page268_i32
#CELL
  mstr_digital gtl2014 *
  page268_i33
#ISCELL
  mstr_standard offpage *
  page268_i34
#ISCELL
  mstr_standard offpage *
  page268_i35
#CELL
  w_hdl 374r2f-1-gp *
  page268_i36
#ISCELL
  mstr_symbols p3v3_stby *
  page268_i37
#CELL
  mstr_ttl ttl3126 *
  page268_i38
#ISCELL
  mstr_symbols p3v3_stby *
  page268_i39
#CELL
  dev_discrete cap_a *
  page268_i4
#CELL
  mstr_discrete cap *
  page268_i40
#ISCELL
  mstr_symbols gnd *
  page268_i41
#ISCELL
  mstr_standard offpage *
  page268_i42
#ISCELL
  mstr_standard offpage *
  page268_i44
#ISCELL
  mstr_standard offpage *
  page268_i45
#ISCELL
  mstr_standard offpage *
  page268_i46
#ISCELL
  mstr_standard offpage *
  page268_i47
#ISCELL
  mstr_standard offpage *
  page268_i48
#ISCELL
  mstr_standard offpage *
  page268_i49
#ISCELL
  mstr_symbols gnd *
  page268_i5
#ISCELL
  mstr_standard offpage *
  page268_i50
#CELL
  mstr_discrete fet_n *
  page268_i51
#ISCELL
  mstr_symbols gnd *
  page268_i52
#ISCELL
  mstr_standard offpage *
  page268_i53
#CELL
  mstr_discrete res *
  page268_i54
#ISCELL
  mstr_symbols p3v3_stby *
  page268_i55
#CELL
  mstr_ttl ttl1g08 *
  page268_i57
#ISCELL
  mstr_symbols p3v3_stby *
  page268_i58
#ISCELL
  mstr_symbols gnd *
  page268_i59
#ISCELL
  mstr_symbols p3v3_stby *
  page268_i6
#CELL
  dev_discrete cap_a *
  page268_i60
#ISCELL
  mstr_standard offpage *
  page268_i61
#ISCELL
  mstr_standard offpage *
  page268_i62
#CELL
  w_hdl sw-slide75-gp *
  page268_i63
#ISCELL
  mstr_symbols gnd *
  page268_i64
#ISCELL
  mstr_symbols gnd *
  page268_i65
#CELL
  mstr_discrete res *
  page268_i66
#ISCELL
  mstr_standard offpage *
  page268_i67
#CELL
  mstr_discrete res *
  page268_i7
#ISCELL
  mstr_symbols p3v3_stby *
  page268_i8
#CELL
  dev_discrete cap_a *
  page268_i9
#ISCELL
  mstr_symbols intel_corp_bpage *
  *
#ISCELL
  mstr_symbols gnd *
  page271_i10
#CELL
  w_hdl tpad-diff-4p-gp *
  page271_i11
#ISCELL
  mstr_symbols gnd *
  page271_i12
#CELL
  w_hdl tpad-diff-4p-gp *
  page271_i13
#ISCELL
  mstr_symbols gnd *
  page271_i14
#CELL
  w_hdl tpad-diff-4p-gp *
  page271_i15
#CELL
  w_hdl tpad-diff-4p-gp *
  page271_i16
#CELL
  w_hdl tpad-diff-4p-gp *
  page271_i17
#ISCELL
  mstr_symbols gnd *
  page271_i18
#CELL
  w_hdl tpad-diff-4p-gp *
  page271_i19
#ISCELL
  mstr_symbols gnd *
  page271_i20
#ISCELL
  mstr_symbols gnd *
  page271_i21
#ISCELL
  mstr_symbols gnd *
  page271_i22
#CELL
  w_hdl tpad-diff-4p-gp *
  page271_i23
#CELL
  w_hdl tpad-diff-4p-gp *
  page271_i24
#ISCELL
  mstr_symbols gnd *
  page271_i25
#ISCELL
  mstr_symbols gnd *
  page271_i26
#CELL
  w_hdl tpad-diff-4p-gp *
  page271_i3
#CELL
  w_hdl tpad-diff-4p-gp *
  page271_i30
#ISCELL
  mstr_symbols gnd *
  page271_i32
#CELL
  w_hdl tpad-diff-4p-gp *
  page271_i36
#ISCELL
  mstr_symbols gnd *
  page271_i37
#CELL
  w_hdl tpad-diff-4p-gp *
  page271_i38
#CELL
  w_hdl tpad-diff-4p-gp *
  page271_i39
#ISCELL
  mstr_symbols gnd *
  page271_i4
#ISCELL
  mstr_symbols gnd *
  page271_i40
#CELL
  w_hdl tpad-diff-4p-gp *
  page271_i45
#ISCELL
  mstr_symbols gnd *
  page271_i46
#CELL
  w_hdl tpad-diff-4p-gp *
  page271_i47
#ISCELL
  mstr_symbols gnd *
  page271_i48
#ISCELL
  mstr_symbols gnd *
  page271_i49
#CELL
  w_hdl tpad-diff-4p-gp *
  page271_i5
#CELL
  w_hdl tpad-se-2p-gp *
  page271_i50
#ISCELL
  mstr_symbols gnd *
  page271_i51
#CELL
  w_hdl tpad-se-2p-gp *
  page271_i52
#ISCELL
  mstr_symbols gnd *
  page271_i53
#CELL
  w_hdl tpad-se-2p-gp *
  page271_i54
#ISCELL
  mstr_symbols gnd *
  page271_i55
#CELL
  w_hdl tpad-se-2p-gp *
  page271_i56
#ISCELL
  mstr_symbols gnd *
  page271_i57
#ISCELL
  mstr_symbols gnd *
  page271_i58
#ISCELL
  mstr_symbols gnd *
  page271_i59
#ISCELL
  mstr_symbols gnd *
  page271_i6
#CELL
  w_hdl tpad-se-2p-gp *
  page271_i60
#CELL
  w_hdl tpad-se-2p-gp *
  page271_i61
#CELL
  w_hdl tpad-se-2p-gp *
  page271_i62
#CELL
  w_hdl tpad-se-2p-gp *
  page271_i63
#ISCELL
  mstr_symbols gnd *
  page271_i64
#ISCELL
  mstr_symbols gnd *
  page271_i65
#ISCELL
  mstr_symbols gnd *
  page271_i66
#CELL
  w_hdl tpad-se-2p-gp *
  page271_i67
#ISCELL
  mstr_symbols gnd *
  page271_i68
#ISCELL
  mstr_symbols gnd *
  page271_i69
#CELL
  w_hdl tpad-diff-4p-gp *
  page271_i7
#ISCELL
  mstr_symbols gnd *
  page271_i70
#CELL
  w_hdl tpad-se-2p-gp *
  page271_i71
#CELL
  w_hdl tpad-se-2p-gp *
  page271_i72
#CELL
  w_hdl tpad-se-2p-gp *
  page271_i73
#CELL
  w_hdl tpad-diff-4p-gp *
  page271_i8
#ISCELL
  mstr_symbols gnd *
  page271_i9
#ISCELL
  mstr_symbols intel_corp_bpage *
  *
#CELL
  w_hdl test-pad-12p-1-gp-u *
  page270_i1
#ISCELL
  mstr_symbols gnd *
  page270_i10
#ISCELL
  mstr_symbols gnd *
  page270_i11
#CELL
  w_hdl test-pad-12p-1-gp-u *
  page270_i12
#CELL
  w_hdl test-pad-12p-1-gp-u *
  page270_i13
#ISCELL
  mstr_symbols gnd *
  page270_i14
#ISCELL
  mstr_symbols gnd *
  page270_i15
#CELL
  w_hdl test-pad-12p-1-gp-u *
  page270_i16
#CELL
  w_hdl test-pad-12p-1-gp-u *
  page270_i17
#CELL
  w_hdl test-pad-12p-1-gp-u *
  page270_i18
#ISCELL
  mstr_symbols gnd *
  page270_i19
#ISCELL
  mstr_symbols gnd *
  page270_i2
#ISCELL
  mstr_symbols gnd *
  page270_i20
#CELL
  w_hdl test-pad-12p-1-gp-u *
  page270_i21
#ISCELL
  mstr_symbols gnd *
  page270_i22
#ISCELL
  mstr_symbols gnd *
  page270_i23
#CELL
  w_hdl test-pad-12p-1-gp-u *
  page270_i24
#CELL
  w_hdl test-pad-12p-1-gp-u *
  page270_i3
#ISCELL
  mstr_symbols gnd *
  page270_i4
#CELL
  w_hdl test-pad-12p-1-gp-u *
  page270_i5
#CELL
  w_hdl test-pad-12p-1-gp-u *
  page270_i6
#ISCELL
  mstr_symbols gnd *
  page270_i7
#ISCELL
  mstr_symbols gnd *
  page270_i8
#CELL
  w_hdl test-pad-12p-1-gp-u *
  page270_i9
#ISCELL
  mstr_symbols intel_corp_bpage *
  *
#CELL
  w_hdl test-pad-12p-1-gp-u *
  page272_i1
#ISCELL
  mstr_symbols gnd *
  page272_i10
#ISCELL
  mstr_symbols gnd *
  page272_i11
#CELL
  w_hdl test-pad-12p-1-gp-u *
  page272_i12
#ISCELL
  mstr_symbols gnd *
  page272_i13
#CELL
  w_hdl test-pad-12p-1-gp-u *
  page272_i14
#ISCELL
  mstr_symbols gnd *
  page272_i15
#CELL
  w_hdl test-pad-12p-1-gp-u *
  page272_i16
#ISCELL
  mstr_symbols gnd *
  page272_i17
#ISCELL
  mstr_symbols gnd *
  page272_i18
#ISCELL
  mstr_symbols gnd *
  page272_i19
#ISCELL
  mstr_symbols gnd *
  page272_i2
#ISCELL
  mstr_symbols gnd *
  page272_i20
#CELL
  w_hdl test-pad-12p-1-gp-u *
  page272_i21
#CELL
  w_hdl test-pad-12p-1-gp-u *
  page272_i22
#CELL
  w_hdl test-pad-12p-1-gp-u *
  page272_i23
#CELL
  w_hdl test-pad-12p-1-gp-u *
  page272_i24
#CELL
  w_hdl test-pad-12p-1-gp-u *
  page272_i3
#ISCELL
  mstr_symbols gnd *
  page272_i4
#CELL
  w_hdl test-pad-12p-1-gp-u *
  page272_i5
#ISCELL
  mstr_symbols gnd *
  page272_i6
#ISCELL
  mstr_symbols gnd *
  page272_i7
#CELL
  w_hdl test-pad-12p-1-gp-u *
  page272_i8
#CELL
  w_hdl test-pad-12p-1-gp-u *
  page272_i9
#ISCELL
  mstr_symbols intel_corp_bpage *
  *
#ISCELL
  mstr_symbols intel_corp_bpage *
  *
#ISCELL
  mstr_symbols intel_corp_bpage *
  *
#ISCELL
  mstr_symbols intel_corp_bpage *
  *
#ISCELL
  mstr_symbols intel_corp_bpage *
  *
#ISCELL
  mstr_symbols intel_corp_bpage *
  *
#ISCELL
  mstr_symbols intel_corp_bpage *
  *
#ISCELL
  mstr_symbols intel_corp_bpage *
  *
#ISCELL
  mstr_symbols intel_corp_bpage *
  *
#ISCELL
  mstr_symbols intel_corp_bpage *
  *
#ISCELL
  mstr_symbols intel_corp_bpage *
  *
#ISCELL
  mstr_symbols intel_corp_bpage *
  *
